G04 ================== begin FILE IDENTIFICATION RECORD ==================*
G04 Layout Name:  D:/<user>/Wistron_project/16369-sd/gbr/16369-sd.brd*
G04 Film Name:    NOTICE*
G04 File Format:  Gerber RS274X*
G04 File Origin:  Cadence Allegro 16.5-S056*
G04 Origin Date:  Wed Mar 29 13:12:51 2017*
G04 *
G04 Layer:  MANUFACTURING/THERMAL*
G04 *
G04 Offset:    (0.00 0.00)*
G04 Mirror:    No*
G04 Mode:      Positive*
G04 Rotation:  0*
G04 FullContactRelief:  No*
G04 UndefLineWidth:     6.00*
G04 ================== end FILE IDENTIFICATION RECORD ====================*
%FSLAX35Y35*MOIN*%
%IR0*IPPOS*OFA0.00000B0.00000*MIA0B0*SFA1.00000B1.00000*%
%ADD10C,.004*%
%ADD11C,.006*%
%ADD12C,.0033*%
%ADD13C,.008*%
%ADD14C,.0055*%
G75*
%LPD*%
G75*
G36*
G01X-203441Y-34903D02*
G02X-152741Y-34643I25558J-40503D01*
G01X-163891Y-55973D01*
X-192391D01*
X-203441Y-34903D01*
G37*
G36*
G01X-206621Y26187D02*
X-197941D01*
G03X-163831Y26177I17058J11442D01*
G01X-156281D01*
X-167151Y5177D01*
X-195651D01*
X-206621Y26187D01*
G37*
G54D10*
G01X291353Y-94925D02*
X315353D01*
G01X314768Y-80904D02*
X264768D01*
G01D02*
Y-70904D01*
G01X284768Y-30904D02*
Y-904D01*
G01Y-70904D02*
Y-40904D01*
G01X264768Y-30904D02*
X284768D01*
G01X264768Y-40904D02*
Y-30904D01*
G01X284768Y-40904D02*
X264768D01*
G01Y-70904D02*
X284768D01*
G01Y9096D02*
Y39096D01*
G01X264768Y49096D02*
X304768D01*
G01X264768Y39096D02*
Y49096D01*
G01X284768Y39096D02*
X264768D01*
G01Y9096D02*
X284768D01*
G01X264768Y-904D02*
Y9096D01*
G01X284768Y-904D02*
X264768D01*
G01X347353Y-96925D02*
Y-92925D01*
G01X334768Y-80904D02*
X384768D01*
G01X334768Y-23544D02*
Y-80904D01*
G01X354213Y-94925D02*
X335353D01*
G01X347353Y-92925D02*
X335353Y-94925D01*
G01Y-106925D02*
Y-86925D01*
G01Y-94925D02*
X347353Y-96925D01*
G01X315353Y-94925D02*
X303353Y-92925D01*
G01X314768Y-24053D02*
Y-80904D01*
G01X315353Y-86925D02*
Y-106925D01*
G01X303353Y-92925D02*
Y-96925D01*
G01D02*
X315353Y-94925D01*
G01X339768Y-23544D02*
X455759D01*
G01X364768Y-30904D02*
Y-904D01*
G01X384768Y-30904D02*
X364768D01*
G01Y-40904D02*
X384768D01*
G01X364768Y-70904D02*
Y-40904D01*
G01X384768Y-70904D02*
X364768D01*
G01X344768Y49096D02*
Y-13544D01*
G01D02*
X334768Y-23544D01*
G01X304764Y-14049D02*
X304768Y-14053D01*
G01Y49096D02*
Y-14053D01*
G01D02*
X314768Y-24053D01*
G01X364768Y39096D02*
X384768D01*
G01X364768Y9096D02*
Y39096D01*
G01X384768Y9096D02*
X364768D01*
G01Y-904D02*
X384768D01*
G01X345273Y70755D02*
Y50755D01*
G01Y58755D02*
X354133D01*
G01X333273Y60755D02*
Y56755D01*
G01X345273Y58755D02*
X333273Y60755D01*
G01Y56755D02*
X345273Y58755D01*
G01X384768Y49096D02*
X344768D01*
G01X305273Y70755D02*
Y50755D01*
G01X317273Y56755D02*
Y60755D01*
G01X305273Y58755D02*
X317273Y56755D01*
G01Y60755D02*
X305273Y58755D01*
G01D02*
X345273D01*
G01X384768Y-80904D02*
Y-70904D01*
G01X448759Y-11544D02*
X450759Y-23544D01*
X452759Y-11544D01*
X448759D01*
G01X452759Y-42904D02*
X450759Y-30904D01*
X448759Y-42904D01*
X452759D01*
G01X389768Y-30904D02*
X455759D01*
G01X384768Y-40904D02*
X384759Y-30993D01*
G01X384768Y39096D02*
Y49096D01*
G01Y-904D02*
Y9096D01*
G01X450759Y456D02*
Y-23544D01*
G01Y-54904D02*
Y-30904D01*
G01X596413Y595D02*
Y-29405D01*
G01Y-39405D02*
Y-69405D01*
G01X576413Y-39405D02*
X596413D01*
G01X576413Y-29405D02*
Y-39405D01*
G01X596413Y-29405D02*
X576413D01*
G01X596413Y-69405D02*
X576413D01*
G01Y-79405D02*
X616413D01*
G01X576413Y-69405D02*
Y-79405D01*
G01X596413Y40595D02*
Y10595D01*
G01X626413Y50595D02*
X576413D01*
G01Y40595D02*
X596413D01*
G01X576413Y50595D02*
Y40595D01*
G01Y595D02*
X596413D01*
G01X576413Y10595D02*
Y595D01*
G01X596413Y10595D02*
X576413D01*
G01X644413Y-95405D02*
Y-99405D01*
G01X656413Y-97405D02*
X644413Y-95405D01*
G01Y-99405D02*
X656413Y-97405D01*
G01D02*
X665273D01*
G01X656413Y-85405D02*
Y-105405D01*
G01X628413Y-99405D02*
Y-95405D01*
G01X616413Y-97405D02*
X628413Y-99405D01*
G01Y-95405D02*
X616413Y-97405D01*
G01D02*
X656413D01*
G01X616413Y-85405D02*
Y-105405D01*
G01X696413Y-39405D02*
X676413D01*
G01Y-29405D02*
X696413D01*
G01X676413Y595D02*
Y-29405D01*
G01Y-69405D02*
X696413D01*
G01X676413Y-39405D02*
Y-69405D01*
G01X656417Y-16260D02*
X656413Y-16256D01*
G01X646413Y-6256D02*
Y50595D01*
G01X656413Y-16256D02*
X646413Y-6256D01*
G01X656413Y-79405D02*
Y-16256D01*
G01X696413Y-79405D02*
X656413D01*
G01X626413Y-6765D02*
Y50595D01*
G01X616413Y-16765D02*
X626413Y-6765D01*
G01X616413Y-79405D02*
Y-16765D01*
G01X658413Y68595D02*
Y72595D01*
G01X696413Y40595D02*
X676413D01*
G01X696413Y595D02*
X676413D01*
G01Y10595D02*
X696413D01*
G01X676413Y40595D02*
Y10595D01*
G01X665273Y70595D02*
X646413D01*
G01D02*
X658413Y68595D01*
G01Y72595D02*
X646413Y70595D01*
G01Y58595D02*
Y78595D01*
G01Y50595D02*
X696413D01*
G01X614413Y72595D02*
Y68595D01*
G01X626413Y70595D02*
X614413Y72595D01*
G01Y68595D02*
X626413Y70595D01*
G01Y78595D02*
Y58595D01*
G01X602413Y70595D02*
X626413D01*
G01X696413Y-29405D02*
Y-39405D01*
G01Y-69405D02*
Y-79405D01*
G01Y50595D02*
Y40595D01*
G01Y10595D02*
Y595D01*
G54D11*
G01X-500941Y275907D02*
X-500991D01*
G01X-450941Y521907D02*
X-450991D01*
G01X-172871Y-27483D02*
X-117101D01*
G01X-220151Y21177D02*
X-225151D01*
Y-4823D01*
X-220151D01*
G01Y177D02*
Y-4823D01*
X-142651D01*
Y177D01*
G01X-216891Y-39973D02*
X-221891D01*
Y-65973D01*
X-216891D01*
G01Y-60973D02*
X-197391D01*
X-208391Y-39973D01*
X-216891D01*
Y-34973D01*
X-203391D01*
X-192391Y-55973D01*
X-163891D01*
X-152891Y-34973D01*
X-139391D01*
Y-39973D01*
X-147891D01*
X-158891Y-60973D01*
X-139391D01*
G01X-216891D02*
Y-65973D01*
X-139391D01*
Y-60973D01*
G01X-175951Y17207D02*
X-117251D01*
G01X-159031Y26217D02*
X-117251D01*
G01X-175651Y58037D02*
X-163651Y60037D01*
X-175651Y62037D01*
Y58037D01*
G01X-165351Y60037D02*
X-163651D01*
G01X-190151Y62037D02*
X-202151Y60037D01*
X-190151Y58037D01*
Y62037D01*
G01X-198951Y60037D02*
X-202151D01*
G01X-220151Y177D02*
X-200651D01*
X-211651Y21177D01*
X-220151D01*
Y26177D01*
X-206651D01*
X-195651Y5177D01*
X-167151D01*
X-156151Y26177D01*
X-142651D01*
Y21177D01*
X-151151D01*
X-162151Y177D01*
X-142651D01*
G01X-165651Y60037D02*
X-201151D01*
G01X-221651Y92037D02*
X-226651D01*
Y66037D01*
X-221651D01*
G01Y71037D02*
Y66037D01*
X-144151D01*
Y71037D01*
G01X-221651D02*
X-202151D01*
X-213151Y92037D01*
X-221651D01*
Y97037D01*
X-208151D01*
X-197151Y76037D01*
X-168651D01*
X-157651Y97037D01*
X-144151D01*
Y92037D01*
X-152651D01*
X-163651Y71037D01*
X-144151D01*
G01X-164651Y102037D02*
X-152651Y104037D01*
X-164651Y106037D01*
Y102037D01*
G01X-170351Y104037D02*
X-152651D01*
G01X-201151Y106037D02*
X-213151Y104037D01*
X-201151Y102037D01*
Y106037D01*
G01X-193951Y104037D02*
X-213151D01*
G01X-120101Y-15483D02*
X-122101Y-27483D01*
X-124101Y-15483D01*
X-120101D01*
G01X-122101Y-10943D02*
Y-27483D01*
G01X-120101Y-46663D02*
X-122101Y-34663D01*
X-124101Y-46663D01*
X-120101D01*
G01X-122101Y-51543D02*
Y-34663D01*
G01X-147871D02*
X-117101D01*
G01X-142651Y21177D02*
X-137651D01*
Y-4823D01*
X-142651D01*
G01X-139391Y-39973D02*
X-134391D01*
Y-65973D01*
X-139391D01*
G01X-120251Y38217D02*
X-122251Y26217D01*
X-124251Y38217D01*
X-120251D01*
G01X-122251Y26217D02*
Y41357D01*
G01X-120251Y5207D02*
X-122251Y17207D01*
X-124251Y5207D01*
X-120251D01*
G01X-122251Y1707D02*
Y17207D01*
G01X-144151Y92037D02*
X-139151D01*
Y66037D01*
X-144151D01*
G01X344259Y-261293D02*
Y-189293D01*
X388259D01*
Y-261293D01*
X344259D01*
G01Y-261244D02*
X315759Y-261293D01*
G01X332262Y-263265D02*
X344259Y-261244D01*
X332256Y-259265D01*
X332262Y-263265D01*
G01X373259Y-181793D02*
X388259Y-179293D01*
X373259Y-176793D01*
Y-181793D01*
G01X359259Y-176793D02*
X344259Y-179293D01*
X359259Y-181793D01*
Y-176793D01*
G01X388259Y-179293D02*
X344259D01*
G01Y-184293D02*
Y-169293D01*
G01X324759Y444332D02*
Y477036D01*
G01X322259Y390836D02*
X324759Y375836D01*
X327259Y390836D01*
X322259D01*
G01X324759Y413082D02*
Y375836D01*
G01X426099D02*
X314759D01*
G01X327259Y462036D02*
X324759Y477036D01*
X322259Y462036D01*
X327259D01*
G01X341099Y477036D02*
X314759D01*
G01X426759Y-246293D02*
X429259Y-261293D01*
X431759Y-246293D01*
X426759D01*
G01X429259Y-236918D02*
Y-261293D01*
G01X398259D02*
X439259D01*
G01X431759Y-204293D02*
X429259Y-189293D01*
X426759Y-204293D01*
X431759D01*
G01X429259Y-205668D02*
Y-189293D01*
G01X398259D02*
X439259D01*
G01X396234Y-179293D02*
X388259D01*
G01Y-184293D02*
Y-169293D01*
G01X651413Y-6256D02*
X769259D01*
G01X609712Y379686D02*
X626259Y368207D01*
X627259D01*
G01X614675Y378068D02*
X609712Y379686D01*
X612965Y375604D01*
X614675Y378068D01*
G01X701413Y595D02*
X769259D01*
G01X766259Y-18256D02*
X764259Y-6256D01*
X762259Y-18256D01*
X766259D01*
G01X764259Y-30256D02*
Y-6256D01*
G01X762259Y12595D02*
X764259Y595D01*
X766259Y12595D01*
X762259D01*
G01X764259Y28407D02*
Y595D01*
G01X-505241Y467207D02*
Y-318293D01*
G01D02*
X189259D01*
G01X-493491Y-297626D02*
X-492824Y-298043D01*
X-492074Y-298293D01*
X-491408D01*
X-490741Y-298043D01*
X-490241Y-297626D01*
X-489991Y-297043D01*
X-490158Y-296460D01*
X-490574Y-295960D01*
X-491324Y-295626D01*
X-492324Y-295460D01*
X-492908Y-295126D01*
X-493158Y-294543D01*
X-492991Y-293960D01*
X-492574Y-293543D01*
X-491991Y-293293D01*
X-491408D01*
X-490824Y-293460D01*
X-490324Y-293876D01*
G01X-486141Y-294960D02*
Y-298293D01*
G01Y-293626D02*
X-486308Y-293543D01*
Y-293376D01*
X-486141Y-293293D01*
X-485974Y-293376D01*
Y-293543D01*
X-486141Y-293626D01*
G01X-480541Y-298293D02*
Y-293293D01*
G01X-476358Y-298293D02*
Y-293293D01*
G01X-473691Y-294960D02*
X-476358Y-296876D01*
G01X-475274Y-296126D02*
X-473524Y-298293D01*
G01X-470591Y-297710D02*
X-470174Y-298043D01*
X-469591Y-298293D01*
X-469091D01*
X-468591Y-298126D01*
X-468258Y-297876D01*
X-468091Y-297543D01*
X-468174Y-297043D01*
X-468508Y-296793D01*
X-470008Y-296293D01*
X-470341Y-295710D01*
X-470174Y-295293D01*
X-469841Y-295043D01*
X-469341Y-294960D01*
X-468841Y-295043D01*
X-468341Y-295293D01*
G01X-462408Y-295376D02*
X-462991Y-295043D01*
X-463491Y-294960D01*
X-464158Y-295126D01*
X-464658Y-295460D01*
X-464991Y-296043D01*
X-465074Y-296626D01*
X-464991Y-297210D01*
X-464658Y-297710D01*
X-464158Y-298126D01*
X-463491Y-298293D01*
X-462908Y-298126D01*
X-462408Y-297793D01*
G01X-459308Y-298293D02*
Y-294960D01*
G01Y-295626D02*
X-458891Y-295293D01*
X-458474Y-295043D01*
X-457891Y-294960D01*
X-457474Y-295043D01*
X-456974Y-295293D01*
G01X-453791Y-296043D02*
X-451124D01*
X-451374Y-295460D01*
X-451791Y-295126D01*
X-452374Y-294960D01*
X-452958Y-295043D01*
X-453458Y-295293D01*
X-453791Y-295876D01*
X-453958Y-296376D01*
Y-296876D01*
X-453791Y-297376D01*
X-453374Y-297876D01*
X-452874Y-298210D01*
X-452291Y-298293D01*
X-451708Y-298126D01*
X-451124Y-297626D01*
G01X-448191Y-296043D02*
X-445524D01*
X-445774Y-295460D01*
X-446191Y-295126D01*
X-446774Y-294960D01*
X-447358Y-295043D01*
X-447858Y-295293D01*
X-448191Y-295876D01*
X-448358Y-296376D01*
Y-296876D01*
X-448191Y-297376D01*
X-447774Y-297876D01*
X-447274Y-298210D01*
X-446691Y-298293D01*
X-446108Y-298126D01*
X-445524Y-297626D01*
G01X-442758Y-298293D02*
Y-294960D01*
G01Y-295793D02*
X-442424Y-295376D01*
X-441924Y-295043D01*
X-441258Y-294960D01*
X-440674Y-295043D01*
X-440174Y-295376D01*
X-439924Y-295960D01*
Y-298293D01*
G01X-493491Y-252626D02*
X-492824Y-253043D01*
X-492074Y-253293D01*
X-491408D01*
X-490741Y-253043D01*
X-490241Y-252626D01*
X-489991Y-252043D01*
X-490158Y-251460D01*
X-490574Y-250960D01*
X-491324Y-250626D01*
X-492324Y-250460D01*
X-492908Y-250126D01*
X-493158Y-249543D01*
X-492991Y-248960D01*
X-492574Y-248543D01*
X-491991Y-248293D01*
X-491408D01*
X-490824Y-248460D01*
X-490324Y-248876D01*
G01X-486141Y-253293D02*
X-486641Y-253210D01*
X-487141Y-252876D01*
X-487474Y-252293D01*
X-487641Y-251626D01*
X-487474Y-250960D01*
X-487141Y-250376D01*
X-486641Y-250043D01*
X-486141Y-249960D01*
X-485641Y-250043D01*
X-485141Y-250376D01*
X-484808Y-250960D01*
X-484724Y-251626D01*
X-484808Y-252293D01*
X-485141Y-252876D01*
X-485641Y-253210D01*
X-486141Y-253293D01*
G01X-480541D02*
Y-248293D01*
G01X-473441D02*
Y-253293D01*
G01Y-252543D02*
X-473774Y-252960D01*
X-474274Y-253210D01*
X-474858Y-253293D01*
X-475524Y-253126D01*
X-476024Y-252710D01*
X-476358Y-252210D01*
X-476441Y-251626D01*
X-476358Y-251043D01*
X-476024Y-250543D01*
X-475524Y-250126D01*
X-474858Y-249960D01*
X-474274Y-250043D01*
X-473858Y-250210D01*
X-473441Y-250543D01*
G01X-470591Y-251043D02*
X-467924D01*
X-468174Y-250460D01*
X-468591Y-250126D01*
X-469174Y-249960D01*
X-469758Y-250043D01*
X-470258Y-250293D01*
X-470591Y-250876D01*
X-470758Y-251376D01*
Y-251876D01*
X-470591Y-252376D01*
X-470174Y-252876D01*
X-469674Y-253210D01*
X-469091Y-253293D01*
X-468508Y-253126D01*
X-467924Y-252626D01*
G01X-464908Y-253293D02*
Y-249960D01*
G01Y-250626D02*
X-464491Y-250293D01*
X-464074Y-250043D01*
X-463491Y-249960D01*
X-463074Y-250043D01*
X-462574Y-250293D01*
G01X-455041Y-253293D02*
Y-249960D01*
G01Y-250876D02*
X-454791Y-250460D01*
X-454374Y-250126D01*
X-453791Y-249960D01*
X-453208Y-250126D01*
X-452791Y-250460D01*
X-452541Y-250876D01*
Y-253293D01*
G01Y-250876D02*
X-452291Y-250460D01*
X-451874Y-250126D01*
X-451291Y-249960D01*
X-450708Y-250126D01*
X-450291Y-250460D01*
X-450041Y-250960D01*
Y-253293D01*
G01X-445441D02*
Y-249960D01*
G01Y-250543D02*
X-445774Y-250210D01*
X-446274Y-250043D01*
X-446858Y-249960D01*
X-447441Y-250126D01*
X-447941Y-250460D01*
X-448274Y-250960D01*
X-448441Y-251626D01*
X-448274Y-252293D01*
X-447941Y-252793D01*
X-447441Y-253126D01*
X-446858Y-253293D01*
X-446274Y-253210D01*
X-445774Y-252960D01*
X-445441Y-252626D01*
G01X-442591Y-252710D02*
X-442174Y-253043D01*
X-441591Y-253293D01*
X-441091D01*
X-440591Y-253126D01*
X-440258Y-252876D01*
X-440091Y-252543D01*
X-440174Y-252043D01*
X-440508Y-251793D01*
X-442008Y-251293D01*
X-442341Y-250710D01*
X-442174Y-250293D01*
X-441841Y-250043D01*
X-441341Y-249960D01*
X-440841Y-250043D01*
X-440341Y-250293D01*
G01X-437158Y-253293D02*
Y-248293D01*
G01X-434491Y-249960D02*
X-437158Y-251876D01*
G01X-436074Y-251126D02*
X-434324Y-253293D01*
G01X-505241Y-273293D02*
X189259D01*
G01X-490074Y-184793D02*
X-493408D01*
Y-179793D01*
X-490074D01*
G01X-491408Y-182210D02*
X-493408D01*
G01X-486141Y-179793D02*
Y-184793D01*
G01X-487308Y-181460D02*
X-484974D01*
G01X-479208Y-181876D02*
X-479791Y-181543D01*
X-480291Y-181460D01*
X-480958Y-181626D01*
X-481458Y-181960D01*
X-481791Y-182543D01*
X-481874Y-183126D01*
X-481791Y-183710D01*
X-481458Y-184210D01*
X-480958Y-184626D01*
X-480291Y-184793D01*
X-479708Y-184626D01*
X-479208Y-184293D01*
G01X-476358Y-184793D02*
Y-179793D01*
G01Y-182210D02*
X-475941Y-181793D01*
X-475524Y-181543D01*
X-474858Y-181460D01*
X-474358Y-181543D01*
X-473774Y-181876D01*
X-473524Y-182376D01*
Y-184793D01*
G01X-505241Y-229293D02*
X189259D01*
G01X-490074Y-137293D02*
X-493408D01*
Y-132293D01*
X-490074D01*
G01X-491408Y-134710D02*
X-493408D01*
G01X-487391Y-133960D02*
X-484891Y-137293D01*
G01Y-133960D02*
X-487391Y-137293D01*
G01X-480541Y-132293D02*
Y-137293D01*
G01X-481708Y-133960D02*
X-479374D01*
G01X-476191Y-135043D02*
X-473524D01*
X-473774Y-134460D01*
X-474191Y-134126D01*
X-474774Y-133960D01*
X-475358Y-134043D01*
X-475858Y-134293D01*
X-476191Y-134876D01*
X-476358Y-135376D01*
Y-135876D01*
X-476191Y-136376D01*
X-475774Y-136876D01*
X-475274Y-137210D01*
X-474691Y-137293D01*
X-474108Y-137126D01*
X-473524Y-136626D01*
G01X-470508Y-137293D02*
Y-133960D01*
G01Y-134626D02*
X-470091Y-134293D01*
X-469674Y-134043D01*
X-469091Y-133960D01*
X-468674Y-134043D01*
X-468174Y-134293D01*
G01X-465158Y-137293D02*
Y-133960D01*
G01Y-134793D02*
X-464824Y-134376D01*
X-464324Y-134043D01*
X-463658Y-133960D01*
X-463074Y-134043D01*
X-462574Y-134376D01*
X-462324Y-134960D01*
Y-137293D01*
G01X-456641D02*
Y-133960D01*
G01Y-134543D02*
X-456974Y-134210D01*
X-457474Y-134043D01*
X-458058Y-133960D01*
X-458641Y-134126D01*
X-459141Y-134460D01*
X-459474Y-134960D01*
X-459641Y-135626D01*
X-459474Y-136293D01*
X-459141Y-136793D01*
X-458641Y-137126D01*
X-458058Y-137293D01*
X-457474Y-137210D01*
X-456974Y-136960D01*
X-456641Y-136626D01*
G01X-452541Y-137293D02*
Y-132293D01*
G01X-441341Y-137293D02*
Y-132293D01*
G01X-434241Y-137293D02*
Y-133960D01*
G01Y-134543D02*
X-434574Y-134210D01*
X-435074Y-134043D01*
X-435658Y-133960D01*
X-436241Y-134126D01*
X-436741Y-134460D01*
X-437074Y-134960D01*
X-437241Y-135626D01*
X-437074Y-136293D01*
X-436741Y-136793D01*
X-436241Y-137126D01*
X-435658Y-137293D01*
X-435074Y-137210D01*
X-434574Y-136960D01*
X-434241Y-136626D01*
G01X-431891Y-138793D02*
X-431391Y-138960D01*
X-430724Y-138793D01*
X-430308Y-138460D01*
X-429974Y-138043D01*
X-429474Y-136710D01*
X-428391Y-133960D01*
G01X-431058D02*
X-429474Y-136710D01*
G01X-425791Y-135043D02*
X-423124D01*
X-423374Y-134460D01*
X-423791Y-134126D01*
X-424374Y-133960D01*
X-424958Y-134043D01*
X-425458Y-134293D01*
X-425791Y-134876D01*
X-425958Y-135376D01*
Y-135876D01*
X-425791Y-136376D01*
X-425374Y-136876D01*
X-424874Y-137210D01*
X-424291Y-137293D01*
X-423708Y-137126D01*
X-423124Y-136626D01*
G01X-420108Y-137293D02*
Y-133960D01*
G01Y-134626D02*
X-419691Y-134293D01*
X-419274Y-134043D01*
X-418691Y-133960D01*
X-418274Y-134043D01*
X-417774Y-134293D01*
G01X-489908Y-102710D02*
X-490408Y-102460D01*
X-490991Y-102293D01*
X-491658D01*
X-492408Y-102543D01*
X-492991Y-102960D01*
X-493408Y-103460D01*
X-493741Y-104293D01*
X-493824Y-105043D01*
X-493658Y-105793D01*
X-493408Y-106293D01*
X-492908Y-106793D01*
X-492324Y-107126D01*
X-491741Y-107293D01*
X-491158D01*
X-490574Y-107126D01*
X-490074Y-106876D01*
X-489658Y-106543D01*
G01X-486141Y-107293D02*
X-486641Y-107210D01*
X-487141Y-106876D01*
X-487474Y-106293D01*
X-487641Y-105626D01*
X-487474Y-104960D01*
X-487141Y-104376D01*
X-486641Y-104043D01*
X-486141Y-103960D01*
X-485641Y-104043D01*
X-485141Y-104376D01*
X-484808Y-104960D01*
X-484724Y-105626D01*
X-484808Y-106293D01*
X-485141Y-106876D01*
X-485641Y-107210D01*
X-486141Y-107293D01*
G01X-482041Y-108960D02*
Y-103960D01*
G01Y-104710D02*
X-481624Y-104293D01*
X-481208Y-104043D01*
X-480541Y-103960D01*
X-479958Y-104043D01*
X-479374Y-104460D01*
X-479124Y-105043D01*
X-479041Y-105626D01*
X-479124Y-106210D01*
X-479374Y-106793D01*
X-479874Y-107126D01*
X-480541Y-107293D01*
X-481124Y-107210D01*
X-481708Y-106960D01*
X-482041Y-106626D01*
G01X-476441Y-108960D02*
Y-103960D01*
G01Y-104710D02*
X-476024Y-104293D01*
X-475608Y-104043D01*
X-474941Y-103960D01*
X-474358Y-104043D01*
X-473774Y-104460D01*
X-473524Y-105043D01*
X-473441Y-105626D01*
X-473524Y-106210D01*
X-473774Y-106793D01*
X-474274Y-107126D01*
X-474941Y-107293D01*
X-475524Y-107210D01*
X-476108Y-106960D01*
X-476441Y-106626D01*
G01X-470591Y-105043D02*
X-467924D01*
X-468174Y-104460D01*
X-468591Y-104126D01*
X-469174Y-103960D01*
X-469758Y-104043D01*
X-470258Y-104293D01*
X-470591Y-104876D01*
X-470758Y-105376D01*
Y-105876D01*
X-470591Y-106376D01*
X-470174Y-106876D01*
X-469674Y-107210D01*
X-469091Y-107293D01*
X-468508Y-107126D01*
X-467924Y-106626D01*
G01X-464908Y-107293D02*
Y-103960D01*
G01Y-104626D02*
X-464491Y-104293D01*
X-464074Y-104043D01*
X-463491Y-103960D01*
X-463074Y-104043D01*
X-462574Y-104293D01*
G01X-454208Y-107293D02*
Y-102293D01*
X-452208D01*
X-451541Y-102543D01*
X-451041Y-103126D01*
X-450874Y-103793D01*
X-451041Y-104460D01*
X-451458Y-104960D01*
X-452208Y-105210D01*
X-454208D01*
G01X-446941Y-107293D02*
Y-102293D01*
G01X-439841Y-107293D02*
Y-103960D01*
G01Y-104543D02*
X-440174Y-104210D01*
X-440674Y-104043D01*
X-441258Y-103960D01*
X-441841Y-104126D01*
X-442341Y-104460D01*
X-442674Y-104960D01*
X-442841Y-105626D01*
X-442674Y-106293D01*
X-442341Y-106793D01*
X-441841Y-107126D01*
X-441258Y-107293D01*
X-440674Y-107210D01*
X-440174Y-106960D01*
X-439841Y-106626D01*
G01X-435741Y-102293D02*
Y-107293D01*
G01X-436908Y-103960D02*
X-434574D01*
G01X-430141D02*
Y-107293D01*
G01Y-102626D02*
X-430308Y-102543D01*
Y-102376D01*
X-430141Y-102293D01*
X-429974Y-102376D01*
Y-102543D01*
X-430141Y-102626D01*
G01X-425958Y-107293D02*
Y-103960D01*
G01Y-104793D02*
X-425624Y-104376D01*
X-425124Y-104043D01*
X-424458Y-103960D01*
X-423874Y-104043D01*
X-423374Y-104376D01*
X-423124Y-104960D01*
Y-107293D01*
G01X-420108Y-108543D02*
X-419524Y-108876D01*
X-418858Y-108960D01*
X-418274Y-108876D01*
X-417774Y-108460D01*
X-417441Y-107876D01*
Y-103960D01*
G01Y-104626D02*
X-417774Y-104293D01*
X-418274Y-104043D01*
X-418858Y-103960D01*
X-419524Y-104126D01*
X-419941Y-104460D01*
X-420274Y-105043D01*
X-420441Y-105626D01*
X-420358Y-106126D01*
X-420024Y-106710D01*
X-419524Y-107126D01*
X-418858Y-107293D01*
X-418358Y-107210D01*
X-417774Y-106876D01*
X-417441Y-106543D01*
G01X-505241Y-143293D02*
X189259D01*
G01X-505241Y-128293D02*
X189259D01*
G01X-503741Y-73293D02*
X189259D01*
G01X-493574Y210207D02*
Y215207D01*
X-491908D01*
X-491241Y214957D01*
X-490741Y214624D01*
X-490324Y214124D01*
X-489991Y213540D01*
X-489908Y212707D01*
X-489991Y211874D01*
X-490324Y211290D01*
X-490741Y210790D01*
X-491241Y210457D01*
X-491908Y210207D01*
X-493574D01*
G01X-487308D02*
Y213540D01*
G01Y212874D02*
X-486891Y213207D01*
X-486474Y213457D01*
X-485891Y213540D01*
X-485474Y213457D01*
X-484974Y213207D01*
G01X-480541Y213540D02*
Y210207D01*
G01Y214874D02*
X-480708Y214957D01*
Y215124D01*
X-480541Y215207D01*
X-480374Y215124D01*
Y214957D01*
X-480541Y214874D01*
G01X-474941Y210207D02*
Y215207D01*
G01X-469341Y210207D02*
Y215207D01*
G01X-480281Y377947D02*
X-478281D01*
G01X-479281D02*
Y372947D01*
G01X-480281D02*
X-478281D01*
G01X-475098D02*
Y376280D01*
G01Y375447D02*
X-474764Y375864D01*
X-474264Y376197D01*
X-473598Y376280D01*
X-473014Y376197D01*
X-472514Y375864D01*
X-472264Y375280D01*
Y372947D01*
G01X-469498D02*
Y376280D01*
G01Y375447D02*
X-469164Y375864D01*
X-468664Y376197D01*
X-467998Y376280D01*
X-467414Y376197D01*
X-466914Y375864D01*
X-466664Y375280D01*
Y372947D01*
G01X-463731Y375197D02*
X-461064D01*
X-461314Y375780D01*
X-461731Y376114D01*
X-462314Y376280D01*
X-462898Y376197D01*
X-463398Y375947D01*
X-463731Y375364D01*
X-463898Y374864D01*
Y374364D01*
X-463731Y373864D01*
X-463314Y373364D01*
X-462814Y373030D01*
X-462231Y372947D01*
X-461648Y373114D01*
X-461064Y373614D01*
G01X-458048Y372947D02*
Y376280D01*
G01Y375614D02*
X-457631Y375947D01*
X-457214Y376197D01*
X-456631Y376280D01*
X-456214Y376197D01*
X-455714Y375947D01*
G01X-445681Y372947D02*
Y377947D01*
G01X-438581Y372947D02*
Y376280D01*
G01Y375697D02*
X-438914Y376030D01*
X-439414Y376197D01*
X-439998Y376280D01*
X-440581Y376114D01*
X-441081Y375780D01*
X-441414Y375280D01*
X-441581Y374614D01*
X-441414Y373947D01*
X-441081Y373447D01*
X-440581Y373114D01*
X-439998Y372947D01*
X-439414Y373030D01*
X-438914Y373280D01*
X-438581Y373614D01*
G01X-436231Y371447D02*
X-435731Y371280D01*
X-435064Y371447D01*
X-434648Y371780D01*
X-434314Y372197D01*
X-433814Y373530D01*
X-432731Y376280D01*
G01X-435398D02*
X-433814Y373530D01*
G01X-430131Y375197D02*
X-427464D01*
X-427714Y375780D01*
X-428131Y376114D01*
X-428714Y376280D01*
X-429298Y376197D01*
X-429798Y375947D01*
X-430131Y375364D01*
X-430298Y374864D01*
Y374364D01*
X-430131Y373864D01*
X-429714Y373364D01*
X-429214Y373030D01*
X-428631Y372947D01*
X-428048Y373114D01*
X-427464Y373614D01*
G01X-424448Y372947D02*
Y376280D01*
G01Y375614D02*
X-424031Y375947D01*
X-423614Y376197D01*
X-423031Y376280D01*
X-422614Y376197D01*
X-422114Y375947D01*
G01X-505241Y350207D02*
X189259D01*
G01X-495324Y444874D02*
X-494824Y445374D01*
X-494241Y445624D01*
X-493574Y445707D01*
X-492741Y445540D01*
X-492158Y445124D01*
X-491991Y444624D01*
X-492074Y444124D01*
X-492408Y443707D01*
X-494074Y442874D01*
X-494824Y442290D01*
X-495324Y441457D01*
X-495491Y440707D01*
X-491991D01*
G01X-488141Y440540D02*
X-488308Y440624D01*
Y440790D01*
X-488141Y440874D01*
X-487974Y440790D01*
Y440624D01*
X-488141Y440540D01*
G01X-482541Y445707D02*
Y440707D01*
G01X-484458Y445707D02*
X-480624D01*
G01X-476941Y440707D02*
X-477441Y440790D01*
X-477941Y441124D01*
X-478274Y441707D01*
X-478441Y442374D01*
X-478274Y443040D01*
X-477941Y443624D01*
X-477441Y443957D01*
X-476941Y444040D01*
X-476441Y443957D01*
X-475941Y443624D01*
X-475608Y443040D01*
X-475524Y442374D01*
X-475608Y441707D01*
X-475941Y441124D01*
X-476441Y440790D01*
X-476941Y440707D01*
G01X-471341D02*
Y445707D01*
G01X-466991Y442957D02*
X-464324D01*
X-464574Y443540D01*
X-464991Y443874D01*
X-465574Y444040D01*
X-466158Y443957D01*
X-466658Y443707D01*
X-466991Y443124D01*
X-467158Y442624D01*
Y442124D01*
X-466991Y441624D01*
X-466574Y441124D01*
X-466074Y440790D01*
X-465491Y440707D01*
X-464908Y440874D01*
X-464324Y441374D01*
G01X-461308Y440707D02*
Y444040D01*
G01Y443374D02*
X-460891Y443707D01*
X-460474Y443957D01*
X-459891Y444040D01*
X-459474Y443957D01*
X-458974Y443707D01*
G01X-453041Y440707D02*
Y444040D01*
G01Y443457D02*
X-453374Y443790D01*
X-453874Y443957D01*
X-454458Y444040D01*
X-455041Y443874D01*
X-455541Y443540D01*
X-455874Y443040D01*
X-456041Y442374D01*
X-455874Y441707D01*
X-455541Y441207D01*
X-455041Y440874D01*
X-454458Y440707D01*
X-453874Y440790D01*
X-453374Y441040D01*
X-453041Y441374D01*
G01X-450358Y440707D02*
Y444040D01*
G01Y443207D02*
X-450024Y443624D01*
X-449524Y443957D01*
X-448858Y444040D01*
X-448274Y443957D01*
X-447774Y443624D01*
X-447524Y443040D01*
Y440707D01*
G01X-442008Y443624D02*
X-442591Y443957D01*
X-443091Y444040D01*
X-443758Y443874D01*
X-444258Y443540D01*
X-444591Y442957D01*
X-444674Y442374D01*
X-444591Y441790D01*
X-444258Y441290D01*
X-443758Y440874D01*
X-443091Y440707D01*
X-442508Y440874D01*
X-442008Y441207D01*
G01X-438991Y442957D02*
X-436324D01*
X-436574Y443540D01*
X-436991Y443874D01*
X-437574Y444040D01*
X-438158Y443957D01*
X-438658Y443707D01*
X-438991Y443124D01*
X-439158Y442624D01*
Y442124D01*
X-438991Y441624D01*
X-438574Y441124D01*
X-438074Y440790D01*
X-437491Y440707D01*
X-436908Y440874D01*
X-436324Y441374D01*
G01X-426541Y445707D02*
Y440707D01*
G01X-427708Y444040D02*
X-425374D01*
G01X-419441Y440707D02*
Y444040D01*
G01Y443457D02*
X-419774Y443790D01*
X-420274Y443957D01*
X-420858Y444040D01*
X-421441Y443874D01*
X-421941Y443540D01*
X-422274Y443040D01*
X-422441Y442374D01*
X-422274Y441707D01*
X-421941Y441207D01*
X-421441Y440874D01*
X-420858Y440707D01*
X-420274Y440790D01*
X-419774Y441040D01*
X-419441Y441374D01*
G01X-416841Y440707D02*
Y445707D01*
G01Y443207D02*
X-416424Y443707D01*
X-415924Y443957D01*
X-415424Y444040D01*
X-414674Y443874D01*
X-414174Y443540D01*
X-413841Y442957D01*
Y442290D01*
X-414008Y441624D01*
X-414341Y441124D01*
X-414924Y440790D01*
X-415424Y440707D01*
X-415924Y440790D01*
X-416424Y441040D01*
X-416841Y441457D01*
G01X-409741Y440707D02*
Y445707D01*
G01X-405391Y442957D02*
X-402724D01*
X-402974Y443540D01*
X-403391Y443874D01*
X-403974Y444040D01*
X-404558Y443957D01*
X-405058Y443707D01*
X-405391Y443124D01*
X-405558Y442624D01*
Y442124D01*
X-405391Y441624D01*
X-404974Y441124D01*
X-404474Y440790D01*
X-403891Y440707D01*
X-403308Y440874D01*
X-402724Y441374D01*
G01X-398541Y440540D02*
X-398708Y440624D01*
Y440790D01*
X-398541Y440874D01*
X-398374Y440790D01*
Y440624D01*
X-398541Y440540D01*
G01Y442790D02*
X-398708Y442874D01*
Y443040D01*
X-398541Y443124D01*
X-398374Y443040D01*
Y442874D01*
X-398541Y442790D01*
G01X-471241Y414540D02*
Y419540D01*
G01Y418790D02*
X-470824Y419207D01*
X-470408Y419457D01*
X-469741Y419540D01*
X-469158Y419457D01*
X-468574Y419040D01*
X-468324Y418457D01*
X-468241Y417874D01*
X-468324Y417290D01*
X-468574Y416707D01*
X-469074Y416374D01*
X-469741Y416207D01*
X-470324Y416290D01*
X-470908Y416540D01*
X-471241Y416874D01*
G01X-465308Y416207D02*
Y419540D01*
G01Y418874D02*
X-464891Y419207D01*
X-464474Y419457D01*
X-463891Y419540D01*
X-463474Y419457D01*
X-462974Y419207D01*
G01X-458541Y416207D02*
X-459041Y416290D01*
X-459541Y416624D01*
X-459874Y417207D01*
X-460041Y417874D01*
X-459874Y418540D01*
X-459541Y419124D01*
X-459041Y419457D01*
X-458541Y419540D01*
X-458041Y419457D01*
X-457541Y419124D01*
X-457208Y418540D01*
X-457124Y417874D01*
X-457208Y417207D01*
X-457541Y416624D01*
X-458041Y416290D01*
X-458541Y416207D01*
G01X-451608Y419124D02*
X-452191Y419457D01*
X-452691Y419540D01*
X-453358Y419374D01*
X-453858Y419040D01*
X-454191Y418457D01*
X-454274Y417874D01*
X-454191Y417290D01*
X-453858Y416790D01*
X-453358Y416374D01*
X-452691Y416207D01*
X-452108Y416374D01*
X-451608Y416707D01*
G01X-448591Y418457D02*
X-445924D01*
X-446174Y419040D01*
X-446591Y419374D01*
X-447174Y419540D01*
X-447758Y419457D01*
X-448258Y419207D01*
X-448591Y418624D01*
X-448758Y418124D01*
Y417624D01*
X-448591Y417124D01*
X-448174Y416624D01*
X-447674Y416290D01*
X-447091Y416207D01*
X-446508Y416374D01*
X-445924Y416874D01*
G01X-442991Y416790D02*
X-442574Y416457D01*
X-441991Y416207D01*
X-441491D01*
X-440991Y416374D01*
X-440658Y416624D01*
X-440491Y416957D01*
X-440574Y417457D01*
X-440908Y417707D01*
X-442408Y418207D01*
X-442741Y418790D01*
X-442574Y419207D01*
X-442241Y419457D01*
X-441741Y419540D01*
X-441241Y419457D01*
X-440741Y419207D01*
G01X-437391Y416790D02*
X-436974Y416457D01*
X-436391Y416207D01*
X-435891D01*
X-435391Y416374D01*
X-435058Y416624D01*
X-434891Y416957D01*
X-434974Y417457D01*
X-435308Y417707D01*
X-436808Y418207D01*
X-437141Y418790D01*
X-436974Y419207D01*
X-436641Y419457D01*
X-436141Y419540D01*
X-435641Y419457D01*
X-435141Y419207D01*
G01X-505241Y430207D02*
X189259D01*
G01X-506241Y405207D02*
X189259D01*
G01X-505241Y601707D02*
Y460207D01*
X189259D01*
Y601707D01*
G01X-498241Y583707D02*
Y588707D01*
X-499241Y587707D01*
G01Y583707D02*
X-497241D01*
G01X-492641Y583540D02*
X-492808Y583624D01*
Y583790D01*
X-492641Y583874D01*
X-492474Y583790D01*
Y583624D01*
X-492641Y583540D01*
G01X-488791Y584374D02*
X-488124Y583957D01*
X-487374Y583707D01*
X-486708D01*
X-486041Y583957D01*
X-485541Y584374D01*
X-485291Y584957D01*
X-485458Y585540D01*
X-485874Y586040D01*
X-486624Y586374D01*
X-487624Y586540D01*
X-488208Y586874D01*
X-488458Y587457D01*
X-488291Y588040D01*
X-487874Y588457D01*
X-487291Y588707D01*
X-486708D01*
X-486124Y588540D01*
X-485624Y588124D01*
G01X-482941Y582040D02*
Y587040D01*
G01Y586290D02*
X-482524Y586707D01*
X-482108Y586957D01*
X-481441Y587040D01*
X-480858Y586957D01*
X-480274Y586540D01*
X-480024Y585957D01*
X-479941Y585374D01*
X-480024Y584790D01*
X-480274Y584207D01*
X-480774Y583874D01*
X-481441Y583707D01*
X-482024Y583790D01*
X-482608Y584040D01*
X-482941Y584374D01*
G01X-477091Y585957D02*
X-474424D01*
X-474674Y586540D01*
X-475091Y586874D01*
X-475674Y587040D01*
X-476258Y586957D01*
X-476758Y586707D01*
X-477091Y586124D01*
X-477258Y585624D01*
Y585124D01*
X-477091Y584624D01*
X-476674Y584124D01*
X-476174Y583790D01*
X-475591Y583707D01*
X-475008Y583874D01*
X-474424Y584374D01*
G01X-468908Y586624D02*
X-469491Y586957D01*
X-469991Y587040D01*
X-470658Y586874D01*
X-471158Y586540D01*
X-471491Y585957D01*
X-471574Y585374D01*
X-471491Y584790D01*
X-471158Y584290D01*
X-470658Y583874D01*
X-469991Y583707D01*
X-469408Y583874D01*
X-468908Y584207D01*
G01X-464641Y587040D02*
Y583707D01*
G01Y588374D02*
X-464808Y588457D01*
Y588624D01*
X-464641Y588707D01*
X-464474Y588624D01*
Y588457D01*
X-464641Y588374D01*
G01X-459541Y583707D02*
Y587957D01*
X-459374Y588374D01*
X-459041Y588624D01*
X-458541Y588707D01*
X-458041Y588540D01*
X-457791Y588124D01*
G01X-458791Y586707D02*
X-460458D01*
G01X-453441Y587040D02*
Y583707D01*
G01Y588374D02*
X-453608Y588457D01*
Y588624D01*
X-453441Y588707D01*
X-453274Y588624D01*
Y588457D01*
X-453441Y588374D01*
G01X-446508Y586624D02*
X-447091Y586957D01*
X-447591Y587040D01*
X-448258Y586874D01*
X-448758Y586540D01*
X-449091Y585957D01*
X-449174Y585374D01*
X-449091Y584790D01*
X-448758Y584290D01*
X-448258Y583874D01*
X-447591Y583707D01*
X-447008Y583874D01*
X-446508Y584207D01*
G01X-440741Y583707D02*
Y587040D01*
G01Y586457D02*
X-441074Y586790D01*
X-441574Y586957D01*
X-442158Y587040D01*
X-442741Y586874D01*
X-443241Y586540D01*
X-443574Y586040D01*
X-443741Y585374D01*
X-443574Y584707D01*
X-443241Y584207D01*
X-442741Y583874D01*
X-442158Y583707D01*
X-441574Y583790D01*
X-441074Y584040D01*
X-440741Y584374D01*
G01X-436641Y588707D02*
Y583707D01*
G01X-437808Y587040D02*
X-435474D01*
G01X-431041D02*
Y583707D01*
G01Y588374D02*
X-431208Y588457D01*
Y588624D01*
X-431041Y588707D01*
X-430874Y588624D01*
Y588457D01*
X-431041Y588374D01*
G01X-425441Y583707D02*
X-425941Y583790D01*
X-426441Y584124D01*
X-426774Y584707D01*
X-426941Y585374D01*
X-426774Y586040D01*
X-426441Y586624D01*
X-425941Y586957D01*
X-425441Y587040D01*
X-424941Y586957D01*
X-424441Y586624D01*
X-424108Y586040D01*
X-424024Y585374D01*
X-424108Y584707D01*
X-424441Y584124D01*
X-424941Y583790D01*
X-425441Y583707D01*
G01X-421258D02*
Y587040D01*
G01Y586207D02*
X-420924Y586624D01*
X-420424Y586957D01*
X-419758Y587040D01*
X-419174Y586957D01*
X-418674Y586624D01*
X-418424Y586040D01*
Y583707D01*
G01X-407141Y588707D02*
Y583707D01*
G01Y584457D02*
X-407474Y584040D01*
X-407974Y583790D01*
X-408558Y583707D01*
X-409224Y583874D01*
X-409724Y584290D01*
X-410058Y584790D01*
X-410141Y585374D01*
X-410058Y585957D01*
X-409724Y586457D01*
X-409224Y586874D01*
X-408558Y587040D01*
X-407974Y586957D01*
X-407558Y586790D01*
X-407141Y586457D01*
G01X-403041Y583707D02*
X-403541Y583790D01*
X-404041Y584124D01*
X-404374Y584707D01*
X-404541Y585374D01*
X-404374Y586040D01*
X-404041Y586624D01*
X-403541Y586957D01*
X-403041Y587040D01*
X-402541Y586957D01*
X-402041Y586624D01*
X-401708Y586040D01*
X-401624Y585374D01*
X-401708Y584707D01*
X-402041Y584124D01*
X-402541Y583790D01*
X-403041Y583707D01*
G01X-396108Y586624D02*
X-396691Y586957D01*
X-397191Y587040D01*
X-397858Y586874D01*
X-398358Y586540D01*
X-398691Y585957D01*
X-398774Y585374D01*
X-398691Y584790D01*
X-398358Y584290D01*
X-397858Y583874D01*
X-397191Y583707D01*
X-396608Y583874D01*
X-396108Y584207D01*
G01X-393258Y587040D02*
Y584707D01*
X-392924Y584124D01*
X-392424Y583790D01*
X-391841Y583707D01*
X-391258Y583790D01*
X-390758Y584124D01*
X-390424Y584707D01*
G01Y583707D02*
Y587040D01*
G01X-388741Y583707D02*
Y587040D01*
G01Y586124D02*
X-388491Y586540D01*
X-388074Y586874D01*
X-387491Y587040D01*
X-386908Y586874D01*
X-386491Y586540D01*
X-386241Y586124D01*
Y583707D01*
G01Y586124D02*
X-385991Y586540D01*
X-385574Y586874D01*
X-384991Y587040D01*
X-384408Y586874D01*
X-383991Y586540D01*
X-383741Y586040D01*
Y583707D01*
G01X-381891Y585957D02*
X-379224D01*
X-379474Y586540D01*
X-379891Y586874D01*
X-380474Y587040D01*
X-381058Y586957D01*
X-381558Y586707D01*
X-381891Y586124D01*
X-382058Y585624D01*
Y585124D01*
X-381891Y584624D01*
X-381474Y584124D01*
X-380974Y583790D01*
X-380391Y583707D01*
X-379808Y583874D01*
X-379224Y584374D01*
G01X-376458Y583707D02*
Y587040D01*
G01Y586207D02*
X-376124Y586624D01*
X-375624Y586957D01*
X-374958Y587040D01*
X-374374Y586957D01*
X-373874Y586624D01*
X-373624Y586040D01*
Y583707D01*
G01X-369441Y588707D02*
Y583707D01*
G01X-370608Y587040D02*
X-368274D01*
G01X-363841Y583540D02*
X-364008Y583624D01*
Y583790D01*
X-363841Y583874D01*
X-363674Y583790D01*
Y583624D01*
X-363841Y583540D01*
G01Y585790D02*
X-364008Y585874D01*
Y586040D01*
X-363841Y586124D01*
X-363674Y586040D01*
Y585874D01*
X-363841Y585790D01*
G01X-505241Y571707D02*
X189259D01*
G01X-505241Y601707D02*
X189259D01*
G01X-392908Y-308793D02*
Y-313793D01*
X-389574D01*
G01X-385641D02*
X-386141Y-313710D01*
X-386641Y-313376D01*
X-386974Y-312793D01*
X-387141Y-312126D01*
X-386974Y-311460D01*
X-386641Y-310876D01*
X-386141Y-310543D01*
X-385641Y-310460D01*
X-385141Y-310543D01*
X-384641Y-310876D01*
X-384308Y-311460D01*
X-384224Y-312126D01*
X-384308Y-312793D01*
X-384641Y-313376D01*
X-385141Y-313710D01*
X-385641Y-313793D01*
G01X-381208Y-315043D02*
X-380624Y-315376D01*
X-379958Y-315460D01*
X-379374Y-315376D01*
X-378874Y-314960D01*
X-378541Y-314376D01*
Y-310460D01*
G01Y-311126D02*
X-378874Y-310793D01*
X-379374Y-310543D01*
X-379958Y-310460D01*
X-380624Y-310626D01*
X-381041Y-310960D01*
X-381374Y-311543D01*
X-381541Y-312126D01*
X-381458Y-312626D01*
X-381124Y-313210D01*
X-380624Y-313626D01*
X-379958Y-313793D01*
X-379458Y-313710D01*
X-378874Y-313376D01*
X-378541Y-313043D01*
G01X-374441Y-313793D02*
X-374941Y-313710D01*
X-375441Y-313376D01*
X-375774Y-312793D01*
X-375941Y-312126D01*
X-375774Y-311460D01*
X-375441Y-310876D01*
X-374941Y-310543D01*
X-374441Y-310460D01*
X-373941Y-310543D01*
X-373441Y-310876D01*
X-373108Y-311460D01*
X-373024Y-312126D01*
X-373108Y-312793D01*
X-373441Y-313376D01*
X-373941Y-313710D01*
X-374441Y-313793D01*
G01X-401741Y430207D02*
Y-318293D01*
G01X-391241Y-263793D02*
Y-268793D01*
G01X-392408Y-265460D02*
X-390074D01*
G01X-387058Y-268793D02*
Y-263793D01*
G01Y-266210D02*
X-386641Y-265793D01*
X-386224Y-265543D01*
X-385558Y-265460D01*
X-385058Y-265543D01*
X-384474Y-265876D01*
X-384224Y-266376D01*
Y-268793D01*
G01X-380041Y-265460D02*
Y-268793D01*
G01Y-264126D02*
X-380208Y-264043D01*
Y-263876D01*
X-380041Y-263793D01*
X-379874Y-263876D01*
Y-264043D01*
X-380041Y-264126D01*
G01X-373108Y-265876D02*
X-373691Y-265543D01*
X-374191Y-265460D01*
X-374858Y-265626D01*
X-375358Y-265960D01*
X-375691Y-266543D01*
X-375774Y-267126D01*
X-375691Y-267710D01*
X-375358Y-268210D01*
X-374858Y-268626D01*
X-374191Y-268793D01*
X-373608Y-268626D01*
X-373108Y-268293D01*
G01X-370258Y-268793D02*
Y-263793D01*
G01X-367591Y-265460D02*
X-370258Y-267376D01*
G01X-369174Y-266626D02*
X-367424Y-268793D01*
G01X-364658D02*
Y-265460D01*
G01Y-266293D02*
X-364324Y-265876D01*
X-363824Y-265543D01*
X-363158Y-265460D01*
X-362574Y-265543D01*
X-362074Y-265876D01*
X-361824Y-266460D01*
Y-268793D01*
G01X-358891Y-266543D02*
X-356224D01*
X-356474Y-265960D01*
X-356891Y-265626D01*
X-357474Y-265460D01*
X-358058Y-265543D01*
X-358558Y-265793D01*
X-358891Y-266376D01*
X-359058Y-266876D01*
Y-267376D01*
X-358891Y-267876D01*
X-358474Y-268376D01*
X-357974Y-268710D01*
X-357391Y-268793D01*
X-356808Y-268626D01*
X-356224Y-268126D01*
G01X-353291Y-268210D02*
X-352874Y-268543D01*
X-352291Y-268793D01*
X-351791D01*
X-351291Y-268626D01*
X-350958Y-268376D01*
X-350791Y-268043D01*
X-350874Y-267543D01*
X-351208Y-267293D01*
X-352708Y-266793D01*
X-353041Y-266210D01*
X-352874Y-265793D01*
X-352541Y-265543D01*
X-352041Y-265460D01*
X-351541Y-265543D01*
X-351041Y-265793D01*
G01X-347691Y-268210D02*
X-347274Y-268543D01*
X-346691Y-268793D01*
X-346191D01*
X-345691Y-268626D01*
X-345358Y-268376D01*
X-345191Y-268043D01*
X-345274Y-267543D01*
X-345608Y-267293D01*
X-347108Y-266793D01*
X-347441Y-266210D01*
X-347274Y-265793D01*
X-346941Y-265543D01*
X-346441Y-265460D01*
X-345941Y-265543D01*
X-345441Y-265793D01*
G01X-391241Y-284793D02*
Y-289793D01*
G01X-392408Y-286460D02*
X-390074D01*
G01X-387058Y-289793D02*
Y-284793D01*
G01Y-287210D02*
X-386641Y-286793D01*
X-386224Y-286543D01*
X-385558Y-286460D01*
X-385058Y-286543D01*
X-384474Y-286876D01*
X-384224Y-287376D01*
Y-289793D01*
G01X-380041Y-286460D02*
Y-289793D01*
G01Y-285126D02*
X-380208Y-285043D01*
Y-284876D01*
X-380041Y-284793D01*
X-379874Y-284876D01*
Y-285043D01*
X-380041Y-285126D01*
G01X-373108Y-286876D02*
X-373691Y-286543D01*
X-374191Y-286460D01*
X-374858Y-286626D01*
X-375358Y-286960D01*
X-375691Y-287543D01*
X-375774Y-288126D01*
X-375691Y-288710D01*
X-375358Y-289210D01*
X-374858Y-289626D01*
X-374191Y-289793D01*
X-373608Y-289626D01*
X-373108Y-289293D01*
G01X-370258Y-289793D02*
Y-284793D01*
G01X-367591Y-286460D02*
X-370258Y-288376D01*
G01X-369174Y-287626D02*
X-367424Y-289793D01*
G01X-364658D02*
Y-286460D01*
G01Y-287293D02*
X-364324Y-286876D01*
X-363824Y-286543D01*
X-363158Y-286460D01*
X-362574Y-286543D01*
X-362074Y-286876D01*
X-361824Y-287460D01*
Y-289793D01*
G01X-358891Y-287543D02*
X-356224D01*
X-356474Y-286960D01*
X-356891Y-286626D01*
X-357474Y-286460D01*
X-358058Y-286543D01*
X-358558Y-286793D01*
X-358891Y-287376D01*
X-359058Y-287876D01*
Y-288376D01*
X-358891Y-288876D01*
X-358474Y-289376D01*
X-357974Y-289710D01*
X-357391Y-289793D01*
X-356808Y-289626D01*
X-356224Y-289126D01*
G01X-353291Y-289210D02*
X-352874Y-289543D01*
X-352291Y-289793D01*
X-351791D01*
X-351291Y-289626D01*
X-350958Y-289376D01*
X-350791Y-289043D01*
X-350874Y-288543D01*
X-351208Y-288293D01*
X-352708Y-287793D01*
X-353041Y-287210D01*
X-352874Y-286793D01*
X-352541Y-286543D01*
X-352041Y-286460D01*
X-351541Y-286543D01*
X-351041Y-286793D01*
G01X-347691Y-289210D02*
X-347274Y-289543D01*
X-346691Y-289793D01*
X-346191D01*
X-345691Y-289626D01*
X-345358Y-289376D01*
X-345191Y-289043D01*
X-345274Y-288543D01*
X-345608Y-288293D01*
X-347108Y-287793D01*
X-347441Y-287210D01*
X-347274Y-286793D01*
X-346941Y-286543D01*
X-346441Y-286460D01*
X-345941Y-286543D01*
X-345441Y-286793D01*
G01X-386058Y-250960D02*
X-386891Y-250126D01*
X-387308Y-249293D01*
Y-245960D01*
X-386891Y-245126D01*
X-386058Y-244293D01*
G01X-381791Y-248626D02*
X-381124Y-249043D01*
X-380374Y-249293D01*
X-379708D01*
X-379041Y-249043D01*
X-378541Y-248626D01*
X-378291Y-248043D01*
X-378458Y-247460D01*
X-378874Y-246960D01*
X-379624Y-246626D01*
X-380624Y-246460D01*
X-381208Y-246126D01*
X-381458Y-245543D01*
X-381291Y-244960D01*
X-380874Y-244543D01*
X-380291Y-244293D01*
X-379708D01*
X-379124Y-244460D01*
X-378624Y-244876D01*
G01X-376608Y-249293D02*
Y-244293D01*
X-374441Y-248460D01*
X-372274Y-244293D01*
Y-249293D01*
G01X-370674D02*
Y-244293D01*
X-369008D01*
X-368341Y-244543D01*
X-367841Y-244876D01*
X-367424Y-245376D01*
X-367091Y-245960D01*
X-367008Y-246793D01*
X-367091Y-247626D01*
X-367424Y-248210D01*
X-367841Y-248710D01*
X-368341Y-249043D01*
X-369008Y-249293D01*
X-370674D01*
G01X-362824Y-250960D02*
X-361991Y-250126D01*
X-361574Y-249293D01*
Y-245960D01*
X-361991Y-245126D01*
X-362824Y-244293D01*
G01X-392991Y-236626D02*
X-392324Y-237043D01*
X-391574Y-237293D01*
X-390908D01*
X-390241Y-237043D01*
X-389741Y-236626D01*
X-389491Y-236043D01*
X-389658Y-235460D01*
X-390074Y-234960D01*
X-390824Y-234626D01*
X-391824Y-234460D01*
X-392408Y-234126D01*
X-392658Y-233543D01*
X-392491Y-232960D01*
X-392074Y-232543D01*
X-391491Y-232293D01*
X-390908D01*
X-390324Y-232460D01*
X-389824Y-232876D01*
G01X-385641Y-237293D02*
X-386141Y-237210D01*
X-386641Y-236876D01*
X-386974Y-236293D01*
X-387141Y-235626D01*
X-386974Y-234960D01*
X-386641Y-234376D01*
X-386141Y-234043D01*
X-385641Y-233960D01*
X-385141Y-234043D01*
X-384641Y-234376D01*
X-384308Y-234960D01*
X-384224Y-235626D01*
X-384308Y-236293D01*
X-384641Y-236876D01*
X-385141Y-237210D01*
X-385641Y-237293D01*
G01X-380041D02*
Y-232293D01*
G01X-372941D02*
Y-237293D01*
G01Y-236543D02*
X-373274Y-236960D01*
X-373774Y-237210D01*
X-374358Y-237293D01*
X-375024Y-237126D01*
X-375524Y-236710D01*
X-375858Y-236210D01*
X-375941Y-235626D01*
X-375858Y-235043D01*
X-375524Y-234543D01*
X-375024Y-234126D01*
X-374358Y-233960D01*
X-373774Y-234043D01*
X-373358Y-234210D01*
X-372941Y-234543D01*
G01X-370091Y-235043D02*
X-367424D01*
X-367674Y-234460D01*
X-368091Y-234126D01*
X-368674Y-233960D01*
X-369258Y-234043D01*
X-369758Y-234293D01*
X-370091Y-234876D01*
X-370258Y-235376D01*
Y-235876D01*
X-370091Y-236376D01*
X-369674Y-236876D01*
X-369174Y-237210D01*
X-368591Y-237293D01*
X-368008Y-237126D01*
X-367424Y-236626D01*
G01X-364408Y-237293D02*
Y-233960D01*
G01Y-234626D02*
X-363991Y-234293D01*
X-363574Y-234043D01*
X-362991Y-233960D01*
X-362574Y-234043D01*
X-362074Y-234293D01*
G01X-354541Y-237293D02*
Y-233960D01*
G01Y-234876D02*
X-354291Y-234460D01*
X-353874Y-234126D01*
X-353291Y-233960D01*
X-352708Y-234126D01*
X-352291Y-234460D01*
X-352041Y-234876D01*
Y-237293D01*
G01Y-234876D02*
X-351791Y-234460D01*
X-351374Y-234126D01*
X-350791Y-233960D01*
X-350208Y-234126D01*
X-349791Y-234460D01*
X-349541Y-234960D01*
Y-237293D01*
G01X-344941D02*
Y-233960D01*
G01Y-234543D02*
X-345274Y-234210D01*
X-345774Y-234043D01*
X-346358Y-233960D01*
X-346941Y-234126D01*
X-347441Y-234460D01*
X-347774Y-234960D01*
X-347941Y-235626D01*
X-347774Y-236293D01*
X-347441Y-236793D01*
X-346941Y-237126D01*
X-346358Y-237293D01*
X-345774Y-237210D01*
X-345274Y-236960D01*
X-344941Y-236626D01*
G01X-342091Y-236710D02*
X-341674Y-237043D01*
X-341091Y-237293D01*
X-340591D01*
X-340091Y-237126D01*
X-339758Y-236876D01*
X-339591Y-236543D01*
X-339674Y-236043D01*
X-340008Y-235793D01*
X-341508Y-235293D01*
X-341841Y-234710D01*
X-341674Y-234293D01*
X-341341Y-234043D01*
X-340841Y-233960D01*
X-340341Y-234043D01*
X-339841Y-234293D01*
G01X-336658Y-237293D02*
Y-232293D01*
G01X-333991Y-233960D02*
X-336658Y-235876D01*
G01X-335574Y-235126D02*
X-333824Y-237293D01*
G01X-322541Y-232293D02*
Y-237293D01*
G01Y-236543D02*
X-322874Y-236960D01*
X-323374Y-237210D01*
X-323958Y-237293D01*
X-324624Y-237126D01*
X-325124Y-236710D01*
X-325458Y-236210D01*
X-325541Y-235626D01*
X-325458Y-235043D01*
X-325124Y-234543D01*
X-324624Y-234126D01*
X-323958Y-233960D01*
X-323374Y-234043D01*
X-322958Y-234210D01*
X-322541Y-234543D01*
G01X-319691Y-235043D02*
X-317024D01*
X-317274Y-234460D01*
X-317691Y-234126D01*
X-318274Y-233960D01*
X-318858Y-234043D01*
X-319358Y-234293D01*
X-319691Y-234876D01*
X-319858Y-235376D01*
Y-235876D01*
X-319691Y-236376D01*
X-319274Y-236876D01*
X-318774Y-237210D01*
X-318191Y-237293D01*
X-317608Y-237126D01*
X-317024Y-236626D01*
G01X-313341Y-237293D02*
Y-233043D01*
X-313174Y-232626D01*
X-312841Y-232376D01*
X-312341Y-232293D01*
X-311841Y-232460D01*
X-311591Y-232876D01*
G01X-312591Y-234293D02*
X-314258D01*
G01X-307241Y-233960D02*
Y-237293D01*
G01Y-232626D02*
X-307408Y-232543D01*
Y-232376D01*
X-307241Y-232293D01*
X-307074Y-232376D01*
Y-232543D01*
X-307241Y-232626D01*
G01X-303058Y-237293D02*
Y-233960D01*
G01Y-234793D02*
X-302724Y-234376D01*
X-302224Y-234043D01*
X-301558Y-233960D01*
X-300974Y-234043D01*
X-300474Y-234376D01*
X-300224Y-234960D01*
Y-237293D01*
G01X-297291Y-235043D02*
X-294624D01*
X-294874Y-234460D01*
X-295291Y-234126D01*
X-295874Y-233960D01*
X-296458Y-234043D01*
X-296958Y-234293D01*
X-297291Y-234876D01*
X-297458Y-235376D01*
Y-235876D01*
X-297291Y-236376D01*
X-296874Y-236876D01*
X-296374Y-237210D01*
X-295791Y-237293D01*
X-295208Y-237126D01*
X-294624Y-236626D01*
G01X-286341Y-238960D02*
Y-233960D01*
G01Y-234710D02*
X-285924Y-234293D01*
X-285508Y-234043D01*
X-284841Y-233960D01*
X-284258Y-234043D01*
X-283674Y-234460D01*
X-283424Y-235043D01*
X-283341Y-235626D01*
X-283424Y-236210D01*
X-283674Y-236793D01*
X-284174Y-237126D01*
X-284841Y-237293D01*
X-285424Y-237210D01*
X-286008Y-236960D01*
X-286341Y-236626D01*
G01X-277741Y-237293D02*
Y-233960D01*
G01Y-234543D02*
X-278074Y-234210D01*
X-278574Y-234043D01*
X-279158Y-233960D01*
X-279741Y-234126D01*
X-280241Y-234460D01*
X-280574Y-234960D01*
X-280741Y-235626D01*
X-280574Y-236293D01*
X-280241Y-236793D01*
X-279741Y-237126D01*
X-279158Y-237293D01*
X-278574Y-237210D01*
X-278074Y-236960D01*
X-277741Y-236626D01*
G01X-272141Y-232293D02*
Y-237293D01*
G01Y-236543D02*
X-272474Y-236960D01*
X-272974Y-237210D01*
X-273558Y-237293D01*
X-274224Y-237126D01*
X-274724Y-236710D01*
X-275058Y-236210D01*
X-275141Y-235626D01*
X-275058Y-235043D01*
X-274724Y-234543D01*
X-274224Y-234126D01*
X-273558Y-233960D01*
X-272974Y-234043D01*
X-272558Y-234210D01*
X-272141Y-234543D01*
G01X-401741Y-258293D02*
X189259D01*
G01X-401741Y-303293D02*
X189259D01*
G01X-392758Y-224093D02*
Y-219093D01*
X-390591Y-223260D01*
X-388424Y-219093D01*
Y-224093D01*
G01X-383491D02*
Y-220760D01*
G01Y-221343D02*
X-383824Y-221010D01*
X-384324Y-220843D01*
X-384908Y-220760D01*
X-385491Y-220926D01*
X-385991Y-221260D01*
X-386324Y-221760D01*
X-386491Y-222426D01*
X-386324Y-223093D01*
X-385991Y-223593D01*
X-385491Y-223926D01*
X-384908Y-224093D01*
X-384324Y-224010D01*
X-383824Y-223760D01*
X-383491Y-223426D01*
G01X-380558Y-224093D02*
Y-220760D01*
G01Y-221426D02*
X-380141Y-221093D01*
X-379724Y-220843D01*
X-379141Y-220760D01*
X-378724Y-220843D01*
X-378224Y-221093D01*
G01X-375208Y-224093D02*
Y-219093D01*
G01X-372541Y-220760D02*
X-375208Y-222676D01*
G01X-374124Y-221926D02*
X-372374Y-224093D01*
G01X-367774Y-225760D02*
X-366941Y-224926D01*
X-366524Y-224093D01*
Y-220760D01*
X-366941Y-219926D01*
X-367774Y-219093D01*
G01X-392171Y-212663D02*
X-390504D01*
Y-214163D01*
X-391004Y-214663D01*
X-391588Y-214996D01*
X-392421Y-215163D01*
X-393254Y-214996D01*
X-393838Y-214663D01*
X-394338Y-214163D01*
X-394671Y-213580D01*
X-394838Y-212913D01*
Y-212330D01*
X-394671Y-211830D01*
X-394338Y-211246D01*
X-393838Y-210746D01*
X-393338Y-210413D01*
X-392671Y-210163D01*
X-392088D01*
X-391421Y-210330D01*
X-390921Y-210663D01*
G01X-387071Y-215163D02*
X-387571Y-215080D01*
X-388071Y-214746D01*
X-388404Y-214163D01*
X-388571Y-213496D01*
X-388404Y-212830D01*
X-388071Y-212246D01*
X-387571Y-211913D01*
X-387071Y-211830D01*
X-386571Y-211913D01*
X-386071Y-212246D01*
X-385738Y-212830D01*
X-385654Y-213496D01*
X-385738Y-214163D01*
X-386071Y-214746D01*
X-386571Y-215080D01*
X-387071Y-215163D01*
G01X-381471D02*
Y-210163D01*
G01X-374371D02*
Y-215163D01*
G01Y-214413D02*
X-374704Y-214830D01*
X-375204Y-215080D01*
X-375788Y-215163D01*
X-376454Y-214996D01*
X-376954Y-214580D01*
X-377288Y-214080D01*
X-377371Y-213496D01*
X-377288Y-212913D01*
X-376954Y-212413D01*
X-376454Y-211996D01*
X-375788Y-211830D01*
X-375204Y-211913D01*
X-374788Y-212080D01*
X-374371Y-212413D01*
G01X-371521Y-212913D02*
X-368854D01*
X-369104Y-212330D01*
X-369521Y-211996D01*
X-370104Y-211830D01*
X-370688Y-211913D01*
X-371188Y-212163D01*
X-371521Y-212746D01*
X-371688Y-213246D01*
Y-213746D01*
X-371521Y-214246D01*
X-371104Y-214746D01*
X-370604Y-215080D01*
X-370021Y-215163D01*
X-369438Y-214996D01*
X-368854Y-214496D01*
G01X-366088Y-215163D02*
Y-211830D01*
G01Y-212663D02*
X-365754Y-212246D01*
X-365254Y-211913D01*
X-364588Y-211830D01*
X-364004Y-211913D01*
X-363504Y-212246D01*
X-363254Y-212830D01*
Y-215163D01*
G01X-353971D02*
Y-210913D01*
X-353804Y-210496D01*
X-353471Y-210246D01*
X-352971Y-210163D01*
X-352471Y-210330D01*
X-352221Y-210746D01*
G01X-353221Y-212163D02*
X-354888D01*
G01X-347871Y-211830D02*
Y-215163D01*
G01Y-210496D02*
X-348038Y-210413D01*
Y-210246D01*
X-347871Y-210163D01*
X-347704Y-210246D01*
Y-210413D01*
X-347871Y-210496D01*
G01X-343688Y-215163D02*
Y-211830D01*
G01Y-212663D02*
X-343354Y-212246D01*
X-342854Y-211913D01*
X-342188Y-211830D01*
X-341604Y-211913D01*
X-341104Y-212246D01*
X-340854Y-212830D01*
Y-215163D01*
G01X-337838Y-216413D02*
X-337254Y-216746D01*
X-336588Y-216830D01*
X-336004Y-216746D01*
X-335504Y-216330D01*
X-335171Y-215746D01*
Y-211830D01*
G01Y-212496D02*
X-335504Y-212163D01*
X-336004Y-211913D01*
X-336588Y-211830D01*
X-337254Y-211996D01*
X-337671Y-212330D01*
X-338004Y-212913D01*
X-338171Y-213496D01*
X-338088Y-213996D01*
X-337754Y-214580D01*
X-337254Y-214996D01*
X-336588Y-215163D01*
X-336088Y-215080D01*
X-335504Y-214746D01*
X-335171Y-214413D01*
G01X-332321Y-212913D02*
X-329654D01*
X-329904Y-212330D01*
X-330321Y-211996D01*
X-330904Y-211830D01*
X-331488Y-211913D01*
X-331988Y-212163D01*
X-332321Y-212746D01*
X-332488Y-213246D01*
Y-213746D01*
X-332321Y-214246D01*
X-331904Y-214746D01*
X-331404Y-215080D01*
X-330821Y-215163D01*
X-330238Y-214996D01*
X-329654Y-214496D01*
G01X-326638Y-215163D02*
Y-211830D01*
G01Y-212496D02*
X-326221Y-212163D01*
X-325804Y-211913D01*
X-325221Y-211830D01*
X-324804Y-211913D01*
X-324304Y-212163D01*
G01X-315938Y-215163D02*
Y-210163D01*
X-313938D01*
X-313271Y-210413D01*
X-312771Y-210996D01*
X-312604Y-211663D01*
X-312771Y-212330D01*
X-313188Y-212830D01*
X-313938Y-213080D01*
X-315938D01*
G01X-310754Y-215163D02*
X-308671Y-210163D01*
X-306588Y-215163D01*
G01X-307338Y-213413D02*
X-310004D01*
G01X-304904Y-215163D02*
Y-210163D01*
X-303238D01*
X-302571Y-210413D01*
X-302071Y-210746D01*
X-301654Y-211246D01*
X-301321Y-211830D01*
X-301238Y-212663D01*
X-301321Y-213496D01*
X-301654Y-214080D01*
X-302071Y-214580D01*
X-302571Y-214913D01*
X-303238Y-215163D01*
X-304904D01*
G01X-293371Y-215330D02*
X-290371Y-210163D01*
G01X-287854Y-215163D02*
Y-210163D01*
X-284688D01*
G01X-285854Y-212580D02*
X-287854D01*
G01X-280671Y-211830D02*
Y-215163D01*
G01Y-210496D02*
X-280838Y-210413D01*
Y-210246D01*
X-280671Y-210163D01*
X-280504Y-210246D01*
Y-210413D01*
X-280671Y-210496D01*
G01X-273571Y-210163D02*
Y-215163D01*
G01Y-214413D02*
X-273904Y-214830D01*
X-274404Y-215080D01*
X-274988Y-215163D01*
X-275654Y-214996D01*
X-276154Y-214580D01*
X-276488Y-214080D01*
X-276571Y-213496D01*
X-276488Y-212913D01*
X-276154Y-212413D01*
X-275654Y-211996D01*
X-274988Y-211830D01*
X-274404Y-211913D01*
X-273988Y-212080D01*
X-273571Y-212413D01*
G01X-270888Y-211830D02*
Y-214163D01*
X-270554Y-214746D01*
X-270054Y-215080D01*
X-269471Y-215163D01*
X-268888Y-215080D01*
X-268388Y-214746D01*
X-268054Y-214163D01*
G01Y-215163D02*
Y-211830D01*
G01X-262538Y-212246D02*
X-263121Y-211913D01*
X-263621Y-211830D01*
X-264288Y-211996D01*
X-264788Y-212330D01*
X-265121Y-212913D01*
X-265204Y-213496D01*
X-265121Y-214080D01*
X-264788Y-214580D01*
X-264288Y-214996D01*
X-263621Y-215163D01*
X-263038Y-214996D01*
X-262538Y-214663D01*
G01X-258271Y-211830D02*
Y-215163D01*
G01Y-210496D02*
X-258438Y-210413D01*
Y-210246D01*
X-258271Y-210163D01*
X-258104Y-210246D01*
Y-210413D01*
X-258271Y-210496D01*
G01X-251171Y-215163D02*
Y-211830D01*
G01Y-212413D02*
X-251504Y-212080D01*
X-252004Y-211913D01*
X-252588Y-211830D01*
X-253171Y-211996D01*
X-253671Y-212330D01*
X-254004Y-212830D01*
X-254171Y-213496D01*
X-254004Y-214163D01*
X-253671Y-214663D01*
X-253171Y-214996D01*
X-252588Y-215163D01*
X-252004Y-215080D01*
X-251504Y-214830D01*
X-251171Y-214496D01*
G01X-247071Y-215163D02*
Y-210163D01*
G01X-392498Y-206120D02*
X-393331Y-205286D01*
X-393748Y-204453D01*
Y-201120D01*
X-393331Y-200286D01*
X-392498Y-199453D01*
G01X-388981Y-204453D02*
Y-201120D01*
G01Y-202036D02*
X-388731Y-201620D01*
X-388314Y-201286D01*
X-387731Y-201120D01*
X-387148Y-201286D01*
X-386731Y-201620D01*
X-386481Y-202036D01*
Y-204453D01*
G01Y-202036D02*
X-386231Y-201620D01*
X-385814Y-201286D01*
X-385231Y-201120D01*
X-384648Y-201286D01*
X-384231Y-201620D01*
X-383981Y-202120D01*
Y-204453D01*
G01X-382131Y-202203D02*
X-379464D01*
X-379714Y-201620D01*
X-380131Y-201286D01*
X-380714Y-201120D01*
X-381298Y-201203D01*
X-381798Y-201453D01*
X-382131Y-202036D01*
X-382298Y-202536D01*
Y-203036D01*
X-382131Y-203536D01*
X-381714Y-204036D01*
X-381214Y-204370D01*
X-380631Y-204453D01*
X-380048Y-204286D01*
X-379464Y-203786D01*
G01X-373781Y-204453D02*
Y-201120D01*
G01Y-201703D02*
X-374114Y-201370D01*
X-374614Y-201203D01*
X-375198Y-201120D01*
X-375781Y-201286D01*
X-376281Y-201620D01*
X-376614Y-202120D01*
X-376781Y-202786D01*
X-376614Y-203453D01*
X-376281Y-203953D01*
X-375781Y-204286D01*
X-375198Y-204453D01*
X-374614Y-204370D01*
X-374114Y-204120D01*
X-373781Y-203786D01*
G01X-370931Y-203870D02*
X-370514Y-204203D01*
X-369931Y-204453D01*
X-369431D01*
X-368931Y-204286D01*
X-368598Y-204036D01*
X-368431Y-203703D01*
X-368514Y-203203D01*
X-368848Y-202953D01*
X-370348Y-202453D01*
X-370681Y-201870D01*
X-370514Y-201453D01*
X-370181Y-201203D01*
X-369681Y-201120D01*
X-369181Y-201203D01*
X-368681Y-201453D01*
G01X-365498Y-201120D02*
Y-203453D01*
X-365164Y-204036D01*
X-364664Y-204370D01*
X-364081Y-204453D01*
X-363498Y-204370D01*
X-362998Y-204036D01*
X-362664Y-203453D01*
G01Y-204453D02*
Y-201120D01*
G01X-359648Y-204453D02*
Y-201120D01*
G01Y-201786D02*
X-359231Y-201453D01*
X-358814Y-201203D01*
X-358231Y-201120D01*
X-357814Y-201203D01*
X-357314Y-201453D01*
G01X-354131Y-202203D02*
X-351464D01*
X-351714Y-201620D01*
X-352131Y-201286D01*
X-352714Y-201120D01*
X-353298Y-201203D01*
X-353798Y-201453D01*
X-354131Y-202036D01*
X-354298Y-202536D01*
Y-203036D01*
X-354131Y-203536D01*
X-353714Y-204036D01*
X-353214Y-204370D01*
X-352631Y-204453D01*
X-352048Y-204286D01*
X-351464Y-203786D01*
G01X-341681Y-199453D02*
Y-204453D01*
G01X-342848Y-201120D02*
X-340514D01*
G01X-336081Y-204453D02*
X-336581Y-204370D01*
X-337081Y-204036D01*
X-337414Y-203453D01*
X-337581Y-202786D01*
X-337414Y-202120D01*
X-337081Y-201536D01*
X-336581Y-201203D01*
X-336081Y-201120D01*
X-335581Y-201203D01*
X-335081Y-201536D01*
X-334748Y-202120D01*
X-334664Y-202786D01*
X-334748Y-203453D01*
X-335081Y-204036D01*
X-335581Y-204370D01*
X-336081Y-204453D01*
G01X-331981Y-206120D02*
Y-201120D01*
G01Y-201870D02*
X-331564Y-201453D01*
X-331148Y-201203D01*
X-330481Y-201120D01*
X-329898Y-201203D01*
X-329314Y-201620D01*
X-329064Y-202203D01*
X-328981Y-202786D01*
X-329064Y-203370D01*
X-329314Y-203953D01*
X-329814Y-204286D01*
X-330481Y-204453D01*
X-331064Y-204370D01*
X-331648Y-204120D01*
X-331981Y-203786D01*
G01X-320531Y-203870D02*
X-320114Y-204203D01*
X-319531Y-204453D01*
X-319031D01*
X-318531Y-204286D01*
X-318198Y-204036D01*
X-318031Y-203703D01*
X-318114Y-203203D01*
X-318448Y-202953D01*
X-319948Y-202453D01*
X-320281Y-201870D01*
X-320114Y-201453D01*
X-319781Y-201203D01*
X-319281Y-201120D01*
X-318781Y-201203D01*
X-318281Y-201453D01*
G01X-313681Y-201120D02*
Y-204453D01*
G01Y-199786D02*
X-313848Y-199703D01*
Y-199536D01*
X-313681Y-199453D01*
X-313514Y-199536D01*
Y-199703D01*
X-313681Y-199786D01*
G01X-309331Y-201120D02*
X-306831D01*
X-309331Y-204453D01*
X-306831D01*
G01X-303731Y-202203D02*
X-301064D01*
X-301314Y-201620D01*
X-301731Y-201286D01*
X-302314Y-201120D01*
X-302898Y-201203D01*
X-303398Y-201453D01*
X-303731Y-202036D01*
X-303898Y-202536D01*
Y-203036D01*
X-303731Y-203536D01*
X-303314Y-204036D01*
X-302814Y-204370D01*
X-302231Y-204453D01*
X-301648Y-204286D01*
X-301064Y-203786D01*
G01X-291281Y-204453D02*
X-291781Y-204370D01*
X-292281Y-204036D01*
X-292614Y-203453D01*
X-292781Y-202786D01*
X-292614Y-202120D01*
X-292281Y-201536D01*
X-291781Y-201203D01*
X-291281Y-201120D01*
X-290781Y-201203D01*
X-290281Y-201536D01*
X-289948Y-202120D01*
X-289864Y-202786D01*
X-289948Y-203453D01*
X-290281Y-204036D01*
X-290781Y-204370D01*
X-291281Y-204453D01*
G01X-286181D02*
Y-200203D01*
X-286014Y-199786D01*
X-285681Y-199536D01*
X-285181Y-199453D01*
X-284681Y-199620D01*
X-284431Y-200036D01*
G01X-285431Y-201453D02*
X-287098D01*
G01X-276148Y-204453D02*
Y-199453D01*
X-274148D01*
X-273481Y-199703D01*
X-272981Y-200286D01*
X-272814Y-200953D01*
X-272981Y-201620D01*
X-273398Y-202120D01*
X-274148Y-202370D01*
X-276148D01*
G01X-270964Y-204453D02*
X-268881Y-199453D01*
X-266798Y-204453D01*
G01X-267548Y-202703D02*
X-270214D01*
G01X-265114Y-204453D02*
Y-199453D01*
X-263448D01*
X-262781Y-199703D01*
X-262281Y-200036D01*
X-261864Y-200536D01*
X-261531Y-201120D01*
X-261448Y-201953D01*
X-261531Y-202786D01*
X-261864Y-203370D01*
X-262281Y-203870D01*
X-262781Y-204203D01*
X-263448Y-204453D01*
X-265114D01*
G01X-253581Y-204620D02*
X-250581Y-199453D01*
G01X-392908Y-197293D02*
Y-192293D01*
X-390908D01*
X-390241Y-192543D01*
X-389741Y-193126D01*
X-389574Y-193793D01*
X-389741Y-194460D01*
X-390158Y-194960D01*
X-390908Y-195210D01*
X-392908D01*
G01X-387724Y-197293D02*
X-385641Y-192293D01*
X-383558Y-197293D01*
G01X-384308Y-195543D02*
X-386974D01*
G01X-381874Y-197293D02*
Y-192293D01*
X-380208D01*
X-379541Y-192543D01*
X-379041Y-192876D01*
X-378624Y-193376D01*
X-378291Y-193960D01*
X-378208Y-194793D01*
X-378291Y-195626D01*
X-378624Y-196210D01*
X-379041Y-196710D01*
X-379541Y-197043D01*
X-380208Y-197293D01*
X-381874D01*
G01X-370091Y-196710D02*
X-369674Y-197043D01*
X-369091Y-197293D01*
X-368591D01*
X-368091Y-197126D01*
X-367758Y-196876D01*
X-367591Y-196543D01*
X-367674Y-196043D01*
X-368008Y-195793D01*
X-369508Y-195293D01*
X-369841Y-194710D01*
X-369674Y-194293D01*
X-369341Y-194043D01*
X-368841Y-193960D01*
X-368341Y-194043D01*
X-367841Y-194293D01*
G01X-363241Y-193960D02*
Y-197293D01*
G01Y-192626D02*
X-363408Y-192543D01*
Y-192376D01*
X-363241Y-192293D01*
X-363074Y-192376D01*
Y-192543D01*
X-363241Y-192626D01*
G01X-358891Y-193960D02*
X-356391D01*
X-358891Y-197293D01*
X-356391D01*
G01X-353291Y-195043D02*
X-350624D01*
X-350874Y-194460D01*
X-351291Y-194126D01*
X-351874Y-193960D01*
X-352458Y-194043D01*
X-352958Y-194293D01*
X-353291Y-194876D01*
X-353458Y-195376D01*
Y-195876D01*
X-353291Y-196376D01*
X-352874Y-196876D01*
X-352374Y-197210D01*
X-351791Y-197293D01*
X-351208Y-197126D01*
X-350624Y-196626D01*
G01X-391241Y-163793D02*
Y-168793D01*
G01X-393158Y-163793D02*
X-389324D01*
G01X-386808Y-168793D02*
Y-165460D01*
G01Y-166126D02*
X-386391Y-165793D01*
X-385974Y-165543D01*
X-385391Y-165460D01*
X-384974Y-165543D01*
X-384474Y-165793D01*
G01X-378541Y-168793D02*
Y-165460D01*
G01Y-166043D02*
X-378874Y-165710D01*
X-379374Y-165543D01*
X-379958Y-165460D01*
X-380541Y-165626D01*
X-381041Y-165960D01*
X-381374Y-166460D01*
X-381541Y-167126D01*
X-381374Y-167793D01*
X-381041Y-168293D01*
X-380541Y-168626D01*
X-379958Y-168793D01*
X-379374Y-168710D01*
X-378874Y-168460D01*
X-378541Y-168126D01*
G01X-373108Y-165876D02*
X-373691Y-165543D01*
X-374191Y-165460D01*
X-374858Y-165626D01*
X-375358Y-165960D01*
X-375691Y-166543D01*
X-375774Y-167126D01*
X-375691Y-167710D01*
X-375358Y-168210D01*
X-374858Y-168626D01*
X-374191Y-168793D01*
X-373608Y-168626D01*
X-373108Y-168293D01*
G01X-370091Y-166543D02*
X-367424D01*
X-367674Y-165960D01*
X-368091Y-165626D01*
X-368674Y-165460D01*
X-369258Y-165543D01*
X-369758Y-165793D01*
X-370091Y-166376D01*
X-370258Y-166876D01*
Y-167376D01*
X-370091Y-167876D01*
X-369674Y-168376D01*
X-369174Y-168710D01*
X-368591Y-168793D01*
X-368008Y-168626D01*
X-367424Y-168126D01*
G01X-359724Y-165460D02*
X-358724Y-168793D01*
X-357641Y-165460D01*
X-356558Y-168793D01*
X-355558Y-165460D01*
G01X-352041D02*
Y-168793D01*
G01Y-164126D02*
X-352208Y-164043D01*
Y-163876D01*
X-352041Y-163793D01*
X-351874Y-163876D01*
Y-164043D01*
X-352041Y-164126D01*
G01X-344941Y-163793D02*
Y-168793D01*
G01Y-168043D02*
X-345274Y-168460D01*
X-345774Y-168710D01*
X-346358Y-168793D01*
X-347024Y-168626D01*
X-347524Y-168210D01*
X-347858Y-167710D01*
X-347941Y-167126D01*
X-347858Y-166543D01*
X-347524Y-166043D01*
X-347024Y-165626D01*
X-346358Y-165460D01*
X-345774Y-165543D01*
X-345358Y-165710D01*
X-344941Y-166043D01*
G01X-340841Y-163793D02*
Y-168793D01*
G01X-342008Y-165460D02*
X-339674D01*
G01X-336658Y-168793D02*
Y-163793D01*
G01Y-166210D02*
X-336241Y-165793D01*
X-335824Y-165543D01*
X-335158Y-165460D01*
X-334658Y-165543D01*
X-334074Y-165876D01*
X-333824Y-166376D01*
Y-168793D01*
G01X-401741Y-188293D02*
X189259D01*
G01X-392908Y-137293D02*
Y-132293D01*
X-390824D01*
X-390158Y-132543D01*
X-389741Y-132876D01*
X-389574Y-133543D01*
X-389741Y-134210D01*
X-390241Y-134626D01*
X-390824Y-134876D01*
X-392908D01*
G01X-390824D02*
X-389574Y-137293D01*
G01X-386891Y-135043D02*
X-384224D01*
X-384474Y-134460D01*
X-384891Y-134126D01*
X-385474Y-133960D01*
X-386058Y-134043D01*
X-386558Y-134293D01*
X-386891Y-134876D01*
X-387058Y-135376D01*
Y-135876D01*
X-386891Y-136376D01*
X-386474Y-136876D01*
X-385974Y-137210D01*
X-385391Y-137293D01*
X-384808Y-137126D01*
X-384224Y-136626D01*
G01X-380041Y-137293D02*
Y-132293D01*
G01X-372941Y-137293D02*
Y-133960D01*
G01Y-134543D02*
X-373274Y-134210D01*
X-373774Y-134043D01*
X-374358Y-133960D01*
X-374941Y-134126D01*
X-375441Y-134460D01*
X-375774Y-134960D01*
X-375941Y-135626D01*
X-375774Y-136293D01*
X-375441Y-136793D01*
X-374941Y-137126D01*
X-374358Y-137293D01*
X-373774Y-137210D01*
X-373274Y-136960D01*
X-372941Y-136626D01*
G01X-368841Y-132293D02*
Y-137293D01*
G01X-370008Y-133960D02*
X-367674D01*
G01X-363241D02*
Y-137293D01*
G01Y-132626D02*
X-363408Y-132543D01*
Y-132376D01*
X-363241Y-132293D01*
X-363074Y-132376D01*
Y-132543D01*
X-363241Y-132626D01*
G01X-359141Y-133960D02*
X-357641Y-137293D01*
X-356141Y-133960D01*
G01X-353291Y-135043D02*
X-350624D01*
X-350874Y-134460D01*
X-351291Y-134126D01*
X-351874Y-133960D01*
X-352458Y-134043D01*
X-352958Y-134293D01*
X-353291Y-134876D01*
X-353458Y-135376D01*
Y-135876D01*
X-353291Y-136376D01*
X-352874Y-136876D01*
X-352374Y-137210D01*
X-351791Y-137293D01*
X-351208Y-137126D01*
X-350624Y-136626D01*
G01X-342341Y-138960D02*
Y-133960D01*
G01Y-134710D02*
X-341924Y-134293D01*
X-341508Y-134043D01*
X-340841Y-133960D01*
X-340258Y-134043D01*
X-339674Y-134460D01*
X-339424Y-135043D01*
X-339341Y-135626D01*
X-339424Y-136210D01*
X-339674Y-136793D01*
X-340174Y-137126D01*
X-340841Y-137293D01*
X-341424Y-137210D01*
X-342008Y-136960D01*
X-342341Y-136626D01*
G01X-335241Y-137293D02*
X-335741Y-137210D01*
X-336241Y-136876D01*
X-336574Y-136293D01*
X-336741Y-135626D01*
X-336574Y-134960D01*
X-336241Y-134376D01*
X-335741Y-134043D01*
X-335241Y-133960D01*
X-334741Y-134043D01*
X-334241Y-134376D01*
X-333908Y-134960D01*
X-333824Y-135626D01*
X-333908Y-136293D01*
X-334241Y-136876D01*
X-334741Y-137210D01*
X-335241Y-137293D01*
G01X-330891Y-136710D02*
X-330474Y-137043D01*
X-329891Y-137293D01*
X-329391D01*
X-328891Y-137126D01*
X-328558Y-136876D01*
X-328391Y-136543D01*
X-328474Y-136043D01*
X-328808Y-135793D01*
X-330308Y-135293D01*
X-330641Y-134710D01*
X-330474Y-134293D01*
X-330141Y-134043D01*
X-329641Y-133960D01*
X-329141Y-134043D01*
X-328641Y-134293D01*
G01X-324041Y-133960D02*
Y-137293D01*
G01Y-132626D02*
X-324208Y-132543D01*
Y-132376D01*
X-324041Y-132293D01*
X-323874Y-132376D01*
Y-132543D01*
X-324041Y-132626D01*
G01X-318441Y-132293D02*
Y-137293D01*
G01X-319608Y-133960D02*
X-317274D01*
G01X-312841D02*
Y-137293D01*
G01Y-132626D02*
X-313008Y-132543D01*
Y-132376D01*
X-312841Y-132293D01*
X-312674Y-132376D01*
Y-132543D01*
X-312841Y-132626D01*
G01X-307241Y-137293D02*
X-307741Y-137210D01*
X-308241Y-136876D01*
X-308574Y-136293D01*
X-308741Y-135626D01*
X-308574Y-134960D01*
X-308241Y-134376D01*
X-307741Y-134043D01*
X-307241Y-133960D01*
X-306741Y-134043D01*
X-306241Y-134376D01*
X-305908Y-134960D01*
X-305824Y-135626D01*
X-305908Y-136293D01*
X-306241Y-136876D01*
X-306741Y-137210D01*
X-307241Y-137293D01*
G01X-303058D02*
Y-133960D01*
G01Y-134793D02*
X-302724Y-134376D01*
X-302224Y-134043D01*
X-301558Y-133960D01*
X-300974Y-134043D01*
X-300474Y-134376D01*
X-300224Y-134960D01*
Y-137293D01*
G01X-391241Y-105293D02*
Y-110293D01*
G01X-392408Y-106960D02*
X-390074D01*
G01X-387058Y-110293D02*
Y-105293D01*
G01Y-107710D02*
X-386641Y-107293D01*
X-386224Y-107043D01*
X-385558Y-106960D01*
X-385058Y-107043D01*
X-384474Y-107376D01*
X-384224Y-107876D01*
Y-110293D01*
G01X-380041Y-106960D02*
Y-110293D01*
G01Y-105626D02*
X-380208Y-105543D01*
Y-105376D01*
X-380041Y-105293D01*
X-379874Y-105376D01*
Y-105543D01*
X-380041Y-105626D01*
G01X-373108Y-107376D02*
X-373691Y-107043D01*
X-374191Y-106960D01*
X-374858Y-107126D01*
X-375358Y-107460D01*
X-375691Y-108043D01*
X-375774Y-108626D01*
X-375691Y-109210D01*
X-375358Y-109710D01*
X-374858Y-110126D01*
X-374191Y-110293D01*
X-373608Y-110126D01*
X-373108Y-109793D01*
G01X-370258Y-110293D02*
Y-105293D01*
G01X-367591Y-106960D02*
X-370258Y-108876D01*
G01X-369174Y-108126D02*
X-367424Y-110293D01*
G01X-364658D02*
Y-106960D01*
G01Y-107793D02*
X-364324Y-107376D01*
X-363824Y-107043D01*
X-363158Y-106960D01*
X-362574Y-107043D01*
X-362074Y-107376D01*
X-361824Y-107960D01*
Y-110293D01*
G01X-358891Y-108043D02*
X-356224D01*
X-356474Y-107460D01*
X-356891Y-107126D01*
X-357474Y-106960D01*
X-358058Y-107043D01*
X-358558Y-107293D01*
X-358891Y-107876D01*
X-359058Y-108376D01*
Y-108876D01*
X-358891Y-109376D01*
X-358474Y-109876D01*
X-357974Y-110210D01*
X-357391Y-110293D01*
X-356808Y-110126D01*
X-356224Y-109626D01*
G01X-353291Y-109710D02*
X-352874Y-110043D01*
X-352291Y-110293D01*
X-351791D01*
X-351291Y-110126D01*
X-350958Y-109876D01*
X-350791Y-109543D01*
X-350874Y-109043D01*
X-351208Y-108793D01*
X-352708Y-108293D01*
X-353041Y-107710D01*
X-352874Y-107293D01*
X-352541Y-107043D01*
X-352041Y-106960D01*
X-351541Y-107043D01*
X-351041Y-107293D01*
G01X-347691Y-109710D02*
X-347274Y-110043D01*
X-346691Y-110293D01*
X-346191D01*
X-345691Y-110126D01*
X-345358Y-109876D01*
X-345191Y-109543D01*
X-345274Y-109043D01*
X-345608Y-108793D01*
X-347108Y-108293D01*
X-347441Y-107710D01*
X-347274Y-107293D01*
X-346941Y-107043D01*
X-346441Y-106960D01*
X-345941Y-107043D01*
X-345441Y-107293D01*
G01X-333741Y-110293D02*
Y-106960D01*
G01Y-107543D02*
X-334074Y-107210D01*
X-334574Y-107043D01*
X-335158Y-106960D01*
X-335741Y-107126D01*
X-336241Y-107460D01*
X-336574Y-107960D01*
X-336741Y-108626D01*
X-336574Y-109293D01*
X-336241Y-109793D01*
X-335741Y-110126D01*
X-335158Y-110293D01*
X-334574Y-110210D01*
X-334074Y-109960D01*
X-333741Y-109626D01*
G01X-330141Y-110293D02*
Y-106043D01*
X-329974Y-105626D01*
X-329641Y-105376D01*
X-329141Y-105293D01*
X-328641Y-105460D01*
X-328391Y-105876D01*
G01X-329391Y-107293D02*
X-331058D01*
G01X-324041Y-105293D02*
Y-110293D01*
G01X-325208Y-106960D02*
X-322874D01*
G01X-319691Y-108043D02*
X-317024D01*
X-317274Y-107460D01*
X-317691Y-107126D01*
X-318274Y-106960D01*
X-318858Y-107043D01*
X-319358Y-107293D01*
X-319691Y-107876D01*
X-319858Y-108376D01*
Y-108876D01*
X-319691Y-109376D01*
X-319274Y-109876D01*
X-318774Y-110210D01*
X-318191Y-110293D01*
X-317608Y-110126D01*
X-317024Y-109626D01*
G01X-314008Y-110293D02*
Y-106960D01*
G01Y-107626D02*
X-313591Y-107293D01*
X-313174Y-107043D01*
X-312591Y-106960D01*
X-312174Y-107043D01*
X-311674Y-107293D01*
G01X-303141Y-111960D02*
Y-106960D01*
G01Y-107710D02*
X-302724Y-107293D01*
X-302308Y-107043D01*
X-301641Y-106960D01*
X-301058Y-107043D01*
X-300474Y-107460D01*
X-300224Y-108043D01*
X-300141Y-108626D01*
X-300224Y-109210D01*
X-300474Y-109793D01*
X-300974Y-110126D01*
X-301641Y-110293D01*
X-302224Y-110210D01*
X-302808Y-109960D01*
X-303141Y-109626D01*
G01X-296041Y-110293D02*
Y-105293D01*
G01X-288941Y-110293D02*
Y-106960D01*
G01Y-107543D02*
X-289274Y-107210D01*
X-289774Y-107043D01*
X-290358Y-106960D01*
X-290941Y-107126D01*
X-291441Y-107460D01*
X-291774Y-107960D01*
X-291941Y-108626D01*
X-291774Y-109293D01*
X-291441Y-109793D01*
X-290941Y-110126D01*
X-290358Y-110293D01*
X-289774Y-110210D01*
X-289274Y-109960D01*
X-288941Y-109626D01*
G01X-284841Y-105293D02*
Y-110293D01*
G01X-286008Y-106960D02*
X-283674D01*
G01X-279241D02*
Y-110293D01*
G01Y-105626D02*
X-279408Y-105543D01*
Y-105376D01*
X-279241Y-105293D01*
X-279074Y-105376D01*
Y-105543D01*
X-279241Y-105626D01*
G01X-275058Y-110293D02*
Y-106960D01*
G01Y-107793D02*
X-274724Y-107376D01*
X-274224Y-107043D01*
X-273558Y-106960D01*
X-272974Y-107043D01*
X-272474Y-107376D01*
X-272224Y-107960D01*
Y-110293D01*
G01X-269208Y-111543D02*
X-268624Y-111876D01*
X-267958Y-111960D01*
X-267374Y-111876D01*
X-266874Y-111460D01*
X-266541Y-110876D01*
Y-106960D01*
G01Y-107626D02*
X-266874Y-107293D01*
X-267374Y-107043D01*
X-267958Y-106960D01*
X-268624Y-107126D01*
X-269041Y-107460D01*
X-269374Y-108043D01*
X-269541Y-108626D01*
X-269458Y-109126D01*
X-269124Y-109710D01*
X-268624Y-110126D01*
X-267958Y-110293D01*
X-267458Y-110210D01*
X-266874Y-109876D01*
X-266541Y-109543D01*
G01X-389574Y-100293D02*
X-392908D01*
Y-95293D01*
X-389574D01*
G01X-390908Y-97710D02*
X-392908D01*
G01X-386891Y-96960D02*
X-384391Y-100293D01*
G01Y-96960D02*
X-386891Y-100293D01*
G01X-380041Y-95293D02*
Y-100293D01*
G01X-381208Y-96960D02*
X-378874D01*
G01X-375691Y-98043D02*
X-373024D01*
X-373274Y-97460D01*
X-373691Y-97126D01*
X-374274Y-96960D01*
X-374858Y-97043D01*
X-375358Y-97293D01*
X-375691Y-97876D01*
X-375858Y-98376D01*
Y-98876D01*
X-375691Y-99376D01*
X-375274Y-99876D01*
X-374774Y-100210D01*
X-374191Y-100293D01*
X-373608Y-100126D01*
X-373024Y-99626D01*
G01X-370008Y-100293D02*
Y-96960D01*
G01Y-97626D02*
X-369591Y-97293D01*
X-369174Y-97043D01*
X-368591Y-96960D01*
X-368174Y-97043D01*
X-367674Y-97293D01*
G01X-364658Y-100293D02*
Y-96960D01*
G01Y-97793D02*
X-364324Y-97376D01*
X-363824Y-97043D01*
X-363158Y-96960D01*
X-362574Y-97043D01*
X-362074Y-97376D01*
X-361824Y-97960D01*
Y-100293D01*
G01X-356141D02*
Y-96960D01*
G01Y-97543D02*
X-356474Y-97210D01*
X-356974Y-97043D01*
X-357558Y-96960D01*
X-358141Y-97126D01*
X-358641Y-97460D01*
X-358974Y-97960D01*
X-359141Y-98626D01*
X-358974Y-99293D01*
X-358641Y-99793D01*
X-358141Y-100126D01*
X-357558Y-100293D01*
X-356974Y-100210D01*
X-356474Y-99960D01*
X-356141Y-99626D01*
G01X-352041Y-100293D02*
Y-95293D01*
G01X-339508Y-97376D02*
X-340091Y-97043D01*
X-340591Y-96960D01*
X-341258Y-97126D01*
X-341758Y-97460D01*
X-342091Y-98043D01*
X-342174Y-98626D01*
X-342091Y-99210D01*
X-341758Y-99710D01*
X-341258Y-100126D01*
X-340591Y-100293D01*
X-340008Y-100126D01*
X-339508Y-99793D01*
G01X-335241Y-100293D02*
X-335741Y-100210D01*
X-336241Y-99876D01*
X-336574Y-99293D01*
X-336741Y-98626D01*
X-336574Y-97960D01*
X-336241Y-97376D01*
X-335741Y-97043D01*
X-335241Y-96960D01*
X-334741Y-97043D01*
X-334241Y-97376D01*
X-333908Y-97960D01*
X-333824Y-98626D01*
X-333908Y-99293D01*
X-334241Y-99876D01*
X-334741Y-100210D01*
X-335241Y-100293D01*
G01X-331058D02*
Y-96960D01*
G01Y-97793D02*
X-330724Y-97376D01*
X-330224Y-97043D01*
X-329558Y-96960D01*
X-328974Y-97043D01*
X-328474Y-97376D01*
X-328224Y-97960D01*
Y-100293D01*
G01X-322541Y-95293D02*
Y-100293D01*
G01Y-99543D02*
X-322874Y-99960D01*
X-323374Y-100210D01*
X-323958Y-100293D01*
X-324624Y-100126D01*
X-325124Y-99710D01*
X-325458Y-99210D01*
X-325541Y-98626D01*
X-325458Y-98043D01*
X-325124Y-97543D01*
X-324624Y-97126D01*
X-323958Y-96960D01*
X-323374Y-97043D01*
X-322958Y-97210D01*
X-322541Y-97543D01*
G01X-319858Y-96960D02*
Y-99293D01*
X-319524Y-99876D01*
X-319024Y-100210D01*
X-318441Y-100293D01*
X-317858Y-100210D01*
X-317358Y-99876D01*
X-317024Y-99293D01*
G01Y-100293D02*
Y-96960D01*
G01X-311508Y-97376D02*
X-312091Y-97043D01*
X-312591Y-96960D01*
X-313258Y-97126D01*
X-313758Y-97460D01*
X-314091Y-98043D01*
X-314174Y-98626D01*
X-314091Y-99210D01*
X-313758Y-99710D01*
X-313258Y-100126D01*
X-312591Y-100293D01*
X-312008Y-100126D01*
X-311508Y-99793D01*
G01X-307241Y-95293D02*
Y-100293D01*
G01X-308408Y-96960D02*
X-306074D01*
G01X-301641Y-100293D02*
X-302141Y-100210D01*
X-302641Y-99876D01*
X-302974Y-99293D01*
X-303141Y-98626D01*
X-302974Y-97960D01*
X-302641Y-97376D01*
X-302141Y-97043D01*
X-301641Y-96960D01*
X-301141Y-97043D01*
X-300641Y-97376D01*
X-300308Y-97960D01*
X-300224Y-98626D01*
X-300308Y-99293D01*
X-300641Y-99876D01*
X-301141Y-100210D01*
X-301641Y-100293D01*
G01X-297208D02*
Y-96960D01*
G01Y-97626D02*
X-296791Y-97293D01*
X-296374Y-97043D01*
X-295791Y-96960D01*
X-295374Y-97043D01*
X-294874Y-97293D01*
G01X-392908Y107707D02*
Y102707D01*
X-389574D01*
G01X-384141D02*
Y106040D01*
G01Y105457D02*
X-384474Y105790D01*
X-384974Y105957D01*
X-385558Y106040D01*
X-386141Y105874D01*
X-386641Y105540D01*
X-386974Y105040D01*
X-387141Y104374D01*
X-386974Y103707D01*
X-386641Y103207D01*
X-386141Y102874D01*
X-385558Y102707D01*
X-384974Y102790D01*
X-384474Y103040D01*
X-384141Y103374D01*
G01X-381291Y103290D02*
X-380874Y102957D01*
X-380291Y102707D01*
X-379791D01*
X-379291Y102874D01*
X-378958Y103124D01*
X-378791Y103457D01*
X-378874Y103957D01*
X-379208Y104207D01*
X-380708Y104707D01*
X-381041Y105290D01*
X-380874Y105707D01*
X-380541Y105957D01*
X-380041Y106040D01*
X-379541Y105957D01*
X-379041Y105707D01*
G01X-375691Y104957D02*
X-373024D01*
X-373274Y105540D01*
X-373691Y105874D01*
X-374274Y106040D01*
X-374858Y105957D01*
X-375358Y105707D01*
X-375691Y105124D01*
X-375858Y104624D01*
Y104124D01*
X-375691Y103624D01*
X-375274Y103124D01*
X-374774Y102790D01*
X-374191Y102707D01*
X-373608Y102874D01*
X-373024Y103374D01*
G01X-370008Y102707D02*
Y106040D01*
G01Y105374D02*
X-369591Y105707D01*
X-369174Y105957D01*
X-368591Y106040D01*
X-368174Y105957D01*
X-367674Y105707D01*
G01X-359141Y106040D02*
X-357641Y102707D01*
X-356141Y106040D01*
G01X-352041D02*
Y102707D01*
G01Y107374D02*
X-352208Y107457D01*
Y107624D01*
X-352041Y107707D01*
X-351874Y107624D01*
Y107457D01*
X-352041Y107374D01*
G01X-344941Y102707D02*
Y106040D01*
G01Y105457D02*
X-345274Y105790D01*
X-345774Y105957D01*
X-346358Y106040D01*
X-346941Y105874D01*
X-347441Y105540D01*
X-347774Y105040D01*
X-347941Y104374D01*
X-347774Y103707D01*
X-347441Y103207D01*
X-346941Y102874D01*
X-346358Y102707D01*
X-345774Y102790D01*
X-345274Y103040D01*
X-344941Y103374D01*
G01X-337074Y102540D02*
X-333408Y106207D01*
G01X-335241Y106874D02*
Y101874D01*
G01X-333408Y102540D02*
X-337074Y106207D01*
G01X-337741Y104374D02*
X-332741D01*
G01X-330058Y101040D02*
X-330891Y101874D01*
X-331308Y102707D01*
Y106040D01*
X-330891Y106874D01*
X-330058Y107707D01*
G01X-325874Y103457D02*
X-325374Y103040D01*
X-324791Y102790D01*
X-324041Y102707D01*
X-323291Y102874D01*
X-322708Y103207D01*
X-322291Y103790D01*
X-322208Y104457D01*
X-322374Y105124D01*
X-322791Y105540D01*
X-323374Y105874D01*
X-323958Y105957D01*
X-324541Y105874D01*
X-325291Y105540D01*
X-325041Y107707D01*
X-322791D01*
G01X-318441Y102540D02*
X-318608Y102624D01*
Y102790D01*
X-318441Y102874D01*
X-318274Y102790D01*
Y102624D01*
X-318441Y102540D01*
G01X-312841Y102707D02*
Y107707D01*
X-313841Y106707D01*
G01Y102707D02*
X-311841D01*
G01X-306824Y101040D02*
X-305991Y101874D01*
X-305574Y102707D01*
Y106040D01*
X-305991Y106874D01*
X-306824Y107707D01*
G01X-400241Y115707D02*
X189259D01*
G01X-392908Y157707D02*
Y162707D01*
X-390908D01*
X-390241Y162457D01*
X-389741Y161874D01*
X-389574Y161207D01*
X-389741Y160540D01*
X-390158Y160040D01*
X-390908Y159790D01*
X-392908D01*
G01X-385641Y162707D02*
Y157707D01*
G01X-387558Y162707D02*
X-383724D01*
G01X-381791Y157707D02*
Y162707D01*
G01X-378291D02*
Y157707D01*
G01Y160207D02*
X-381791D01*
G01X-370008Y157707D02*
Y161040D01*
G01Y160374D02*
X-369591Y160707D01*
X-369174Y160957D01*
X-368591Y161040D01*
X-368174Y160957D01*
X-367674Y160707D01*
G01X-364491Y159957D02*
X-361824D01*
X-362074Y160540D01*
X-362491Y160874D01*
X-363074Y161040D01*
X-363658Y160957D01*
X-364158Y160707D01*
X-364491Y160124D01*
X-364658Y159624D01*
Y159124D01*
X-364491Y158624D01*
X-364074Y158124D01*
X-363574Y157790D01*
X-362991Y157707D01*
X-362408Y157874D01*
X-361824Y158374D01*
G01X-358808Y156457D02*
X-358224Y156124D01*
X-357558Y156040D01*
X-356974Y156124D01*
X-356474Y156540D01*
X-356141Y157124D01*
Y161040D01*
G01Y160374D02*
X-356474Y160707D01*
X-356974Y160957D01*
X-357558Y161040D01*
X-358224Y160874D01*
X-358641Y160540D01*
X-358974Y159957D01*
X-359141Y159374D01*
X-359058Y158874D01*
X-358724Y158290D01*
X-358224Y157874D01*
X-357558Y157707D01*
X-357058Y157790D01*
X-356474Y158124D01*
X-356141Y158457D01*
G01X-352041Y161040D02*
Y157707D01*
G01Y162374D02*
X-352208Y162457D01*
Y162624D01*
X-352041Y162707D01*
X-351874Y162624D01*
Y162457D01*
X-352041Y162374D01*
G01X-347691Y158290D02*
X-347274Y157957D01*
X-346691Y157707D01*
X-346191D01*
X-345691Y157874D01*
X-345358Y158124D01*
X-345191Y158457D01*
X-345274Y158957D01*
X-345608Y159207D01*
X-347108Y159707D01*
X-347441Y160290D01*
X-347274Y160707D01*
X-346941Y160957D01*
X-346441Y161040D01*
X-345941Y160957D01*
X-345441Y160707D01*
G01X-340841Y162707D02*
Y157707D01*
G01X-342008Y161040D02*
X-339674D01*
G01X-336408Y157707D02*
Y161040D01*
G01Y160374D02*
X-335991Y160707D01*
X-335574Y160957D01*
X-334991Y161040D01*
X-334574Y160957D01*
X-334074Y160707D01*
G01X-328141Y157707D02*
Y161040D01*
G01Y160457D02*
X-328474Y160790D01*
X-328974Y160957D01*
X-329558Y161040D01*
X-330141Y160874D01*
X-330641Y160540D01*
X-330974Y160040D01*
X-331141Y159374D01*
X-330974Y158707D01*
X-330641Y158207D01*
X-330141Y157874D01*
X-329558Y157707D01*
X-328974Y157790D01*
X-328474Y158040D01*
X-328141Y158374D01*
G01X-324041Y162707D02*
Y157707D01*
G01X-325208Y161040D02*
X-322874D01*
G01X-318441D02*
Y157707D01*
G01Y162374D02*
X-318608Y162457D01*
Y162624D01*
X-318441Y162707D01*
X-318274Y162624D01*
Y162457D01*
X-318441Y162374D01*
G01X-312841Y157707D02*
X-313341Y157790D01*
X-313841Y158124D01*
X-314174Y158707D01*
X-314341Y159374D01*
X-314174Y160040D01*
X-313841Y160624D01*
X-313341Y160957D01*
X-312841Y161040D01*
X-312341Y160957D01*
X-311841Y160624D01*
X-311508Y160040D01*
X-311424Y159374D01*
X-311508Y158707D01*
X-311841Y158124D01*
X-312341Y157790D01*
X-312841Y157707D01*
G01X-308658D02*
Y161040D01*
G01Y160207D02*
X-308324Y160624D01*
X-307824Y160957D01*
X-307158Y161040D01*
X-306574Y160957D01*
X-306074Y160624D01*
X-305824Y160040D01*
Y157707D01*
G01X-393074Y184207D02*
Y189207D01*
X-391408D01*
X-390741Y188957D01*
X-390241Y188624D01*
X-389824Y188124D01*
X-389491Y187540D01*
X-389408Y186707D01*
X-389491Y185874D01*
X-389824Y185290D01*
X-390241Y184790D01*
X-390741Y184457D01*
X-391408Y184207D01*
X-393074D01*
G01X-386891Y186457D02*
X-384224D01*
X-384474Y187040D01*
X-384891Y187374D01*
X-385474Y187540D01*
X-386058Y187457D01*
X-386558Y187207D01*
X-386891Y186624D01*
X-387058Y186124D01*
Y185624D01*
X-386891Y185124D01*
X-386474Y184624D01*
X-385974Y184290D01*
X-385391Y184207D01*
X-384808Y184374D01*
X-384224Y184874D01*
G01X-381541Y182540D02*
Y187540D01*
G01Y186790D02*
X-381124Y187207D01*
X-380708Y187457D01*
X-380041Y187540D01*
X-379458Y187457D01*
X-378874Y187040D01*
X-378624Y186457D01*
X-378541Y185874D01*
X-378624Y185290D01*
X-378874Y184707D01*
X-379374Y184374D01*
X-380041Y184207D01*
X-380624Y184290D01*
X-381208Y184540D01*
X-381541Y184874D01*
G01X-374441Y189207D02*
Y184207D01*
G01X-375608Y187540D02*
X-373274D01*
G01X-370258Y184207D02*
Y189207D01*
G01Y186790D02*
X-369841Y187207D01*
X-369424Y187457D01*
X-368758Y187540D01*
X-368258Y187457D01*
X-367674Y187124D01*
X-367424Y186624D01*
Y184207D01*
G01X-356308Y187124D02*
X-356891Y187457D01*
X-357391Y187540D01*
X-358058Y187374D01*
X-358558Y187040D01*
X-358891Y186457D01*
X-358974Y185874D01*
X-358891Y185290D01*
X-358558Y184790D01*
X-358058Y184374D01*
X-357391Y184207D01*
X-356808Y184374D01*
X-356308Y184707D01*
G01X-352041Y184207D02*
X-352541Y184290D01*
X-353041Y184624D01*
X-353374Y185207D01*
X-353541Y185874D01*
X-353374Y186540D01*
X-353041Y187124D01*
X-352541Y187457D01*
X-352041Y187540D01*
X-351541Y187457D01*
X-351041Y187124D01*
X-350708Y186540D01*
X-350624Y185874D01*
X-350708Y185207D01*
X-351041Y184624D01*
X-351541Y184290D01*
X-352041Y184207D01*
G01X-347858D02*
Y187540D01*
G01Y186707D02*
X-347524Y187124D01*
X-347024Y187457D01*
X-346358Y187540D01*
X-345774Y187457D01*
X-345274Y187124D01*
X-345024Y186540D01*
Y184207D01*
G01X-340841Y189207D02*
Y184207D01*
G01X-342008Y187540D02*
X-339674D01*
G01X-336408Y184207D02*
Y187540D01*
G01Y186874D02*
X-335991Y187207D01*
X-335574Y187457D01*
X-334991Y187540D01*
X-334574Y187457D01*
X-334074Y187207D01*
G01X-329641Y184207D02*
X-330141Y184290D01*
X-330641Y184624D01*
X-330974Y185207D01*
X-331141Y185874D01*
X-330974Y186540D01*
X-330641Y187124D01*
X-330141Y187457D01*
X-329641Y187540D01*
X-329141Y187457D01*
X-328641Y187124D01*
X-328308Y186540D01*
X-328224Y185874D01*
X-328308Y185207D01*
X-328641Y184624D01*
X-329141Y184290D01*
X-329641Y184207D01*
G01X-324041D02*
Y189207D01*
G01X-314258Y184207D02*
Y189207D01*
G01Y186790D02*
X-313841Y187207D01*
X-313424Y187457D01*
X-312758Y187540D01*
X-312258Y187457D01*
X-311674Y187124D01*
X-311424Y186624D01*
Y184207D01*
G01X-307241D02*
X-307741Y184290D01*
X-308241Y184624D01*
X-308574Y185207D01*
X-308741Y185874D01*
X-308574Y186540D01*
X-308241Y187124D01*
X-307741Y187457D01*
X-307241Y187540D01*
X-306741Y187457D01*
X-306241Y187124D01*
X-305908Y186540D01*
X-305824Y185874D01*
X-305908Y185207D01*
X-306241Y184624D01*
X-306741Y184290D01*
X-307241Y184207D01*
G01X-301641D02*
Y189207D01*
G01X-297291Y186457D02*
X-294624D01*
X-294874Y187040D01*
X-295291Y187374D01*
X-295874Y187540D01*
X-296458Y187457D01*
X-296958Y187207D01*
X-297291Y186624D01*
X-297458Y186124D01*
Y185624D01*
X-297291Y185124D01*
X-296874Y184624D01*
X-296374Y184290D01*
X-295791Y184207D01*
X-295208Y184374D01*
X-294624Y184874D01*
G01X-392908Y206207D02*
Y211207D01*
X-390824D01*
X-390158Y210957D01*
X-389741Y210624D01*
X-389574Y209957D01*
X-389741Y209290D01*
X-390241Y208874D01*
X-390824Y208624D01*
X-392908D01*
G01X-390824D02*
X-389574Y206207D01*
G01X-385641D02*
X-386141Y206290D01*
X-386641Y206624D01*
X-386974Y207207D01*
X-387141Y207874D01*
X-386974Y208540D01*
X-386641Y209124D01*
X-386141Y209457D01*
X-385641Y209540D01*
X-385141Y209457D01*
X-384641Y209124D01*
X-384308Y208540D01*
X-384224Y207874D01*
X-384308Y207207D01*
X-384641Y206624D01*
X-385141Y206290D01*
X-385641Y206207D01*
G01X-381458Y209540D02*
Y207207D01*
X-381124Y206624D01*
X-380624Y206290D01*
X-380041Y206207D01*
X-379458Y206290D01*
X-378958Y206624D01*
X-378624Y207207D01*
G01Y206207D02*
Y209540D01*
G01X-375608Y204957D02*
X-375024Y204624D01*
X-374358Y204540D01*
X-373774Y204624D01*
X-373274Y205040D01*
X-372941Y205624D01*
Y209540D01*
G01Y208874D02*
X-373274Y209207D01*
X-373774Y209457D01*
X-374358Y209540D01*
X-375024Y209374D01*
X-375441Y209040D01*
X-375774Y208457D01*
X-375941Y207874D01*
X-375858Y207374D01*
X-375524Y206790D01*
X-375024Y206374D01*
X-374358Y206207D01*
X-373858Y206290D01*
X-373274Y206624D01*
X-372941Y206957D01*
G01X-370258Y206207D02*
Y211207D01*
G01Y208790D02*
X-369841Y209207D01*
X-369424Y209457D01*
X-368758Y209540D01*
X-368258Y209457D01*
X-367674Y209124D01*
X-367424Y208624D01*
Y206207D01*
G01X-364658D02*
Y209540D01*
G01Y208707D02*
X-364324Y209124D01*
X-363824Y209457D01*
X-363158Y209540D01*
X-362574Y209457D01*
X-362074Y209124D01*
X-361824Y208540D01*
Y206207D01*
G01X-358891Y208457D02*
X-356224D01*
X-356474Y209040D01*
X-356891Y209374D01*
X-357474Y209540D01*
X-358058Y209457D01*
X-358558Y209207D01*
X-358891Y208624D01*
X-359058Y208124D01*
Y207624D01*
X-358891Y207124D01*
X-358474Y206624D01*
X-357974Y206290D01*
X-357391Y206207D01*
X-356808Y206374D01*
X-356224Y206874D01*
G01X-353291Y206790D02*
X-352874Y206457D01*
X-352291Y206207D01*
X-351791D01*
X-351291Y206374D01*
X-350958Y206624D01*
X-350791Y206957D01*
X-350874Y207457D01*
X-351208Y207707D01*
X-352708Y208207D01*
X-353041Y208790D01*
X-352874Y209207D01*
X-352541Y209457D01*
X-352041Y209540D01*
X-351541Y209457D01*
X-351041Y209207D01*
G01X-347691Y206790D02*
X-347274Y206457D01*
X-346691Y206207D01*
X-346191D01*
X-345691Y206374D01*
X-345358Y206624D01*
X-345191Y206957D01*
X-345274Y207457D01*
X-345608Y207707D01*
X-347108Y208207D01*
X-347441Y208790D01*
X-347274Y209207D01*
X-346941Y209457D01*
X-346441Y209540D01*
X-345941Y209457D01*
X-345441Y209207D01*
G01X-401741Y200207D02*
X189259D01*
G01X-401241Y215207D02*
X189259D01*
G01X-401741Y175207D02*
X189259D01*
G01X-392991Y264707D02*
Y269707D01*
G01X-389491D02*
Y264707D01*
G01Y267207D02*
X-392991D01*
G01X-385641Y264707D02*
X-386141Y264790D01*
X-386641Y265124D01*
X-386974Y265707D01*
X-387141Y266374D01*
X-386974Y267040D01*
X-386641Y267624D01*
X-386141Y267957D01*
X-385641Y268040D01*
X-385141Y267957D01*
X-384641Y267624D01*
X-384308Y267040D01*
X-384224Y266374D01*
X-384308Y265707D01*
X-384641Y265124D01*
X-385141Y264790D01*
X-385641Y264707D01*
G01X-380041D02*
Y269707D01*
G01X-375691Y266957D02*
X-373024D01*
X-373274Y267540D01*
X-373691Y267874D01*
X-374274Y268040D01*
X-374858Y267957D01*
X-375358Y267707D01*
X-375691Y267124D01*
X-375858Y266624D01*
Y266124D01*
X-375691Y265624D01*
X-375274Y265124D01*
X-374774Y264790D01*
X-374191Y264707D01*
X-373608Y264874D01*
X-373024Y265374D01*
G01X-364491Y265290D02*
X-364074Y264957D01*
X-363491Y264707D01*
X-362991D01*
X-362491Y264874D01*
X-362158Y265124D01*
X-361991Y265457D01*
X-362074Y265957D01*
X-362408Y266207D01*
X-363908Y266707D01*
X-364241Y267290D01*
X-364074Y267707D01*
X-363741Y267957D01*
X-363241Y268040D01*
X-362741Y267957D01*
X-362241Y267707D01*
G01X-357641Y268040D02*
Y264707D01*
G01Y269374D02*
X-357808Y269457D01*
Y269624D01*
X-357641Y269707D01*
X-357474Y269624D01*
Y269457D01*
X-357641Y269374D01*
G01X-353291Y268040D02*
X-350791D01*
X-353291Y264707D01*
X-350791D01*
G01X-347691Y266957D02*
X-345024D01*
X-345274Y267540D01*
X-345691Y267874D01*
X-346274Y268040D01*
X-346858Y267957D01*
X-347358Y267707D01*
X-347691Y267124D01*
X-347858Y266624D01*
Y266124D01*
X-347691Y265624D01*
X-347274Y265124D01*
X-346774Y264790D01*
X-346191Y264707D01*
X-345608Y264874D01*
X-345024Y265374D01*
G01X-393324Y361207D02*
X-391241Y356207D01*
X-389158Y361207D01*
G01X-385641Y359540D02*
Y356207D01*
G01Y360874D02*
X-385808Y360957D01*
Y361124D01*
X-385641Y361207D01*
X-385474Y361124D01*
Y360957D01*
X-385641Y360874D01*
G01X-378541Y356207D02*
Y359540D01*
G01Y358957D02*
X-378874Y359290D01*
X-379374Y359457D01*
X-379958Y359540D01*
X-380541Y359374D01*
X-381041Y359040D01*
X-381374Y358540D01*
X-381541Y357874D01*
X-381374Y357207D01*
X-381041Y356707D01*
X-380541Y356374D01*
X-379958Y356207D01*
X-379374Y356290D01*
X-378874Y356540D01*
X-378541Y356874D01*
G01X-370258Y356207D02*
Y361207D01*
G01Y358790D02*
X-369841Y359207D01*
X-369424Y359457D01*
X-368758Y359540D01*
X-368258Y359457D01*
X-367674Y359124D01*
X-367424Y358624D01*
Y356207D01*
G01X-363241D02*
X-363741Y356290D01*
X-364241Y356624D01*
X-364574Y357207D01*
X-364741Y357874D01*
X-364574Y358540D01*
X-364241Y359124D01*
X-363741Y359457D01*
X-363241Y359540D01*
X-362741Y359457D01*
X-362241Y359124D01*
X-361908Y358540D01*
X-361824Y357874D01*
X-361908Y357207D01*
X-362241Y356624D01*
X-362741Y356290D01*
X-363241Y356207D01*
G01X-357641D02*
Y361207D01*
G01X-353291Y358457D02*
X-350624D01*
X-350874Y359040D01*
X-351291Y359374D01*
X-351874Y359540D01*
X-352458Y359457D01*
X-352958Y359207D01*
X-353291Y358624D01*
X-353458Y358124D01*
Y357624D01*
X-353291Y357124D01*
X-352874Y356624D01*
X-352374Y356290D01*
X-351791Y356207D01*
X-351208Y356374D01*
X-350624Y356874D01*
G01X-340841Y361207D02*
Y356207D01*
G01X-342008Y359540D02*
X-339674D01*
G01X-336658Y356207D02*
Y361207D01*
G01Y358790D02*
X-336241Y359207D01*
X-335824Y359457D01*
X-335158Y359540D01*
X-334658Y359457D01*
X-334074Y359124D01*
X-333824Y358624D01*
Y356207D01*
G01X-330891Y358457D02*
X-328224D01*
X-328474Y359040D01*
X-328891Y359374D01*
X-329474Y359540D01*
X-330058Y359457D01*
X-330558Y359207D01*
X-330891Y358624D01*
X-331058Y358124D01*
Y357624D01*
X-330891Y357124D01*
X-330474Y356624D01*
X-329974Y356290D01*
X-329391Y356207D01*
X-328808Y356374D01*
X-328224Y356874D01*
G01X-325208Y356207D02*
Y359540D01*
G01Y358874D02*
X-324791Y359207D01*
X-324374Y359457D01*
X-323791Y359540D01*
X-323374Y359457D01*
X-322874Y359207D01*
G01X-320941Y356207D02*
Y359540D01*
G01Y358624D02*
X-320691Y359040D01*
X-320274Y359374D01*
X-319691Y359540D01*
X-319108Y359374D01*
X-318691Y359040D01*
X-318441Y358624D01*
Y356207D01*
G01Y358624D02*
X-318191Y359040D01*
X-317774Y359374D01*
X-317191Y359540D01*
X-316608Y359374D01*
X-316191Y359040D01*
X-315941Y358540D01*
Y356207D01*
G01X-311341D02*
Y359540D01*
G01Y358957D02*
X-311674Y359290D01*
X-312174Y359457D01*
X-312758Y359540D01*
X-313341Y359374D01*
X-313841Y359040D01*
X-314174Y358540D01*
X-314341Y357874D01*
X-314174Y357207D01*
X-313841Y356707D01*
X-313341Y356374D01*
X-312758Y356207D01*
X-312174Y356290D01*
X-311674Y356540D01*
X-311341Y356874D01*
G01X-307241Y356207D02*
Y361207D01*
G01X-297541Y354540D02*
Y359540D01*
G01Y358790D02*
X-297124Y359207D01*
X-296708Y359457D01*
X-296041Y359540D01*
X-295458Y359457D01*
X-294874Y359040D01*
X-294624Y358457D01*
X-294541Y357874D01*
X-294624Y357290D01*
X-294874Y356707D01*
X-295374Y356374D01*
X-296041Y356207D01*
X-296624Y356290D01*
X-297208Y356540D01*
X-297541Y356874D01*
G01X-288941Y356207D02*
Y359540D01*
G01Y358957D02*
X-289274Y359290D01*
X-289774Y359457D01*
X-290358Y359540D01*
X-290941Y359374D01*
X-291441Y359040D01*
X-291774Y358540D01*
X-291941Y357874D01*
X-291774Y357207D01*
X-291441Y356707D01*
X-290941Y356374D01*
X-290358Y356207D01*
X-289774Y356290D01*
X-289274Y356540D01*
X-288941Y356874D01*
G01X-283341Y361207D02*
Y356207D01*
G01Y356957D02*
X-283674Y356540D01*
X-284174Y356290D01*
X-284758Y356207D01*
X-285424Y356374D01*
X-285924Y356790D01*
X-286258Y357290D01*
X-286341Y357874D01*
X-286258Y358457D01*
X-285924Y358957D01*
X-285424Y359374D01*
X-284758Y359540D01*
X-284174Y359457D01*
X-283758Y359290D01*
X-283341Y358957D01*
G01X-392991Y339707D02*
Y344707D01*
G01X-389491D02*
Y339707D01*
G01Y342207D02*
X-392991D01*
G01X-385641Y339707D02*
X-386141Y339790D01*
X-386641Y340124D01*
X-386974Y340707D01*
X-387141Y341374D01*
X-386974Y342040D01*
X-386641Y342624D01*
X-386141Y342957D01*
X-385641Y343040D01*
X-385141Y342957D01*
X-384641Y342624D01*
X-384308Y342040D01*
X-384224Y341374D01*
X-384308Y340707D01*
X-384641Y340124D01*
X-385141Y339790D01*
X-385641Y339707D01*
G01X-380041D02*
Y344707D01*
G01X-375691Y341957D02*
X-373024D01*
X-373274Y342540D01*
X-373691Y342874D01*
X-374274Y343040D01*
X-374858Y342957D01*
X-375358Y342707D01*
X-375691Y342124D01*
X-375858Y341624D01*
Y341124D01*
X-375691Y340624D01*
X-375274Y340124D01*
X-374774Y339790D01*
X-374191Y339707D01*
X-373608Y339874D01*
X-373024Y340374D01*
G01X-364741Y338040D02*
Y343040D01*
G01Y342290D02*
X-364324Y342707D01*
X-363908Y342957D01*
X-363241Y343040D01*
X-362658Y342957D01*
X-362074Y342540D01*
X-361824Y341957D01*
X-361741Y341374D01*
X-361824Y340790D01*
X-362074Y340207D01*
X-362574Y339874D01*
X-363241Y339707D01*
X-363824Y339790D01*
X-364408Y340040D01*
X-364741Y340374D01*
G01X-357641Y339707D02*
X-358141Y339790D01*
X-358641Y340124D01*
X-358974Y340707D01*
X-359141Y341374D01*
X-358974Y342040D01*
X-358641Y342624D01*
X-358141Y342957D01*
X-357641Y343040D01*
X-357141Y342957D01*
X-356641Y342624D01*
X-356308Y342040D01*
X-356224Y341374D01*
X-356308Y340707D01*
X-356641Y340124D01*
X-357141Y339790D01*
X-357641Y339707D01*
G01X-353291Y340290D02*
X-352874Y339957D01*
X-352291Y339707D01*
X-351791D01*
X-351291Y339874D01*
X-350958Y340124D01*
X-350791Y340457D01*
X-350874Y340957D01*
X-351208Y341207D01*
X-352708Y341707D01*
X-353041Y342290D01*
X-352874Y342707D01*
X-352541Y342957D01*
X-352041Y343040D01*
X-351541Y342957D01*
X-351041Y342707D01*
G01X-346441Y343040D02*
Y339707D01*
G01Y344374D02*
X-346608Y344457D01*
Y344624D01*
X-346441Y344707D01*
X-346274Y344624D01*
Y344457D01*
X-346441Y344374D01*
G01X-340841Y344707D02*
Y339707D01*
G01X-342008Y343040D02*
X-339674D01*
G01X-335241D02*
Y339707D01*
G01Y344374D02*
X-335408Y344457D01*
Y344624D01*
X-335241Y344707D01*
X-335074Y344624D01*
Y344457D01*
X-335241Y344374D01*
G01X-329641Y339707D02*
X-330141Y339790D01*
X-330641Y340124D01*
X-330974Y340707D01*
X-331141Y341374D01*
X-330974Y342040D01*
X-330641Y342624D01*
X-330141Y342957D01*
X-329641Y343040D01*
X-329141Y342957D01*
X-328641Y342624D01*
X-328308Y342040D01*
X-328224Y341374D01*
X-328308Y340707D01*
X-328641Y340124D01*
X-329141Y339790D01*
X-329641Y339707D01*
G01X-325458D02*
Y343040D01*
G01Y342207D02*
X-325124Y342624D01*
X-324624Y342957D01*
X-323958Y343040D01*
X-323374Y342957D01*
X-322874Y342624D01*
X-322624Y342040D01*
Y339707D01*
G01X-312841Y344707D02*
Y339707D01*
G01X-314008Y343040D02*
X-311674D01*
G01X-307241Y339707D02*
X-307741Y339790D01*
X-308241Y340124D01*
X-308574Y340707D01*
X-308741Y341374D01*
X-308574Y342040D01*
X-308241Y342624D01*
X-307741Y342957D01*
X-307241Y343040D01*
X-306741Y342957D01*
X-306241Y342624D01*
X-305908Y342040D01*
X-305824Y341374D01*
X-305908Y340707D01*
X-306241Y340124D01*
X-306741Y339790D01*
X-307241Y339707D01*
G01X-301641D02*
Y344707D01*
G01X-297291Y341957D02*
X-294624D01*
X-294874Y342540D01*
X-295291Y342874D01*
X-295874Y343040D01*
X-296458Y342957D01*
X-296958Y342707D01*
X-297291Y342124D01*
X-297458Y341624D01*
Y341124D01*
X-297291Y340624D01*
X-296874Y340124D01*
X-296374Y339790D01*
X-295791Y339707D01*
X-295208Y339874D01*
X-294624Y340374D01*
G01X-291608Y339707D02*
Y343040D01*
G01Y342374D02*
X-291191Y342707D01*
X-290774Y342957D01*
X-290191Y343040D01*
X-289774Y342957D01*
X-289274Y342707D01*
G01X-283341Y339707D02*
Y343040D01*
G01Y342457D02*
X-283674Y342790D01*
X-284174Y342957D01*
X-284758Y343040D01*
X-285341Y342874D01*
X-285841Y342540D01*
X-286174Y342040D01*
X-286341Y341374D01*
X-286174Y340707D01*
X-285841Y340207D01*
X-285341Y339874D01*
X-284758Y339707D01*
X-284174Y339790D01*
X-283674Y340040D01*
X-283341Y340374D01*
G01X-280658Y339707D02*
Y343040D01*
G01Y342207D02*
X-280324Y342624D01*
X-279824Y342957D01*
X-279158Y343040D01*
X-278574Y342957D01*
X-278074Y342624D01*
X-277824Y342040D01*
Y339707D01*
G01X-272308Y342624D02*
X-272891Y342957D01*
X-273391Y343040D01*
X-274058Y342874D01*
X-274558Y342540D01*
X-274891Y341957D01*
X-274974Y341374D01*
X-274891Y340790D01*
X-274558Y340290D01*
X-274058Y339874D01*
X-273391Y339707D01*
X-272808Y339874D01*
X-272308Y340207D01*
G01X-269291Y341957D02*
X-266624D01*
X-266874Y342540D01*
X-267291Y342874D01*
X-267874Y343040D01*
X-268458Y342957D01*
X-268958Y342707D01*
X-269291Y342124D01*
X-269458Y341624D01*
Y341124D01*
X-269291Y340624D01*
X-268874Y340124D01*
X-268374Y339790D01*
X-267791Y339707D01*
X-267208Y339874D01*
X-266624Y340374D01*
G01X-393324Y371207D02*
X-391241Y376207D01*
X-389158Y371207D01*
G01X-389908Y372957D02*
X-392574D01*
G01X-387058Y371207D02*
Y374540D01*
G01Y373707D02*
X-386724Y374124D01*
X-386224Y374457D01*
X-385558Y374540D01*
X-384974Y374457D01*
X-384474Y374124D01*
X-384224Y373540D01*
Y371207D01*
G01X-380041Y376207D02*
Y371207D01*
G01X-381208Y374540D02*
X-378874D01*
G01X-374441D02*
Y371207D01*
G01Y375874D02*
X-374608Y375957D01*
Y376124D01*
X-374441Y376207D01*
X-374274Y376124D01*
Y375957D01*
X-374441Y375874D01*
G01X-369924Y372874D02*
X-367758D01*
G01X-359141Y369540D02*
Y374540D01*
G01Y373790D02*
X-358724Y374207D01*
X-358308Y374457D01*
X-357641Y374540D01*
X-357058Y374457D01*
X-356474Y374040D01*
X-356224Y373457D01*
X-356141Y372874D01*
X-356224Y372290D01*
X-356474Y371707D01*
X-356974Y371374D01*
X-357641Y371207D01*
X-358224Y371290D01*
X-358808Y371540D01*
X-359141Y371874D01*
G01X-350541Y371207D02*
Y374540D01*
G01Y373957D02*
X-350874Y374290D01*
X-351374Y374457D01*
X-351958Y374540D01*
X-352541Y374374D01*
X-353041Y374040D01*
X-353374Y373540D01*
X-353541Y372874D01*
X-353374Y372207D01*
X-353041Y371707D01*
X-352541Y371374D01*
X-351958Y371207D01*
X-351374Y371290D01*
X-350874Y371540D01*
X-350541Y371874D01*
G01X-344941Y376207D02*
Y371207D01*
G01Y371957D02*
X-345274Y371540D01*
X-345774Y371290D01*
X-346358Y371207D01*
X-347024Y371374D01*
X-347524Y371790D01*
X-347858Y372290D01*
X-347941Y372874D01*
X-347858Y373457D01*
X-347524Y373957D01*
X-347024Y374374D01*
X-346358Y374540D01*
X-345774Y374457D01*
X-345358Y374290D01*
X-344941Y373957D01*
G01X-401741Y365207D02*
X189259D01*
G01X-401741Y335207D02*
X189259D01*
G01X-393398Y390797D02*
Y395797D01*
X-389564Y390797D01*
Y395797D01*
G01X-385881Y390797D02*
X-386381Y390880D01*
X-386881Y391214D01*
X-387214Y391797D01*
X-387381Y392464D01*
X-387214Y393130D01*
X-386881Y393714D01*
X-386381Y394047D01*
X-385881Y394130D01*
X-385381Y394047D01*
X-384881Y393714D01*
X-384548Y393130D01*
X-384464Y392464D01*
X-384548Y391797D01*
X-384881Y391214D01*
X-385381Y390880D01*
X-385881Y390797D01*
G01X-381698D02*
Y394130D01*
G01Y393297D02*
X-381364Y393714D01*
X-380864Y394047D01*
X-380198Y394130D01*
X-379614Y394047D01*
X-379114Y393714D01*
X-378864Y393130D01*
Y390797D01*
G01X-375764Y392464D02*
X-373598D01*
G01X-369581Y390797D02*
Y395047D01*
X-369414Y395464D01*
X-369081Y395714D01*
X-368581Y395797D01*
X-368081Y395630D01*
X-367831Y395214D01*
G01X-368831Y393797D02*
X-370498D01*
G01X-364898Y394130D02*
Y391797D01*
X-364564Y391214D01*
X-364064Y390880D01*
X-363481Y390797D01*
X-362898Y390880D01*
X-362398Y391214D01*
X-362064Y391797D01*
G01Y390797D02*
Y394130D01*
G01X-359298Y390797D02*
Y394130D01*
G01Y393297D02*
X-358964Y393714D01*
X-358464Y394047D01*
X-357798Y394130D01*
X-357214Y394047D01*
X-356714Y393714D01*
X-356464Y393130D01*
Y390797D01*
G01X-350948Y393714D02*
X-351531Y394047D01*
X-352031Y394130D01*
X-352698Y393964D01*
X-353198Y393630D01*
X-353531Y393047D01*
X-353614Y392464D01*
X-353531Y391880D01*
X-353198Y391380D01*
X-352698Y390964D01*
X-352031Y390797D01*
X-351448Y390964D01*
X-350948Y391297D01*
G01X-346681Y395797D02*
Y390797D01*
G01X-347848Y394130D02*
X-345514D01*
G01X-341081D02*
Y390797D01*
G01Y395464D02*
X-341248Y395547D01*
Y395714D01*
X-341081Y395797D01*
X-340914Y395714D01*
Y395547D01*
X-341081Y395464D01*
G01X-335481Y390797D02*
X-335981Y390880D01*
X-336481Y391214D01*
X-336814Y391797D01*
X-336981Y392464D01*
X-336814Y393130D01*
X-336481Y393714D01*
X-335981Y394047D01*
X-335481Y394130D01*
X-334981Y394047D01*
X-334481Y393714D01*
X-334148Y393130D01*
X-334064Y392464D01*
X-334148Y391797D01*
X-334481Y391214D01*
X-334981Y390880D01*
X-335481Y390797D01*
G01X-331298D02*
Y394130D01*
G01Y393297D02*
X-330964Y393714D01*
X-330464Y394047D01*
X-329798Y394130D01*
X-329214Y394047D01*
X-328714Y393714D01*
X-328464Y393130D01*
Y390797D01*
G01X-322781D02*
Y394130D01*
G01Y393547D02*
X-323114Y393880D01*
X-323614Y394047D01*
X-324198Y394130D01*
X-324781Y393964D01*
X-325281Y393630D01*
X-325614Y393130D01*
X-325781Y392464D01*
X-325614Y391797D01*
X-325281Y391297D01*
X-324781Y390964D01*
X-324198Y390797D01*
X-323614Y390880D01*
X-323114Y391130D01*
X-322781Y391464D01*
G01X-318681Y390797D02*
Y395797D01*
G01X-308981Y389130D02*
Y394130D01*
G01Y393380D02*
X-308564Y393797D01*
X-308148Y394047D01*
X-307481Y394130D01*
X-306898Y394047D01*
X-306314Y393630D01*
X-306064Y393047D01*
X-305981Y392464D01*
X-306064Y391880D01*
X-306314Y391297D01*
X-306814Y390964D01*
X-307481Y390797D01*
X-308064Y390880D01*
X-308648Y391130D01*
X-308981Y391464D01*
G01X-300381Y390797D02*
Y394130D01*
G01Y393547D02*
X-300714Y393880D01*
X-301214Y394047D01*
X-301798Y394130D01*
X-302381Y393964D01*
X-302881Y393630D01*
X-303214Y393130D01*
X-303381Y392464D01*
X-303214Y391797D01*
X-302881Y391297D01*
X-302381Y390964D01*
X-301798Y390797D01*
X-301214Y390880D01*
X-300714Y391130D01*
X-300381Y391464D01*
G01X-294781Y395797D02*
Y390797D01*
G01Y391547D02*
X-295114Y391130D01*
X-295614Y390880D01*
X-296198Y390797D01*
X-296864Y390964D01*
X-297364Y391380D01*
X-297698Y391880D01*
X-297781Y392464D01*
X-297698Y393047D01*
X-297364Y393547D01*
X-296864Y393964D01*
X-296198Y394130D01*
X-295614Y394047D01*
X-295198Y393880D01*
X-294781Y393547D01*
G01X-401741Y380207D02*
X189259D01*
G01X-438241Y521640D02*
X-438408Y521724D01*
Y521890D01*
X-438241Y521974D01*
X-438074Y521890D01*
Y521724D01*
X-438241Y521640D01*
G01Y512640D02*
X-438408Y512724D01*
Y512890D01*
X-438241Y512974D01*
X-438074Y512890D01*
Y512724D01*
X-438241Y512640D01*
G01Y503640D02*
X-438408Y503724D01*
Y503890D01*
X-438241Y503974D01*
X-438074Y503890D01*
Y503724D01*
X-438241Y503640D01*
G01Y494640D02*
X-438408Y494724D01*
Y494890D01*
X-438241Y494974D01*
X-438074Y494890D01*
Y494724D01*
X-438241Y494640D01*
G01X-434241Y480807D02*
X-432241D01*
G01X-433241D02*
Y475807D01*
G01X-434241D02*
X-432241D01*
G01X-429308D02*
Y480807D01*
X-427308D01*
X-426641Y480557D01*
X-426141Y479974D01*
X-425974Y479307D01*
X-426141Y478640D01*
X-426558Y478140D01*
X-427308Y477890D01*
X-429308D01*
G01X-420208Y480390D02*
X-420708Y480640D01*
X-421291Y480807D01*
X-421958D01*
X-422708Y480557D01*
X-423291Y480140D01*
X-423708Y479640D01*
X-424041Y478807D01*
X-424124Y478057D01*
X-423958Y477307D01*
X-423708Y476807D01*
X-423208Y476307D01*
X-422624Y475974D01*
X-422041Y475807D01*
X-421458D01*
X-420874Y475974D01*
X-420374Y476224D01*
X-419958Y476557D01*
G01X-417524Y477474D02*
X-415358D01*
G01X-412508Y480807D02*
Y475807D01*
X-409174D01*
G01X-406324Y477474D02*
X-404158D01*
G01X-399641Y475807D02*
Y480807D01*
X-400641Y479807D01*
G01Y475807D02*
X-398641D01*
G01X-394041Y480807D02*
X-394708Y480640D01*
X-395208Y480224D01*
X-395541Y479724D01*
X-395791Y479057D01*
X-395874Y478307D01*
X-395791Y477557D01*
X-395541Y476890D01*
X-395208Y476390D01*
X-394708Y475974D01*
X-394041Y475807D01*
X-393374Y475974D01*
X-392874Y476390D01*
X-392541Y476890D01*
X-392291Y477557D01*
X-392208Y478307D01*
X-392291Y479057D01*
X-392541Y479724D01*
X-392874Y480224D01*
X-393374Y480640D01*
X-394041Y480807D01*
G01X-389858Y476390D02*
X-389274Y475974D01*
X-388608Y475807D01*
X-387941Y475974D01*
X-387358Y476474D01*
X-386941Y477224D01*
X-386774Y477974D01*
Y478890D01*
X-386941Y479640D01*
X-387358Y480307D01*
X-387858Y480640D01*
X-388441Y480807D01*
X-389108Y480640D01*
X-389608Y480307D01*
X-389941Y479807D01*
X-390108Y479140D01*
X-389941Y478557D01*
X-389524Y477974D01*
X-389024Y477640D01*
X-388441Y477557D01*
X-387774Y477724D01*
X-387274Y478140D01*
X-386774Y478890D01*
G01X-378991Y476474D02*
X-378324Y476057D01*
X-377574Y475807D01*
X-376908D01*
X-376241Y476057D01*
X-375741Y476474D01*
X-375491Y477057D01*
X-375658Y477640D01*
X-376074Y478140D01*
X-376824Y478474D01*
X-377824Y478640D01*
X-378408Y478974D01*
X-378658Y479557D01*
X-378491Y480140D01*
X-378074Y480557D01*
X-377491Y480807D01*
X-376908D01*
X-376324Y480640D01*
X-375824Y480224D01*
G01X-373141Y474140D02*
Y479140D01*
G01Y478390D02*
X-372724Y478807D01*
X-372308Y479057D01*
X-371641Y479140D01*
X-371058Y479057D01*
X-370474Y478640D01*
X-370224Y478057D01*
X-370141Y477474D01*
X-370224Y476890D01*
X-370474Y476307D01*
X-370974Y475974D01*
X-371641Y475807D01*
X-372224Y475890D01*
X-372808Y476140D01*
X-373141Y476474D01*
G01X-367291Y478057D02*
X-364624D01*
X-364874Y478640D01*
X-365291Y478974D01*
X-365874Y479140D01*
X-366458Y479057D01*
X-366958Y478807D01*
X-367291Y478224D01*
X-367458Y477724D01*
Y477224D01*
X-367291Y476724D01*
X-366874Y476224D01*
X-366374Y475890D01*
X-365791Y475807D01*
X-365208Y475974D01*
X-364624Y476474D01*
G01X-359108Y478724D02*
X-359691Y479057D01*
X-360191Y479140D01*
X-360858Y478974D01*
X-361358Y478640D01*
X-361691Y478057D01*
X-361774Y477474D01*
X-361691Y476890D01*
X-361358Y476390D01*
X-360858Y475974D01*
X-360191Y475807D01*
X-359608Y475974D01*
X-359108Y476307D01*
G01X-354841Y479140D02*
Y475807D01*
G01Y480474D02*
X-355008Y480557D01*
Y480724D01*
X-354841Y480807D01*
X-354674Y480724D01*
Y480557D01*
X-354841Y480474D01*
G01X-349741Y475807D02*
Y480057D01*
X-349574Y480474D01*
X-349241Y480724D01*
X-348741Y480807D01*
X-348241Y480640D01*
X-347991Y480224D01*
G01X-348991Y478807D02*
X-350658D01*
G01X-343641Y479140D02*
Y475807D01*
G01Y480474D02*
X-343808Y480557D01*
Y480724D01*
X-343641Y480807D01*
X-343474Y480724D01*
Y480557D01*
X-343641Y480474D01*
G01X-336708Y478724D02*
X-337291Y479057D01*
X-337791Y479140D01*
X-338458Y478974D01*
X-338958Y478640D01*
X-339291Y478057D01*
X-339374Y477474D01*
X-339291Y476890D01*
X-338958Y476390D01*
X-338458Y475974D01*
X-337791Y475807D01*
X-337208Y475974D01*
X-336708Y476307D01*
G01X-330941Y475807D02*
Y479140D01*
G01Y478557D02*
X-331274Y478890D01*
X-331774Y479057D01*
X-332358Y479140D01*
X-332941Y478974D01*
X-333441Y478640D01*
X-333774Y478140D01*
X-333941Y477474D01*
X-333774Y476807D01*
X-333441Y476307D01*
X-332941Y475974D01*
X-332358Y475807D01*
X-331774Y475890D01*
X-331274Y476140D01*
X-330941Y476474D01*
G01X-326841Y480807D02*
Y475807D01*
G01X-328008Y479140D02*
X-325674D01*
G01X-321241D02*
Y475807D01*
G01Y480474D02*
X-321408Y480557D01*
Y480724D01*
X-321241Y480807D01*
X-321074Y480724D01*
Y480557D01*
X-321241Y480474D01*
G01X-315641Y475807D02*
X-316141Y475890D01*
X-316641Y476224D01*
X-316974Y476807D01*
X-317141Y477474D01*
X-316974Y478140D01*
X-316641Y478724D01*
X-316141Y479057D01*
X-315641Y479140D01*
X-315141Y479057D01*
X-314641Y478724D01*
X-314308Y478140D01*
X-314224Y477474D01*
X-314308Y476807D01*
X-314641Y476224D01*
X-315141Y475890D01*
X-315641Y475807D01*
G01X-311458D02*
Y479140D01*
G01Y478307D02*
X-311124Y478724D01*
X-310624Y479057D01*
X-309958Y479140D01*
X-309374Y479057D01*
X-308874Y478724D01*
X-308624Y478140D01*
Y475807D01*
G01X-299341D02*
Y480057D01*
X-299174Y480474D01*
X-298841Y480724D01*
X-298341Y480807D01*
X-297841Y480640D01*
X-297591Y480224D01*
G01X-298591Y478807D02*
X-300258D01*
G01X-293241Y475807D02*
X-293741Y475890D01*
X-294241Y476224D01*
X-294574Y476807D01*
X-294741Y477474D01*
X-294574Y478140D01*
X-294241Y478724D01*
X-293741Y479057D01*
X-293241Y479140D01*
X-292741Y479057D01*
X-292241Y478724D01*
X-291908Y478140D01*
X-291824Y477474D01*
X-291908Y476807D01*
X-292241Y476224D01*
X-292741Y475890D01*
X-293241Y475807D01*
G01X-288808D02*
Y479140D01*
G01Y478474D02*
X-288391Y478807D01*
X-287974Y479057D01*
X-287391Y479140D01*
X-286974Y479057D01*
X-286474Y478807D01*
G01X-278108Y475807D02*
Y480807D01*
X-276024D01*
X-275358Y480557D01*
X-274941Y480224D01*
X-274774Y479557D01*
X-274941Y478890D01*
X-275441Y478474D01*
X-276024Y478224D01*
X-278108D01*
G01X-276024D02*
X-274774Y475807D01*
G01X-272091Y478057D02*
X-269424D01*
X-269674Y478640D01*
X-270091Y478974D01*
X-270674Y479140D01*
X-271258Y479057D01*
X-271758Y478807D01*
X-272091Y478224D01*
X-272258Y477724D01*
Y477224D01*
X-272091Y476724D01*
X-271674Y476224D01*
X-271174Y475890D01*
X-270591Y475807D01*
X-270008Y475974D01*
X-269424Y476474D01*
G01X-266491Y476390D02*
X-266074Y476057D01*
X-265491Y475807D01*
X-264991D01*
X-264491Y475974D01*
X-264158Y476224D01*
X-263991Y476557D01*
X-264074Y477057D01*
X-264408Y477307D01*
X-265908Y477807D01*
X-266241Y478390D01*
X-266074Y478807D01*
X-265741Y479057D01*
X-265241Y479140D01*
X-264741Y479057D01*
X-264241Y478807D01*
G01X-259641Y479140D02*
Y475807D01*
G01Y480474D02*
X-259808Y480557D01*
Y480724D01*
X-259641Y480807D01*
X-259474Y480724D01*
Y480557D01*
X-259641Y480474D01*
G01X-255458Y475807D02*
Y479140D01*
G01Y478307D02*
X-255124Y478724D01*
X-254624Y479057D01*
X-253958Y479140D01*
X-253374Y479057D01*
X-252874Y478724D01*
X-252624Y478140D01*
Y475807D01*
G01X-243841Y480807D02*
X-241841D01*
G01X-242841D02*
Y475807D01*
G01X-243841D02*
X-241841D01*
G01X-239741D02*
Y479140D01*
G01Y478224D02*
X-239491Y478640D01*
X-239074Y478974D01*
X-238491Y479140D01*
X-237908Y478974D01*
X-237491Y478640D01*
X-237241Y478224D01*
Y475807D01*
G01Y478224D02*
X-236991Y478640D01*
X-236574Y478974D01*
X-235991Y479140D01*
X-235408Y478974D01*
X-234991Y478640D01*
X-234741Y478140D01*
Y475807D01*
G01X-233141Y474140D02*
Y479140D01*
G01Y478390D02*
X-232724Y478807D01*
X-232308Y479057D01*
X-231641Y479140D01*
X-231058Y479057D01*
X-230474Y478640D01*
X-230224Y478057D01*
X-230141Y477474D01*
X-230224Y476890D01*
X-230474Y476307D01*
X-230974Y475974D01*
X-231641Y475807D01*
X-232224Y475890D01*
X-232808Y476140D01*
X-233141Y476474D01*
G01X-227208Y475807D02*
Y479140D01*
G01Y478474D02*
X-226791Y478807D01*
X-226374Y479057D01*
X-225791Y479140D01*
X-225374Y479057D01*
X-224874Y478807D01*
G01X-221691Y478057D02*
X-219024D01*
X-219274Y478640D01*
X-219691Y478974D01*
X-220274Y479140D01*
X-220858Y479057D01*
X-221358Y478807D01*
X-221691Y478224D01*
X-221858Y477724D01*
Y477224D01*
X-221691Y476724D01*
X-221274Y476224D01*
X-220774Y475890D01*
X-220191Y475807D01*
X-219608Y475974D01*
X-219024Y476474D01*
G01X-216008Y474557D02*
X-215424Y474224D01*
X-214758Y474140D01*
X-214174Y474224D01*
X-213674Y474640D01*
X-213341Y475224D01*
Y479140D01*
G01Y478474D02*
X-213674Y478807D01*
X-214174Y479057D01*
X-214758Y479140D01*
X-215424Y478974D01*
X-215841Y478640D01*
X-216174Y478057D01*
X-216341Y477474D01*
X-216258Y476974D01*
X-215924Y476390D01*
X-215424Y475974D01*
X-214758Y475807D01*
X-214258Y475890D01*
X-213674Y476224D01*
X-213341Y476557D01*
G01X-210658Y475807D02*
Y479140D01*
G01Y478307D02*
X-210324Y478724D01*
X-209824Y479057D01*
X-209158Y479140D01*
X-208574Y479057D01*
X-208074Y478724D01*
X-207824Y478140D01*
Y475807D01*
G01X-202141D02*
Y479140D01*
G01Y478557D02*
X-202474Y478890D01*
X-202974Y479057D01*
X-203558Y479140D01*
X-204141Y478974D01*
X-204641Y478640D01*
X-204974Y478140D01*
X-205141Y477474D01*
X-204974Y476807D01*
X-204641Y476307D01*
X-204141Y475974D01*
X-203558Y475807D01*
X-202974Y475890D01*
X-202474Y476140D01*
X-202141Y476474D01*
G01X-198041Y480807D02*
Y475807D01*
G01X-199208Y479140D02*
X-196874D01*
G01X-193691Y478057D02*
X-191024D01*
X-191274Y478640D01*
X-191691Y478974D01*
X-192274Y479140D01*
X-192858Y479057D01*
X-193358Y478807D01*
X-193691Y478224D01*
X-193858Y477724D01*
Y477224D01*
X-193691Y476724D01*
X-193274Y476224D01*
X-192774Y475890D01*
X-192191Y475807D01*
X-191608Y475974D01*
X-191024Y476474D01*
G01X-185341Y480807D02*
Y475807D01*
G01Y476557D02*
X-185674Y476140D01*
X-186174Y475890D01*
X-186758Y475807D01*
X-187424Y475974D01*
X-187924Y476390D01*
X-188258Y476890D01*
X-188341Y477474D01*
X-188258Y478057D01*
X-187924Y478557D01*
X-187424Y478974D01*
X-186758Y479140D01*
X-186174Y479057D01*
X-185758Y478890D01*
X-185341Y478557D01*
G01X-177224Y475807D02*
Y480807D01*
X-174058D01*
G01X-175224Y478390D02*
X-177224D01*
G01X-168541Y475807D02*
Y479140D01*
G01Y478557D02*
X-168874Y478890D01*
X-169374Y479057D01*
X-169958Y479140D01*
X-170541Y478974D01*
X-171041Y478640D01*
X-171374Y478140D01*
X-171541Y477474D01*
X-171374Y476807D01*
X-171041Y476307D01*
X-170541Y475974D01*
X-169958Y475807D01*
X-169374Y475890D01*
X-168874Y476140D01*
X-168541Y476474D01*
G01X-165941Y475807D02*
Y480807D01*
G01Y478307D02*
X-165524Y478807D01*
X-165024Y479057D01*
X-164524Y479140D01*
X-163774Y478974D01*
X-163274Y478640D01*
X-162941Y478057D01*
Y477390D01*
X-163108Y476724D01*
X-163441Y476224D01*
X-164024Y475890D01*
X-164524Y475807D01*
X-165024Y475890D01*
X-165524Y476140D01*
X-165941Y476557D01*
G01X-160008Y475807D02*
Y479140D01*
G01Y478474D02*
X-159591Y478807D01*
X-159174Y479057D01*
X-158591Y479140D01*
X-158174Y479057D01*
X-157674Y478807D01*
G01X-153241Y479140D02*
Y475807D01*
G01Y480474D02*
X-153408Y480557D01*
Y480724D01*
X-153241Y480807D01*
X-153074Y480724D01*
Y480557D01*
X-153241Y480474D01*
G01X-146308Y478724D02*
X-146891Y479057D01*
X-147391Y479140D01*
X-148058Y478974D01*
X-148558Y478640D01*
X-148891Y478057D01*
X-148974Y477474D01*
X-148891Y476890D01*
X-148558Y476390D01*
X-148058Y475974D01*
X-147391Y475807D01*
X-146808Y475974D01*
X-146308Y476307D01*
G01X-142458Y474140D02*
X-143291Y474974D01*
X-143708Y475807D01*
Y479140D01*
X-143291Y479974D01*
X-142458Y480807D01*
G01X-138108Y475807D02*
Y480807D01*
X-136108D01*
X-135441Y480557D01*
X-134941Y479974D01*
X-134774Y479307D01*
X-134941Y478640D01*
X-135358Y478140D01*
X-136108Y477890D01*
X-138108D01*
G01X-132008Y475807D02*
Y479140D01*
G01Y478474D02*
X-131591Y478807D01*
X-131174Y479057D01*
X-130591Y479140D01*
X-130174Y479057D01*
X-129674Y478807D01*
G01X-126491Y478057D02*
X-123824D01*
X-124074Y478640D01*
X-124491Y478974D01*
X-125074Y479140D01*
X-125658Y479057D01*
X-126158Y478807D01*
X-126491Y478224D01*
X-126658Y477724D01*
Y477224D01*
X-126491Y476724D01*
X-126074Y476224D01*
X-125574Y475890D01*
X-124991Y475807D01*
X-124408Y475974D01*
X-123824Y476474D01*
G01X-121141Y474140D02*
Y479140D01*
G01Y478390D02*
X-120724Y478807D01*
X-120308Y479057D01*
X-119641Y479140D01*
X-119058Y479057D01*
X-118474Y478640D01*
X-118224Y478057D01*
X-118141Y477474D01*
X-118224Y476890D01*
X-118474Y476307D01*
X-118974Y475974D01*
X-119641Y475807D01*
X-120224Y475890D01*
X-120808Y476140D01*
X-121141Y476474D01*
G01X-115208Y475807D02*
Y479140D01*
G01Y478474D02*
X-114791Y478807D01*
X-114374Y479057D01*
X-113791Y479140D01*
X-113374Y479057D01*
X-112874Y478807D01*
G01X-109691Y478057D02*
X-107024D01*
X-107274Y478640D01*
X-107691Y478974D01*
X-108274Y479140D01*
X-108858Y479057D01*
X-109358Y478807D01*
X-109691Y478224D01*
X-109858Y477724D01*
Y477224D01*
X-109691Y476724D01*
X-109274Y476224D01*
X-108774Y475890D01*
X-108191Y475807D01*
X-107608Y475974D01*
X-107024Y476474D01*
G01X-104008Y474557D02*
X-103424Y474224D01*
X-102758Y474140D01*
X-102174Y474224D01*
X-101674Y474640D01*
X-101341Y475224D01*
Y479140D01*
G01Y478474D02*
X-101674Y478807D01*
X-102174Y479057D01*
X-102758Y479140D01*
X-103424Y478974D01*
X-103841Y478640D01*
X-104174Y478057D01*
X-104341Y477474D01*
X-104258Y476974D01*
X-103924Y476390D01*
X-103424Y475974D01*
X-102758Y475807D01*
X-102258Y475890D01*
X-101674Y476224D01*
X-101341Y476557D01*
G01X-96824Y474140D02*
X-95991Y474974D01*
X-95574Y475807D01*
Y479140D01*
X-95991Y479974D01*
X-96824Y480807D01*
G01X-86541Y475807D02*
Y480057D01*
X-86374Y480474D01*
X-86041Y480724D01*
X-85541Y480807D01*
X-85041Y480640D01*
X-84791Y480224D01*
G01X-85791Y478807D02*
X-87458D01*
G01X-80441Y475807D02*
X-80941Y475890D01*
X-81441Y476224D01*
X-81774Y476807D01*
X-81941Y477474D01*
X-81774Y478140D01*
X-81441Y478724D01*
X-80941Y479057D01*
X-80441Y479140D01*
X-79941Y479057D01*
X-79441Y478724D01*
X-79108Y478140D01*
X-79024Y477474D01*
X-79108Y476807D01*
X-79441Y476224D01*
X-79941Y475890D01*
X-80441Y475807D01*
G01X-76008D02*
Y479140D01*
G01Y478474D02*
X-75591Y478807D01*
X-75174Y479057D01*
X-74591Y479140D01*
X-74174Y479057D01*
X-73674Y478807D01*
G01X-65808Y475807D02*
Y480807D01*
X-63641Y476640D01*
X-61474Y480807D01*
Y475807D01*
G01X-59458Y479140D02*
Y476807D01*
X-59124Y476224D01*
X-58624Y475890D01*
X-58041Y475807D01*
X-57458Y475890D01*
X-56958Y476224D01*
X-56624Y476807D01*
G01Y475807D02*
Y479140D01*
G01X-52441Y475807D02*
Y480807D01*
G01X-46841D02*
Y475807D01*
G01X-48008Y479140D02*
X-45674D01*
G01X-41241D02*
Y475807D01*
G01Y480474D02*
X-41408Y480557D01*
Y480724D01*
X-41241Y480807D01*
X-41074Y480724D01*
Y480557D01*
X-41241Y480474D01*
G01X-35641Y475807D02*
Y480807D01*
G01X-28541Y475807D02*
Y479140D01*
G01Y478557D02*
X-28874Y478890D01*
X-29374Y479057D01*
X-29958Y479140D01*
X-30541Y478974D01*
X-31041Y478640D01*
X-31374Y478140D01*
X-31541Y477474D01*
X-31374Y476807D01*
X-31041Y476307D01*
X-30541Y475974D01*
X-29958Y475807D01*
X-29374Y475890D01*
X-28874Y476140D01*
X-28541Y476474D01*
G01X-26191Y474307D02*
X-25691Y474140D01*
X-25024Y474307D01*
X-24608Y474640D01*
X-24274Y475057D01*
X-23774Y476390D01*
X-22691Y479140D01*
G01X-25358D02*
X-23774Y476390D01*
G01X-20091Y478057D02*
X-17424D01*
X-17674Y478640D01*
X-18091Y478974D01*
X-18674Y479140D01*
X-19258Y479057D01*
X-19758Y478807D01*
X-20091Y478224D01*
X-20258Y477724D01*
Y477224D01*
X-20091Y476724D01*
X-19674Y476224D01*
X-19174Y475890D01*
X-18591Y475807D01*
X-18008Y475974D01*
X-17424Y476474D01*
G01X-14408Y475807D02*
Y479140D01*
G01Y478474D02*
X-13991Y478807D01*
X-13574Y479057D01*
X-12991Y479140D01*
X-12574Y479057D01*
X-12074Y478807D01*
G01X-3708Y475807D02*
Y480807D01*
X-1708D01*
X-1041Y480557D01*
X-541Y479974D01*
X-374Y479307D01*
X-541Y478640D01*
X-958Y478140D01*
X-1708Y477890D01*
X-3708D01*
G01X2392Y475807D02*
Y479140D01*
G01Y478474D02*
X2809Y478807D01*
X3226Y479057D01*
X3809Y479140D01*
X4226Y479057D01*
X4726Y478807D01*
G01X9159Y479140D02*
Y475807D01*
G01Y480474D02*
X8992Y480557D01*
Y480724D01*
X9159Y480807D01*
X9326Y480724D01*
Y480557D01*
X9159Y480474D01*
G01X13342Y475807D02*
Y479140D01*
G01Y478307D02*
X13676Y478724D01*
X14176Y479057D01*
X14842Y479140D01*
X15426Y479057D01*
X15926Y478724D01*
X16176Y478140D01*
Y475807D01*
G01X20359Y480807D02*
Y475807D01*
G01X19192Y479140D02*
X21526D01*
G01X24709Y478057D02*
X27376D01*
X27126Y478640D01*
X26709Y478974D01*
X26126Y479140D01*
X25542Y479057D01*
X25042Y478807D01*
X24709Y478224D01*
X24542Y477724D01*
Y477224D01*
X24709Y476724D01*
X25126Y476224D01*
X25626Y475890D01*
X26209Y475807D01*
X26792Y475974D01*
X27376Y476474D01*
G01X33059Y480807D02*
Y475807D01*
G01Y476557D02*
X32726Y476140D01*
X32226Y475890D01*
X31642Y475807D01*
X30976Y475974D01*
X30476Y476390D01*
X30142Y476890D01*
X30059Y477474D01*
X30142Y478057D01*
X30476Y478557D01*
X30976Y478974D01*
X31642Y479140D01*
X32226Y479057D01*
X32642Y478890D01*
X33059Y478557D01*
G01X43426Y478474D02*
X43759Y478724D01*
X44009Y479140D01*
X44176Y479724D01*
X44009Y480224D01*
X43676Y480557D01*
X43092Y480807D01*
X40842D01*
Y475807D01*
X43592D01*
X44176Y476140D01*
X44509Y476640D01*
X44676Y477224D01*
X44509Y477807D01*
X44009Y478307D01*
X43426Y478474D01*
X40842D01*
G01X48359Y475807D02*
X47859Y475890D01*
X47359Y476224D01*
X47026Y476807D01*
X46859Y477474D01*
X47026Y478140D01*
X47359Y478724D01*
X47859Y479057D01*
X48359Y479140D01*
X48859Y479057D01*
X49359Y478724D01*
X49692Y478140D01*
X49776Y477474D01*
X49692Y476807D01*
X49359Y476224D01*
X48859Y475890D01*
X48359Y475807D01*
G01X55459D02*
Y479140D01*
G01Y478557D02*
X55126Y478890D01*
X54626Y479057D01*
X54042Y479140D01*
X53459Y478974D01*
X52959Y478640D01*
X52626Y478140D01*
X52459Y477474D01*
X52626Y476807D01*
X52959Y476307D01*
X53459Y475974D01*
X54042Y475807D01*
X54626Y475890D01*
X55126Y476140D01*
X55459Y476474D01*
G01X58392Y475807D02*
Y479140D01*
G01Y478474D02*
X58809Y478807D01*
X59226Y479057D01*
X59809Y479140D01*
X60226Y479057D01*
X60726Y478807D01*
G01X66659Y480807D02*
Y475807D01*
G01Y476557D02*
X66326Y476140D01*
X65826Y475890D01*
X65242Y475807D01*
X64576Y475974D01*
X64076Y476390D01*
X63742Y476890D01*
X63659Y477474D01*
X63742Y478057D01*
X64076Y478557D01*
X64576Y478974D01*
X65242Y479140D01*
X65826Y479057D01*
X66242Y478890D01*
X66659Y478557D01*
G01X69509Y476390D02*
X69926Y476057D01*
X70509Y475807D01*
X71009D01*
X71509Y475974D01*
X71842Y476224D01*
X72009Y476557D01*
X71926Y477057D01*
X71592Y477307D01*
X70092Y477807D01*
X69759Y478390D01*
X69926Y478807D01*
X70259Y479057D01*
X70759Y479140D01*
X71259Y479057D01*
X71759Y478807D01*
G01X-434241Y489807D02*
X-432241D01*
G01X-433241D02*
Y484807D01*
G01X-434241D02*
X-432241D01*
G01X-429308D02*
Y489807D01*
X-427308D01*
X-426641Y489557D01*
X-426141Y488974D01*
X-425974Y488307D01*
X-426141Y487640D01*
X-426558Y487140D01*
X-427308Y486890D01*
X-429308D01*
G01X-420208Y489390D02*
X-420708Y489640D01*
X-421291Y489807D01*
X-421958D01*
X-422708Y489557D01*
X-423291Y489140D01*
X-423708Y488640D01*
X-424041Y487807D01*
X-424124Y487057D01*
X-423958Y486307D01*
X-423708Y485807D01*
X-423208Y485307D01*
X-422624Y484974D01*
X-422041Y484807D01*
X-421458D01*
X-420874Y484974D01*
X-420374Y485224D01*
X-419958Y485557D01*
G01X-417524Y486474D02*
X-415358D01*
G01X-413008Y484807D02*
Y489807D01*
X-410841Y485640D01*
X-408674Y489807D01*
Y484807D01*
G01X-406824D02*
Y489807D01*
X-403658D01*
G01X-404824Y487390D02*
X-406824D01*
G01X-400724Y486474D02*
X-398558D01*
G01X-394041Y484807D02*
Y489807D01*
X-395041Y488807D01*
G01Y484807D02*
X-393041D01*
G01X-390274Y485557D02*
X-389774Y485140D01*
X-389191Y484890D01*
X-388441Y484807D01*
X-387691Y484974D01*
X-387108Y485307D01*
X-386691Y485890D01*
X-386608Y486557D01*
X-386774Y487224D01*
X-387191Y487640D01*
X-387774Y487974D01*
X-388358Y488057D01*
X-388941Y487974D01*
X-389691Y487640D01*
X-389441Y489807D01*
X-387191D01*
G01X-382841D02*
X-383508Y489640D01*
X-384008Y489224D01*
X-384341Y488724D01*
X-384591Y488057D01*
X-384674Y487307D01*
X-384591Y486557D01*
X-384341Y485890D01*
X-384008Y485390D01*
X-383508Y484974D01*
X-382841Y484807D01*
X-382174Y484974D01*
X-381674Y485390D01*
X-381341Y485890D01*
X-381091Y486557D01*
X-381008Y487307D01*
X-381091Y488057D01*
X-381341Y488724D01*
X-381674Y489224D01*
X-382174Y489640D01*
X-382841Y489807D01*
G01X-373808Y484807D02*
Y489807D01*
X-371641Y485640D01*
X-369474Y489807D01*
Y484807D01*
G01X-367291Y487057D02*
X-364624D01*
X-364874Y487640D01*
X-365291Y487974D01*
X-365874Y488140D01*
X-366458Y488057D01*
X-366958Y487807D01*
X-367291Y487224D01*
X-367458Y486724D01*
Y486224D01*
X-367291Y485724D01*
X-366874Y485224D01*
X-366374Y484890D01*
X-365791Y484807D01*
X-365208Y484974D01*
X-364624Y485474D01*
G01X-360441Y489807D02*
Y484807D01*
G01X-361608Y488140D02*
X-359274D01*
G01X-353341Y484807D02*
Y488140D01*
G01Y487557D02*
X-353674Y487890D01*
X-354174Y488057D01*
X-354758Y488140D01*
X-355341Y487974D01*
X-355841Y487640D01*
X-356174Y487140D01*
X-356341Y486474D01*
X-356174Y485807D01*
X-355841Y485307D01*
X-355341Y484974D01*
X-354758Y484807D01*
X-354174Y484890D01*
X-353674Y485140D01*
X-353341Y485474D01*
G01X-349241Y484807D02*
Y489807D01*
G01X-339624Y484807D02*
Y489807D01*
X-336458D01*
G01X-337624Y487390D02*
X-339624D01*
G01X-332441Y484807D02*
X-332941Y484890D01*
X-333441Y485224D01*
X-333774Y485807D01*
X-333941Y486474D01*
X-333774Y487140D01*
X-333441Y487724D01*
X-332941Y488057D01*
X-332441Y488140D01*
X-331941Y488057D01*
X-331441Y487724D01*
X-331108Y487140D01*
X-331024Y486474D01*
X-331108Y485807D01*
X-331441Y485224D01*
X-331941Y484890D01*
X-332441Y484807D01*
G01X-326841Y488140D02*
Y484807D01*
G01Y489474D02*
X-327008Y489557D01*
Y489724D01*
X-326841Y489807D01*
X-326674Y489724D01*
Y489557D01*
X-326841Y489474D01*
G01X-321241Y484807D02*
Y489807D01*
G01X-310541Y484807D02*
Y489057D01*
X-310374Y489474D01*
X-310041Y489724D01*
X-309541Y489807D01*
X-309041Y489640D01*
X-308791Y489224D01*
G01X-309791Y487807D02*
X-311458D01*
G01X-304441Y484807D02*
X-304941Y484890D01*
X-305441Y485224D01*
X-305774Y485807D01*
X-305941Y486474D01*
X-305774Y487140D01*
X-305441Y487724D01*
X-304941Y488057D01*
X-304441Y488140D01*
X-303941Y488057D01*
X-303441Y487724D01*
X-303108Y487140D01*
X-303024Y486474D01*
X-303108Y485807D01*
X-303441Y485224D01*
X-303941Y484890D01*
X-304441Y484807D01*
G01X-300008D02*
Y488140D01*
G01Y487474D02*
X-299591Y487807D01*
X-299174Y488057D01*
X-298591Y488140D01*
X-298174Y488057D01*
X-297674Y487807D01*
G01X-289308Y484807D02*
Y489807D01*
X-287308D01*
X-286641Y489557D01*
X-286141Y488974D01*
X-285974Y488307D01*
X-286141Y487640D01*
X-286558Y487140D01*
X-287308Y486890D01*
X-289308D01*
G01X-283208Y484807D02*
Y488140D01*
G01Y487474D02*
X-282791Y487807D01*
X-282374Y488057D01*
X-281791Y488140D01*
X-281374Y488057D01*
X-280874Y487807D01*
G01X-276441Y488140D02*
Y484807D01*
G01Y489474D02*
X-276608Y489557D01*
Y489724D01*
X-276441Y489807D01*
X-276274Y489724D01*
Y489557D01*
X-276441Y489474D01*
G01X-272258Y484807D02*
Y488140D01*
G01Y487307D02*
X-271924Y487724D01*
X-271424Y488057D01*
X-270758Y488140D01*
X-270174Y488057D01*
X-269674Y487724D01*
X-269424Y487140D01*
Y484807D01*
G01X-265241Y489807D02*
Y484807D01*
G01X-266408Y488140D02*
X-264074D01*
G01X-260891Y487057D02*
X-258224D01*
X-258474Y487640D01*
X-258891Y487974D01*
X-259474Y488140D01*
X-260058Y488057D01*
X-260558Y487807D01*
X-260891Y487224D01*
X-261058Y486724D01*
Y486224D01*
X-260891Y485724D01*
X-260474Y485224D01*
X-259974Y484890D01*
X-259391Y484807D01*
X-258808Y484974D01*
X-258224Y485474D01*
G01X-252541Y489807D02*
Y484807D01*
G01Y485557D02*
X-252874Y485140D01*
X-253374Y484890D01*
X-253958Y484807D01*
X-254624Y484974D01*
X-255124Y485390D01*
X-255458Y485890D01*
X-255541Y486474D01*
X-255458Y487057D01*
X-255124Y487557D01*
X-254624Y487974D01*
X-253958Y488140D01*
X-253374Y488057D01*
X-252958Y487890D01*
X-252541Y487557D01*
G01X-245341Y489807D02*
X-244174Y484807D01*
X-242841Y489807D01*
X-241508Y484807D01*
X-240341Y489807D01*
G01X-237241Y488140D02*
Y484807D01*
G01Y489474D02*
X-237408Y489557D01*
Y489724D01*
X-237241Y489807D01*
X-237074Y489724D01*
Y489557D01*
X-237241Y489474D01*
G01X-232808Y484807D02*
Y488140D01*
G01Y487474D02*
X-232391Y487807D01*
X-231974Y488057D01*
X-231391Y488140D01*
X-230974Y488057D01*
X-230474Y487807D01*
G01X-226041Y488140D02*
Y484807D01*
G01Y489474D02*
X-226208Y489557D01*
Y489724D01*
X-226041Y489807D01*
X-225874Y489724D01*
Y489557D01*
X-226041Y489474D01*
G01X-221858Y484807D02*
Y488140D01*
G01Y487307D02*
X-221524Y487724D01*
X-221024Y488057D01*
X-220358Y488140D01*
X-219774Y488057D01*
X-219274Y487724D01*
X-219024Y487140D01*
Y484807D01*
G01X-216008Y483557D02*
X-215424Y483224D01*
X-214758Y483140D01*
X-214174Y483224D01*
X-213674Y483640D01*
X-213341Y484224D01*
Y488140D01*
G01Y487474D02*
X-213674Y487807D01*
X-214174Y488057D01*
X-214758Y488140D01*
X-215424Y487974D01*
X-215841Y487640D01*
X-216174Y487057D01*
X-216341Y486474D01*
X-216258Y485974D01*
X-215924Y485390D01*
X-215424Y484974D01*
X-214758Y484807D01*
X-214258Y484890D01*
X-213674Y485224D01*
X-213341Y485557D01*
G01X-205724Y484807D02*
X-203641Y489807D01*
X-201558Y484807D01*
G01X-202308Y486557D02*
X-204974D01*
G01X-199541Y483140D02*
Y488140D01*
G01Y487390D02*
X-199124Y487807D01*
X-198708Y488057D01*
X-198041Y488140D01*
X-197458Y488057D01*
X-196874Y487640D01*
X-196624Y487057D01*
X-196541Y486474D01*
X-196624Y485890D01*
X-196874Y485307D01*
X-197374Y484974D01*
X-198041Y484807D01*
X-198624Y484890D01*
X-199208Y485140D01*
X-199541Y485474D01*
G01X-193941Y483140D02*
Y488140D01*
G01Y487390D02*
X-193524Y487807D01*
X-193108Y488057D01*
X-192441Y488140D01*
X-191858Y488057D01*
X-191274Y487640D01*
X-191024Y487057D01*
X-190941Y486474D01*
X-191024Y485890D01*
X-191274Y485307D01*
X-191774Y484974D01*
X-192441Y484807D01*
X-193024Y484890D01*
X-193608Y485140D01*
X-193941Y485474D01*
G01X-186841Y484807D02*
Y489807D01*
G01X-181241Y488140D02*
Y484807D01*
G01Y489474D02*
X-181408Y489557D01*
Y489724D01*
X-181241Y489807D01*
X-181074Y489724D01*
Y489557D01*
X-181241Y489474D01*
G01X-174308Y487724D02*
X-174891Y488057D01*
X-175391Y488140D01*
X-176058Y487974D01*
X-176558Y487640D01*
X-176891Y487057D01*
X-176974Y486474D01*
X-176891Y485890D01*
X-176558Y485390D01*
X-176058Y484974D01*
X-175391Y484807D01*
X-174808Y484974D01*
X-174308Y485307D01*
G01X-168541Y484807D02*
Y488140D01*
G01Y487557D02*
X-168874Y487890D01*
X-169374Y488057D01*
X-169958Y488140D01*
X-170541Y487974D01*
X-171041Y487640D01*
X-171374Y487140D01*
X-171541Y486474D01*
X-171374Y485807D01*
X-171041Y485307D01*
X-170541Y484974D01*
X-169958Y484807D01*
X-169374Y484890D01*
X-168874Y485140D01*
X-168541Y485474D01*
G01X-164441Y489807D02*
Y484807D01*
G01X-165608Y488140D02*
X-163274D01*
G01X-158841D02*
Y484807D01*
G01Y489474D02*
X-159008Y489557D01*
Y489724D01*
X-158841Y489807D01*
X-158674Y489724D01*
Y489557D01*
X-158841Y489474D01*
G01X-153241Y484807D02*
X-153741Y484890D01*
X-154241Y485224D01*
X-154574Y485807D01*
X-154741Y486474D01*
X-154574Y487140D01*
X-154241Y487724D01*
X-153741Y488057D01*
X-153241Y488140D01*
X-152741Y488057D01*
X-152241Y487724D01*
X-151908Y487140D01*
X-151824Y486474D01*
X-151908Y485807D01*
X-152241Y485224D01*
X-152741Y484890D01*
X-153241Y484807D01*
G01X-149058D02*
Y488140D01*
G01Y487307D02*
X-148724Y487724D01*
X-148224Y488057D01*
X-147558Y488140D01*
X-146974Y488057D01*
X-146474Y487724D01*
X-146224Y487140D01*
Y484807D01*
G01X-143291Y485390D02*
X-142874Y485057D01*
X-142291Y484807D01*
X-141791D01*
X-141291Y484974D01*
X-140958Y485224D01*
X-140791Y485557D01*
X-140874Y486057D01*
X-141208Y486307D01*
X-142708Y486807D01*
X-143041Y487390D01*
X-142874Y487807D01*
X-142541Y488057D01*
X-142041Y488140D01*
X-141541Y488057D01*
X-141041Y487807D01*
G01X-434241Y498807D02*
X-432241D01*
G01X-433241D02*
Y493807D01*
G01X-434241D02*
X-432241D01*
G01X-429308D02*
Y498807D01*
X-427308D01*
X-426641Y498557D01*
X-426141Y497974D01*
X-425974Y497307D01*
X-426141Y496640D01*
X-426558Y496140D01*
X-427308Y495890D01*
X-429308D01*
G01X-420208Y498390D02*
X-420708Y498640D01*
X-421291Y498807D01*
X-421958D01*
X-422708Y498557D01*
X-423291Y498140D01*
X-423708Y497640D01*
X-424041Y496807D01*
X-424124Y496057D01*
X-423958Y495307D01*
X-423708Y494807D01*
X-423208Y494307D01*
X-422624Y493974D01*
X-422041Y493807D01*
X-421458D01*
X-420874Y493974D01*
X-420374Y494224D01*
X-419958Y494557D01*
G01X-417524Y495474D02*
X-415358D01*
G01X-409841Y493807D02*
Y498807D01*
X-412924Y495224D01*
X-408758D01*
G01X-405241Y493807D02*
Y498807D01*
X-406241Y497807D01*
G01Y493807D02*
X-404241D01*
G01X-399641Y498807D02*
X-400308Y498640D01*
X-400808Y498224D01*
X-401141Y497724D01*
X-401391Y497057D01*
X-401474Y496307D01*
X-401391Y495557D01*
X-401141Y494890D01*
X-400808Y494390D01*
X-400308Y493974D01*
X-399641Y493807D01*
X-398974Y493974D01*
X-398474Y494390D01*
X-398141Y494890D01*
X-397891Y495557D01*
X-397808Y496307D01*
X-397891Y497057D01*
X-398141Y497724D01*
X-398474Y498224D01*
X-398974Y498640D01*
X-399641Y498807D01*
G01X-394041Y493807D02*
Y498807D01*
X-395041Y497807D01*
G01Y493807D02*
X-393041D01*
G01X-384591Y494474D02*
X-383924Y494057D01*
X-383174Y493807D01*
X-382508D01*
X-381841Y494057D01*
X-381341Y494474D01*
X-381091Y495057D01*
X-381258Y495640D01*
X-381674Y496140D01*
X-382424Y496474D01*
X-383424Y496640D01*
X-384008Y496974D01*
X-384258Y497557D01*
X-384091Y498140D01*
X-383674Y498557D01*
X-383091Y498807D01*
X-382508D01*
X-381924Y498640D01*
X-381424Y498224D01*
G01X-378741Y492140D02*
Y497140D01*
G01Y496390D02*
X-378324Y496807D01*
X-377908Y497057D01*
X-377241Y497140D01*
X-376658Y497057D01*
X-376074Y496640D01*
X-375824Y496057D01*
X-375741Y495474D01*
X-375824Y494890D01*
X-376074Y494307D01*
X-376574Y493974D01*
X-377241Y493807D01*
X-377824Y493890D01*
X-378408Y494140D01*
X-378741Y494474D01*
G01X-372891Y496057D02*
X-370224D01*
X-370474Y496640D01*
X-370891Y496974D01*
X-371474Y497140D01*
X-372058Y497057D01*
X-372558Y496807D01*
X-372891Y496224D01*
X-373058Y495724D01*
Y495224D01*
X-372891Y494724D01*
X-372474Y494224D01*
X-371974Y493890D01*
X-371391Y493807D01*
X-370808Y493974D01*
X-370224Y494474D01*
G01X-364708Y496724D02*
X-365291Y497057D01*
X-365791Y497140D01*
X-366458Y496974D01*
X-366958Y496640D01*
X-367291Y496057D01*
X-367374Y495474D01*
X-367291Y494890D01*
X-366958Y494390D01*
X-366458Y493974D01*
X-365791Y493807D01*
X-365208Y493974D01*
X-364708Y494307D01*
G01X-360441Y497140D02*
Y493807D01*
G01Y498474D02*
X-360608Y498557D01*
Y498724D01*
X-360441Y498807D01*
X-360274Y498724D01*
Y498557D01*
X-360441Y498474D01*
G01X-355341Y493807D02*
Y498057D01*
X-355174Y498474D01*
X-354841Y498724D01*
X-354341Y498807D01*
X-353841Y498640D01*
X-353591Y498224D01*
G01X-354591Y496807D02*
X-356258D01*
G01X-349241Y497140D02*
Y493807D01*
G01Y498474D02*
X-349408Y498557D01*
Y498724D01*
X-349241Y498807D01*
X-349074Y498724D01*
Y498557D01*
X-349241Y498474D01*
G01X-342308Y496724D02*
X-342891Y497057D01*
X-343391Y497140D01*
X-344058Y496974D01*
X-344558Y496640D01*
X-344891Y496057D01*
X-344974Y495474D01*
X-344891Y494890D01*
X-344558Y494390D01*
X-344058Y493974D01*
X-343391Y493807D01*
X-342808Y493974D01*
X-342308Y494307D01*
G01X-336541Y493807D02*
Y497140D01*
G01Y496557D02*
X-336874Y496890D01*
X-337374Y497057D01*
X-337958Y497140D01*
X-338541Y496974D01*
X-339041Y496640D01*
X-339374Y496140D01*
X-339541Y495474D01*
X-339374Y494807D01*
X-339041Y494307D01*
X-338541Y493974D01*
X-337958Y493807D01*
X-337374Y493890D01*
X-336874Y494140D01*
X-336541Y494474D01*
G01X-332441Y498807D02*
Y493807D01*
G01X-333608Y497140D02*
X-331274D01*
G01X-326841D02*
Y493807D01*
G01Y498474D02*
X-327008Y498557D01*
Y498724D01*
X-326841Y498807D01*
X-326674Y498724D01*
Y498557D01*
X-326841Y498474D01*
G01X-321241Y493807D02*
X-321741Y493890D01*
X-322241Y494224D01*
X-322574Y494807D01*
X-322741Y495474D01*
X-322574Y496140D01*
X-322241Y496724D01*
X-321741Y497057D01*
X-321241Y497140D01*
X-320741Y497057D01*
X-320241Y496724D01*
X-319908Y496140D01*
X-319824Y495474D01*
X-319908Y494807D01*
X-320241Y494224D01*
X-320741Y493890D01*
X-321241Y493807D01*
G01X-317058D02*
Y497140D01*
G01Y496307D02*
X-316724Y496724D01*
X-316224Y497057D01*
X-315558Y497140D01*
X-314974Y497057D01*
X-314474Y496724D01*
X-314224Y496140D01*
Y493807D01*
G01X-304941D02*
Y498057D01*
X-304774Y498474D01*
X-304441Y498724D01*
X-303941Y498807D01*
X-303441Y498640D01*
X-303191Y498224D01*
G01X-304191Y496807D02*
X-305858D01*
G01X-298841Y493807D02*
X-299341Y493890D01*
X-299841Y494224D01*
X-300174Y494807D01*
X-300341Y495474D01*
X-300174Y496140D01*
X-299841Y496724D01*
X-299341Y497057D01*
X-298841Y497140D01*
X-298341Y497057D01*
X-297841Y496724D01*
X-297508Y496140D01*
X-297424Y495474D01*
X-297508Y494807D01*
X-297841Y494224D01*
X-298341Y493890D01*
X-298841Y493807D01*
G01X-294408D02*
Y497140D01*
G01Y496474D02*
X-293991Y496807D01*
X-293574Y497057D01*
X-292991Y497140D01*
X-292574Y497057D01*
X-292074Y496807D01*
G01X-281374Y496474D02*
X-281041Y496724D01*
X-280791Y497140D01*
X-280624Y497724D01*
X-280791Y498224D01*
X-281124Y498557D01*
X-281708Y498807D01*
X-283958D01*
Y493807D01*
X-281208D01*
X-280624Y494140D01*
X-280291Y494640D01*
X-280124Y495224D01*
X-280291Y495807D01*
X-280791Y496307D01*
X-281374Y496474D01*
X-283958D01*
G01X-274941Y493807D02*
Y497140D01*
G01Y496557D02*
X-275274Y496890D01*
X-275774Y497057D01*
X-276358Y497140D01*
X-276941Y496974D01*
X-277441Y496640D01*
X-277774Y496140D01*
X-277941Y495474D01*
X-277774Y494807D01*
X-277441Y494307D01*
X-276941Y493974D01*
X-276358Y493807D01*
X-275774Y493890D01*
X-275274Y494140D01*
X-274941Y494474D01*
G01X-272091Y494390D02*
X-271674Y494057D01*
X-271091Y493807D01*
X-270591D01*
X-270091Y493974D01*
X-269758Y494224D01*
X-269591Y494557D01*
X-269674Y495057D01*
X-270008Y495307D01*
X-271508Y495807D01*
X-271841Y496390D01*
X-271674Y496807D01*
X-271341Y497057D01*
X-270841Y497140D01*
X-270341Y497057D01*
X-269841Y496807D01*
G01X-266491Y496057D02*
X-263824D01*
X-264074Y496640D01*
X-264491Y496974D01*
X-265074Y497140D01*
X-265658Y497057D01*
X-266158Y496807D01*
X-266491Y496224D01*
X-266658Y495724D01*
Y495224D01*
X-266491Y494724D01*
X-266074Y494224D01*
X-265574Y493890D01*
X-264991Y493807D01*
X-264408Y493974D01*
X-263824Y494474D01*
G01X-256208Y493807D02*
Y498807D01*
X-254041Y494640D01*
X-251874Y498807D01*
Y493807D01*
G01X-246941D02*
Y497140D01*
G01Y496557D02*
X-247274Y496890D01*
X-247774Y497057D01*
X-248358Y497140D01*
X-248941Y496974D01*
X-249441Y496640D01*
X-249774Y496140D01*
X-249941Y495474D01*
X-249774Y494807D01*
X-249441Y494307D01*
X-248941Y493974D01*
X-248358Y493807D01*
X-247774Y493890D01*
X-247274Y494140D01*
X-246941Y494474D01*
G01X-242841Y498807D02*
Y493807D01*
G01X-244008Y497140D02*
X-241674D01*
G01X-238491Y496057D02*
X-235824D01*
X-236074Y496640D01*
X-236491Y496974D01*
X-237074Y497140D01*
X-237658Y497057D01*
X-238158Y496807D01*
X-238491Y496224D01*
X-238658Y495724D01*
Y495224D01*
X-238491Y494724D01*
X-238074Y494224D01*
X-237574Y493890D01*
X-236991Y493807D01*
X-236408Y493974D01*
X-235824Y494474D01*
G01X-232808Y493807D02*
Y497140D01*
G01Y496474D02*
X-232391Y496807D01*
X-231974Y497057D01*
X-231391Y497140D01*
X-230974Y497057D01*
X-230474Y496807D01*
G01X-226041Y497140D02*
Y493807D01*
G01Y498474D02*
X-226208Y498557D01*
Y498724D01*
X-226041Y498807D01*
X-225874Y498724D01*
Y498557D01*
X-226041Y498474D01*
G01X-218941Y493807D02*
Y497140D01*
G01Y496557D02*
X-219274Y496890D01*
X-219774Y497057D01*
X-220358Y497140D01*
X-220941Y496974D01*
X-221441Y496640D01*
X-221774Y496140D01*
X-221941Y495474D01*
X-221774Y494807D01*
X-221441Y494307D01*
X-220941Y493974D01*
X-220358Y493807D01*
X-219774Y493890D01*
X-219274Y494140D01*
X-218941Y494474D01*
G01X-214841Y493807D02*
Y498807D01*
G01X-210491Y494390D02*
X-210074Y494057D01*
X-209491Y493807D01*
X-208991D01*
X-208491Y493974D01*
X-208158Y494224D01*
X-207991Y494557D01*
X-208074Y495057D01*
X-208408Y495307D01*
X-209908Y495807D01*
X-210241Y496390D01*
X-210074Y496807D01*
X-209741Y497057D01*
X-209241Y497140D01*
X-208741Y497057D01*
X-208241Y496807D01*
G01X-198541Y493807D02*
Y498057D01*
X-198374Y498474D01*
X-198041Y498724D01*
X-197541Y498807D01*
X-197041Y498640D01*
X-196791Y498224D01*
G01X-197791Y496807D02*
X-199458D01*
G01X-192441Y493807D02*
X-192941Y493890D01*
X-193441Y494224D01*
X-193774Y494807D01*
X-193941Y495474D01*
X-193774Y496140D01*
X-193441Y496724D01*
X-192941Y497057D01*
X-192441Y497140D01*
X-191941Y497057D01*
X-191441Y496724D01*
X-191108Y496140D01*
X-191024Y495474D01*
X-191108Y494807D01*
X-191441Y494224D01*
X-191941Y493890D01*
X-192441Y493807D01*
G01X-188008D02*
Y497140D01*
G01Y496474D02*
X-187591Y496807D01*
X-187174Y497057D01*
X-186591Y497140D01*
X-186174Y497057D01*
X-185674Y496807D01*
G01X-177308Y493807D02*
Y498807D01*
X-175224D01*
X-174558Y498557D01*
X-174141Y498224D01*
X-173974Y497557D01*
X-174141Y496890D01*
X-174641Y496474D01*
X-175224Y496224D01*
X-177308D01*
G01X-175224D02*
X-173974Y493807D01*
G01X-170041Y497140D02*
Y493807D01*
G01Y498474D02*
X-170208Y498557D01*
Y498724D01*
X-170041Y498807D01*
X-169874Y498724D01*
Y498557D01*
X-170041Y498474D01*
G01X-165608Y492557D02*
X-165024Y492224D01*
X-164358Y492140D01*
X-163774Y492224D01*
X-163274Y492640D01*
X-162941Y493224D01*
Y497140D01*
G01Y496474D02*
X-163274Y496807D01*
X-163774Y497057D01*
X-164358Y497140D01*
X-165024Y496974D01*
X-165441Y496640D01*
X-165774Y496057D01*
X-165941Y495474D01*
X-165858Y494974D01*
X-165524Y494390D01*
X-165024Y493974D01*
X-164358Y493807D01*
X-163858Y493890D01*
X-163274Y494224D01*
X-162941Y494557D01*
G01X-158841Y497140D02*
Y493807D01*
G01Y498474D02*
X-159008Y498557D01*
Y498724D01*
X-158841Y498807D01*
X-158674Y498724D01*
Y498557D01*
X-158841Y498474D01*
G01X-151741Y498807D02*
Y493807D01*
G01Y494557D02*
X-152074Y494140D01*
X-152574Y493890D01*
X-153158Y493807D01*
X-153824Y493974D01*
X-154324Y494390D01*
X-154658Y494890D01*
X-154741Y495474D01*
X-154658Y496057D01*
X-154324Y496557D01*
X-153824Y496974D01*
X-153158Y497140D01*
X-152574Y497057D01*
X-152158Y496890D01*
X-151741Y496557D01*
G01X-140541Y493807D02*
Y497140D01*
G01Y496557D02*
X-140874Y496890D01*
X-141374Y497057D01*
X-141958Y497140D01*
X-142541Y496974D01*
X-143041Y496640D01*
X-143374Y496140D01*
X-143541Y495474D01*
X-143374Y494807D01*
X-143041Y494307D01*
X-142541Y493974D01*
X-141958Y493807D01*
X-141374Y493890D01*
X-140874Y494140D01*
X-140541Y494474D01*
G01X-137858Y493807D02*
Y497140D01*
G01Y496307D02*
X-137524Y496724D01*
X-137024Y497057D01*
X-136358Y497140D01*
X-135774Y497057D01*
X-135274Y496724D01*
X-135024Y496140D01*
Y493807D01*
G01X-129341Y498807D02*
Y493807D01*
G01Y494557D02*
X-129674Y494140D01*
X-130174Y493890D01*
X-130758Y493807D01*
X-131424Y493974D01*
X-131924Y494390D01*
X-132258Y494890D01*
X-132341Y495474D01*
X-132258Y496057D01*
X-131924Y496557D01*
X-131424Y496974D01*
X-130758Y497140D01*
X-130174Y497057D01*
X-129758Y496890D01*
X-129341Y496557D01*
G01X-121808Y493807D02*
Y498807D01*
X-119641Y494640D01*
X-117474Y498807D01*
Y493807D01*
G01X-115458Y497140D02*
Y494807D01*
X-115124Y494224D01*
X-114624Y493890D01*
X-114041Y493807D01*
X-113458Y493890D01*
X-112958Y494224D01*
X-112624Y494807D01*
G01Y493807D02*
Y497140D01*
G01X-108441Y493807D02*
Y498807D01*
G01X-102841D02*
Y493807D01*
G01X-104008Y497140D02*
X-101674D01*
G01X-97241D02*
Y493807D01*
G01Y498474D02*
X-97408Y498557D01*
Y498724D01*
X-97241Y498807D01*
X-97074Y498724D01*
Y498557D01*
X-97241Y498474D01*
G01X-91641Y493807D02*
Y498807D01*
G01X-84541Y493807D02*
Y497140D01*
G01Y496557D02*
X-84874Y496890D01*
X-85374Y497057D01*
X-85958Y497140D01*
X-86541Y496974D01*
X-87041Y496640D01*
X-87374Y496140D01*
X-87541Y495474D01*
X-87374Y494807D01*
X-87041Y494307D01*
X-86541Y493974D01*
X-85958Y493807D01*
X-85374Y493890D01*
X-84874Y494140D01*
X-84541Y494474D01*
G01X-82191Y492307D02*
X-81691Y492140D01*
X-81024Y492307D01*
X-80608Y492640D01*
X-80274Y493057D01*
X-79774Y494390D01*
X-78691Y497140D01*
G01X-81358D02*
X-79774Y494390D01*
G01X-76091Y496057D02*
X-73424D01*
X-73674Y496640D01*
X-74091Y496974D01*
X-74674Y497140D01*
X-75258Y497057D01*
X-75758Y496807D01*
X-76091Y496224D01*
X-76258Y495724D01*
Y495224D01*
X-76091Y494724D01*
X-75674Y494224D01*
X-75174Y493890D01*
X-74591Y493807D01*
X-74008Y493974D01*
X-73424Y494474D01*
G01X-70408Y493807D02*
Y497140D01*
G01Y496474D02*
X-69991Y496807D01*
X-69574Y497057D01*
X-68991Y497140D01*
X-68574Y497057D01*
X-68074Y496807D01*
G01X-59708Y493807D02*
Y498807D01*
X-57708D01*
X-57041Y498557D01*
X-56541Y497974D01*
X-56374Y497307D01*
X-56541Y496640D01*
X-56958Y496140D01*
X-57708Y495890D01*
X-59708D01*
G01X-53608Y493807D02*
Y497140D01*
G01Y496474D02*
X-53191Y496807D01*
X-52774Y497057D01*
X-52191Y497140D01*
X-51774Y497057D01*
X-51274Y496807D01*
G01X-46841Y497140D02*
Y493807D01*
G01Y498474D02*
X-47008Y498557D01*
Y498724D01*
X-46841Y498807D01*
X-46674Y498724D01*
Y498557D01*
X-46841Y498474D01*
G01X-42658Y493807D02*
Y497140D01*
G01Y496307D02*
X-42324Y496724D01*
X-41824Y497057D01*
X-41158Y497140D01*
X-40574Y497057D01*
X-40074Y496724D01*
X-39824Y496140D01*
Y493807D01*
G01X-35641Y498807D02*
Y493807D01*
G01X-36808Y497140D02*
X-34474D01*
G01X-31291Y496057D02*
X-28624D01*
X-28874Y496640D01*
X-29291Y496974D01*
X-29874Y497140D01*
X-30458Y497057D01*
X-30958Y496807D01*
X-31291Y496224D01*
X-31458Y495724D01*
Y495224D01*
X-31291Y494724D01*
X-30874Y494224D01*
X-30374Y493890D01*
X-29791Y493807D01*
X-29208Y493974D01*
X-28624Y494474D01*
G01X-22941Y498807D02*
Y493807D01*
G01Y494557D02*
X-23274Y494140D01*
X-23774Y493890D01*
X-24358Y493807D01*
X-25024Y493974D01*
X-25524Y494390D01*
X-25858Y494890D01*
X-25941Y495474D01*
X-25858Y496057D01*
X-25524Y496557D01*
X-25024Y496974D01*
X-24358Y497140D01*
X-23774Y497057D01*
X-23358Y496890D01*
X-22941Y496557D01*
G01X-12574Y496474D02*
X-12241Y496724D01*
X-11991Y497140D01*
X-11824Y497724D01*
X-11991Y498224D01*
X-12324Y498557D01*
X-12908Y498807D01*
X-15158D01*
Y493807D01*
X-12408D01*
X-11824Y494140D01*
X-11491Y494640D01*
X-11324Y495224D01*
X-11491Y495807D01*
X-11991Y496307D01*
X-12574Y496474D01*
X-15158D01*
G01X-7641Y493807D02*
X-8141Y493890D01*
X-8641Y494224D01*
X-8974Y494807D01*
X-9141Y495474D01*
X-8974Y496140D01*
X-8641Y496724D01*
X-8141Y497057D01*
X-7641Y497140D01*
X-7141Y497057D01*
X-6641Y496724D01*
X-6308Y496140D01*
X-6224Y495474D01*
X-6308Y494807D01*
X-6641Y494224D01*
X-7141Y493890D01*
X-7641Y493807D01*
G01X-541D02*
Y497140D01*
G01Y496557D02*
X-874Y496890D01*
X-1374Y497057D01*
X-1958Y497140D01*
X-2541Y496974D01*
X-3041Y496640D01*
X-3374Y496140D01*
X-3541Y495474D01*
X-3374Y494807D01*
X-3041Y494307D01*
X-2541Y493974D01*
X-1958Y493807D01*
X-1374Y493890D01*
X-874Y494140D01*
X-541Y494474D01*
G01X2392Y493807D02*
Y497140D01*
G01Y496474D02*
X2809Y496807D01*
X3226Y497057D01*
X3809Y497140D01*
X4226Y497057D01*
X4726Y496807D01*
G01X10659Y498807D02*
Y493807D01*
G01Y494557D02*
X10326Y494140D01*
X9826Y493890D01*
X9242Y493807D01*
X8576Y493974D01*
X8076Y494390D01*
X7742Y494890D01*
X7659Y495474D01*
X7742Y496057D01*
X8076Y496557D01*
X8576Y496974D01*
X9242Y497140D01*
X9826Y497057D01*
X10242Y496890D01*
X10659Y496557D01*
G01X13509Y494390D02*
X13926Y494057D01*
X14509Y493807D01*
X15009D01*
X15509Y493974D01*
X15842Y494224D01*
X16009Y494557D01*
X15926Y495057D01*
X15592Y495307D01*
X14092Y495807D01*
X13759Y496390D01*
X13926Y496807D01*
X14259Y497057D01*
X14759Y497140D01*
X15259Y497057D01*
X15759Y496807D01*
G01X-434241Y507807D02*
X-432241D01*
G01X-433241D02*
Y502807D01*
G01X-434241D02*
X-432241D01*
G01X-429308D02*
Y507807D01*
X-427308D01*
X-426641Y507557D01*
X-426141Y506974D01*
X-425974Y506307D01*
X-426141Y505640D01*
X-426558Y505140D01*
X-427308Y504890D01*
X-429308D01*
G01X-420208Y507390D02*
X-420708Y507640D01*
X-421291Y507807D01*
X-421958D01*
X-422708Y507557D01*
X-423291Y507140D01*
X-423708Y506640D01*
X-424041Y505807D01*
X-424124Y505057D01*
X-423958Y504307D01*
X-423708Y503807D01*
X-423208Y503307D01*
X-422624Y502974D01*
X-422041Y502807D01*
X-421458D01*
X-420874Y502974D01*
X-420374Y503224D01*
X-419958Y503557D01*
G01X-417524Y504474D02*
X-415358D01*
G01X-410841Y507807D02*
Y502807D01*
G01X-412758Y507807D02*
X-408924D01*
G01X-407408Y502807D02*
Y507807D01*
X-405241Y503640D01*
X-403074Y507807D01*
Y502807D01*
G01X-400724Y504474D02*
X-398558D01*
G01X-395624Y504890D02*
X-395041Y505474D01*
X-394541Y505807D01*
X-393874Y505974D01*
X-393291Y505807D01*
X-392874Y505474D01*
X-392541Y504974D01*
X-392458Y504390D01*
X-392541Y503890D01*
X-392874Y503390D01*
X-393374Y502974D01*
X-393958Y502807D01*
X-394624Y502974D01*
X-395208Y503474D01*
X-395541Y504224D01*
X-395624Y505057D01*
X-395458Y506140D01*
X-395208Y506724D01*
X-394791Y507307D01*
X-394208Y507724D01*
X-393624Y507807D01*
X-393041Y507640D01*
X-392624Y507224D01*
G01X-390274Y503557D02*
X-389774Y503140D01*
X-389191Y502890D01*
X-388441Y502807D01*
X-387691Y502974D01*
X-387108Y503307D01*
X-386691Y503890D01*
X-386608Y504557D01*
X-386774Y505224D01*
X-387191Y505640D01*
X-387774Y505974D01*
X-388358Y506057D01*
X-388941Y505974D01*
X-389691Y505640D01*
X-389441Y507807D01*
X-387191D01*
G01X-382841D02*
X-383508Y507640D01*
X-384008Y507224D01*
X-384341Y506724D01*
X-384591Y506057D01*
X-384674Y505307D01*
X-384591Y504557D01*
X-384341Y503890D01*
X-384008Y503390D01*
X-383508Y502974D01*
X-382841Y502807D01*
X-382174Y502974D01*
X-381674Y503390D01*
X-381341Y503890D01*
X-381091Y504557D01*
X-381008Y505307D01*
X-381091Y506057D01*
X-381341Y506724D01*
X-381674Y507224D01*
X-382174Y507640D01*
X-382841Y507807D01*
G01X-371641D02*
Y502807D01*
G01X-373558Y507807D02*
X-369724D01*
G01X-367291Y505057D02*
X-364624D01*
X-364874Y505640D01*
X-365291Y505974D01*
X-365874Y506140D01*
X-366458Y506057D01*
X-366958Y505807D01*
X-367291Y505224D01*
X-367458Y504724D01*
Y504224D01*
X-367291Y503724D01*
X-366874Y503224D01*
X-366374Y502890D01*
X-365791Y502807D01*
X-365208Y502974D01*
X-364624Y503474D01*
G01X-361691Y503390D02*
X-361274Y503057D01*
X-360691Y502807D01*
X-360191D01*
X-359691Y502974D01*
X-359358Y503224D01*
X-359191Y503557D01*
X-359274Y504057D01*
X-359608Y504307D01*
X-361108Y504807D01*
X-361441Y505390D01*
X-361274Y505807D01*
X-360941Y506057D01*
X-360441Y506140D01*
X-359941Y506057D01*
X-359441Y505807D01*
G01X-354841Y507807D02*
Y502807D01*
G01X-356008Y506140D02*
X-353674D01*
G01X-345808Y502807D02*
Y507807D01*
X-343641Y503640D01*
X-341474Y507807D01*
Y502807D01*
G01X-339291Y505057D02*
X-336624D01*
X-336874Y505640D01*
X-337291Y505974D01*
X-337874Y506140D01*
X-338458Y506057D01*
X-338958Y505807D01*
X-339291Y505224D01*
X-339458Y504724D01*
Y504224D01*
X-339291Y503724D01*
X-338874Y503224D01*
X-338374Y502890D01*
X-337791Y502807D01*
X-337208Y502974D01*
X-336624Y503474D01*
G01X-332441Y507807D02*
Y502807D01*
G01X-333608Y506140D02*
X-331274D01*
G01X-328258Y502807D02*
Y507807D01*
G01Y505390D02*
X-327841Y505807D01*
X-327424Y506057D01*
X-326758Y506140D01*
X-326258Y506057D01*
X-325674Y505724D01*
X-325424Y505224D01*
Y502807D01*
G01X-321241D02*
X-321741Y502890D01*
X-322241Y503224D01*
X-322574Y503807D01*
X-322741Y504474D01*
X-322574Y505140D01*
X-322241Y505724D01*
X-321741Y506057D01*
X-321241Y506140D01*
X-320741Y506057D01*
X-320241Y505724D01*
X-319908Y505140D01*
X-319824Y504474D01*
X-319908Y503807D01*
X-320241Y503224D01*
X-320741Y502890D01*
X-321241Y502807D01*
G01X-314141Y507807D02*
Y502807D01*
G01Y503557D02*
X-314474Y503140D01*
X-314974Y502890D01*
X-315558Y502807D01*
X-316224Y502974D01*
X-316724Y503390D01*
X-317058Y503890D01*
X-317141Y504474D01*
X-317058Y505057D01*
X-316724Y505557D01*
X-316224Y505974D01*
X-315558Y506140D01*
X-314974Y506057D01*
X-314558Y505890D01*
X-314141Y505557D01*
G01X-311291Y503390D02*
X-310874Y503057D01*
X-310291Y502807D01*
X-309791D01*
X-309291Y502974D01*
X-308958Y503224D01*
X-308791Y503557D01*
X-308874Y504057D01*
X-309208Y504307D01*
X-310708Y504807D01*
X-311041Y505390D01*
X-310874Y505807D01*
X-310541Y506057D01*
X-310041Y506140D01*
X-309541Y506057D01*
X-309041Y505807D01*
G01X-301008Y502807D02*
Y507807D01*
X-298841Y503640D01*
X-296674Y507807D01*
Y502807D01*
G01X-291741D02*
Y506140D01*
G01Y505557D02*
X-292074Y505890D01*
X-292574Y506057D01*
X-293158Y506140D01*
X-293741Y505974D01*
X-294241Y505640D01*
X-294574Y505140D01*
X-294741Y504474D01*
X-294574Y503807D01*
X-294241Y503307D01*
X-293741Y502974D01*
X-293158Y502807D01*
X-292574Y502890D01*
X-292074Y503140D01*
X-291741Y503474D01*
G01X-289058Y502807D02*
Y506140D01*
G01Y505307D02*
X-288724Y505724D01*
X-288224Y506057D01*
X-287558Y506140D01*
X-286974Y506057D01*
X-286474Y505724D01*
X-286224Y505140D01*
Y502807D01*
G01X-283458Y506140D02*
Y503807D01*
X-283124Y503224D01*
X-282624Y502890D01*
X-282041Y502807D01*
X-281458Y502890D01*
X-280958Y503224D01*
X-280624Y503807D01*
G01Y502807D02*
Y506140D01*
G01X-274941Y502807D02*
Y506140D01*
G01Y505557D02*
X-275274Y505890D01*
X-275774Y506057D01*
X-276358Y506140D01*
X-276941Y505974D01*
X-277441Y505640D01*
X-277774Y505140D01*
X-277941Y504474D01*
X-277774Y503807D01*
X-277441Y503307D01*
X-276941Y502974D01*
X-276358Y502807D01*
X-275774Y502890D01*
X-275274Y503140D01*
X-274941Y503474D01*
G01X-270841Y502807D02*
Y507807D01*
G01X-434241Y516807D02*
X-432241D01*
G01X-433241D02*
Y511807D01*
G01X-434241D02*
X-432241D01*
G01X-429308D02*
Y516807D01*
X-427308D01*
X-426641Y516557D01*
X-426141Y515974D01*
X-425974Y515307D01*
X-426141Y514640D01*
X-426558Y514140D01*
X-427308Y513890D01*
X-429308D01*
G01X-420208Y516390D02*
X-420708Y516640D01*
X-421291Y516807D01*
X-421958D01*
X-422708Y516557D01*
X-423291Y516140D01*
X-423708Y515640D01*
X-424041Y514807D01*
X-424124Y514057D01*
X-423958Y513307D01*
X-423708Y512807D01*
X-423208Y512307D01*
X-422624Y511974D01*
X-422041Y511807D01*
X-421458D01*
X-420874Y511974D01*
X-420374Y512224D01*
X-419958Y512557D01*
G01X-417524Y513474D02*
X-415358D01*
G01X-412424Y513890D02*
X-411841Y514474D01*
X-411341Y514807D01*
X-410674Y514974D01*
X-410091Y514807D01*
X-409674Y514474D01*
X-409341Y513974D01*
X-409258Y513390D01*
X-409341Y512890D01*
X-409674Y512390D01*
X-410174Y511974D01*
X-410758Y511807D01*
X-411424Y511974D01*
X-412008Y512474D01*
X-412341Y513224D01*
X-412424Y514057D01*
X-412258Y515140D01*
X-412008Y515724D01*
X-411591Y516307D01*
X-411008Y516724D01*
X-410424Y516807D01*
X-409841Y516640D01*
X-409424Y516224D01*
G01X-405241Y516807D02*
X-405908Y516640D01*
X-406408Y516224D01*
X-406741Y515724D01*
X-406991Y515057D01*
X-407074Y514307D01*
X-406991Y513557D01*
X-406741Y512890D01*
X-406408Y512390D01*
X-405908Y511974D01*
X-405241Y511807D01*
X-404574Y511974D01*
X-404074Y512390D01*
X-403741Y512890D01*
X-403491Y513557D01*
X-403408Y514307D01*
X-403491Y515057D01*
X-403741Y515724D01*
X-404074Y516224D01*
X-404574Y516640D01*
X-405241Y516807D01*
G01X-399641Y511807D02*
Y516807D01*
X-400641Y515807D01*
G01Y511807D02*
X-398641D01*
G01X-395624Y513890D02*
X-395041Y514474D01*
X-394541Y514807D01*
X-393874Y514974D01*
X-393291Y514807D01*
X-392874Y514474D01*
X-392541Y513974D01*
X-392458Y513390D01*
X-392541Y512890D01*
X-392874Y512390D01*
X-393374Y511974D01*
X-393958Y511807D01*
X-394624Y511974D01*
X-395208Y512474D01*
X-395541Y513224D01*
X-395624Y514057D01*
X-395458Y515140D01*
X-395208Y515724D01*
X-394791Y516307D01*
X-394208Y516724D01*
X-393624Y516807D01*
X-393041Y516640D01*
X-392624Y516224D01*
G01X-382841Y511807D02*
X-383508Y511890D01*
X-384091Y512224D01*
X-384591Y512724D01*
X-384924Y513307D01*
X-385091Y513974D01*
Y514640D01*
X-384924Y515307D01*
X-384591Y515890D01*
X-384091Y516390D01*
X-383508Y516724D01*
X-382841Y516807D01*
X-382174Y516724D01*
X-381591Y516390D01*
X-381091Y515890D01*
X-380758Y515307D01*
X-380591Y514640D01*
Y513974D01*
X-380758Y513307D01*
X-381091Y512724D01*
X-381591Y512224D01*
X-382174Y511890D01*
X-382841Y511807D01*
G01X-382174Y513140D02*
X-381174Y511807D01*
G01X-378658Y515140D02*
Y512807D01*
X-378324Y512224D01*
X-377824Y511890D01*
X-377241Y511807D01*
X-376658Y511890D01*
X-376158Y512224D01*
X-375824Y512807D01*
G01Y511807D02*
Y515140D01*
G01X-370141Y511807D02*
Y515140D01*
G01Y514557D02*
X-370474Y514890D01*
X-370974Y515057D01*
X-371558Y515140D01*
X-372141Y514974D01*
X-372641Y514640D01*
X-372974Y514140D01*
X-373141Y513474D01*
X-372974Y512807D01*
X-372641Y512307D01*
X-372141Y511974D01*
X-371558Y511807D01*
X-370974Y511890D01*
X-370474Y512140D01*
X-370141Y512474D01*
G01X-366041Y511807D02*
Y516807D01*
G01X-360441Y515140D02*
Y511807D01*
G01Y516474D02*
X-360608Y516557D01*
Y516724D01*
X-360441Y516807D01*
X-360274Y516724D01*
Y516557D01*
X-360441Y516474D01*
G01X-355341Y511807D02*
Y516057D01*
X-355174Y516474D01*
X-354841Y516724D01*
X-354341Y516807D01*
X-353841Y516640D01*
X-353591Y516224D01*
G01X-354591Y514807D02*
X-356258D01*
G01X-349241Y515140D02*
Y511807D01*
G01Y516474D02*
X-349408Y516557D01*
Y516724D01*
X-349241Y516807D01*
X-349074Y516724D01*
Y516557D01*
X-349241Y516474D01*
G01X-342308Y514724D02*
X-342891Y515057D01*
X-343391Y515140D01*
X-344058Y514974D01*
X-344558Y514640D01*
X-344891Y514057D01*
X-344974Y513474D01*
X-344891Y512890D01*
X-344558Y512390D01*
X-344058Y511974D01*
X-343391Y511807D01*
X-342808Y511974D01*
X-342308Y512307D01*
G01X-336541Y511807D02*
Y515140D01*
G01Y514557D02*
X-336874Y514890D01*
X-337374Y515057D01*
X-337958Y515140D01*
X-338541Y514974D01*
X-339041Y514640D01*
X-339374Y514140D01*
X-339541Y513474D01*
X-339374Y512807D01*
X-339041Y512307D01*
X-338541Y511974D01*
X-337958Y511807D01*
X-337374Y511890D01*
X-336874Y512140D01*
X-336541Y512474D01*
G01X-332441Y516807D02*
Y511807D01*
G01X-333608Y515140D02*
X-331274D01*
G01X-326841D02*
Y511807D01*
G01Y516474D02*
X-327008Y516557D01*
Y516724D01*
X-326841Y516807D01*
X-326674Y516724D01*
Y516557D01*
X-326841Y516474D01*
G01X-321241Y511807D02*
X-321741Y511890D01*
X-322241Y512224D01*
X-322574Y512807D01*
X-322741Y513474D01*
X-322574Y514140D01*
X-322241Y514724D01*
X-321741Y515057D01*
X-321241Y515140D01*
X-320741Y515057D01*
X-320241Y514724D01*
X-319908Y514140D01*
X-319824Y513474D01*
X-319908Y512807D01*
X-320241Y512224D01*
X-320741Y511890D01*
X-321241Y511807D01*
G01X-317058D02*
Y515140D01*
G01Y514307D02*
X-316724Y514724D01*
X-316224Y515057D01*
X-315558Y515140D01*
X-314974Y515057D01*
X-314474Y514724D01*
X-314224Y514140D01*
Y511807D01*
G01X-301941Y510140D02*
X-306108Y515140D01*
Y515974D01*
X-305274Y516807D01*
X-304441D01*
X-303608Y515974D01*
Y515140D01*
X-304441Y514307D01*
X-306108Y513474D01*
X-306941Y512640D01*
Y510974D01*
X-306108Y510140D01*
X-303608D01*
X-301941Y511807D01*
G01X-294908D02*
Y516807D01*
X-292908D01*
X-292241Y516557D01*
X-291741Y515974D01*
X-291574Y515307D01*
X-291741Y514640D01*
X-292158Y514140D01*
X-292908Y513890D01*
X-294908D01*
G01X-288891Y514057D02*
X-286224D01*
X-286474Y514640D01*
X-286891Y514974D01*
X-287474Y515140D01*
X-288058Y515057D01*
X-288558Y514807D01*
X-288891Y514224D01*
X-289058Y513724D01*
Y513224D01*
X-288891Y512724D01*
X-288474Y512224D01*
X-287974Y511890D01*
X-287391Y511807D01*
X-286808Y511974D01*
X-286224Y512474D01*
G01X-283208Y511807D02*
Y515140D01*
G01Y514474D02*
X-282791Y514807D01*
X-282374Y515057D01*
X-281791Y515140D01*
X-281374Y515057D01*
X-280874Y514807D01*
G01X-276941Y511807D02*
Y516057D01*
X-276774Y516474D01*
X-276441Y516724D01*
X-275941Y516807D01*
X-275441Y516640D01*
X-275191Y516224D01*
G01X-276191Y514807D02*
X-277858D01*
G01X-270841Y511807D02*
X-271341Y511890D01*
X-271841Y512224D01*
X-272174Y512807D01*
X-272341Y513474D01*
X-272174Y514140D01*
X-271841Y514724D01*
X-271341Y515057D01*
X-270841Y515140D01*
X-270341Y515057D01*
X-269841Y514724D01*
X-269508Y514140D01*
X-269424Y513474D01*
X-269508Y512807D01*
X-269841Y512224D01*
X-270341Y511890D01*
X-270841Y511807D01*
G01X-266408D02*
Y515140D01*
G01Y514474D02*
X-265991Y514807D01*
X-265574Y515057D01*
X-264991Y515140D01*
X-264574Y515057D01*
X-264074Y514807D01*
G01X-262141Y511807D02*
Y515140D01*
G01Y514224D02*
X-261891Y514640D01*
X-261474Y514974D01*
X-260891Y515140D01*
X-260308Y514974D01*
X-259891Y514640D01*
X-259641Y514224D01*
Y511807D01*
G01Y514224D02*
X-259391Y514640D01*
X-258974Y514974D01*
X-258391Y515140D01*
X-257808Y514974D01*
X-257391Y514640D01*
X-257141Y514140D01*
Y511807D01*
G01X-252541D02*
Y515140D01*
G01Y514557D02*
X-252874Y514890D01*
X-253374Y515057D01*
X-253958Y515140D01*
X-254541Y514974D01*
X-255041Y514640D01*
X-255374Y514140D01*
X-255541Y513474D01*
X-255374Y512807D01*
X-255041Y512307D01*
X-254541Y511974D01*
X-253958Y511807D01*
X-253374Y511890D01*
X-252874Y512140D01*
X-252541Y512474D01*
G01X-249858Y511807D02*
Y515140D01*
G01Y514307D02*
X-249524Y514724D01*
X-249024Y515057D01*
X-248358Y515140D01*
X-247774Y515057D01*
X-247274Y514724D01*
X-247024Y514140D01*
Y511807D01*
G01X-241508Y514724D02*
X-242091Y515057D01*
X-242591Y515140D01*
X-243258Y514974D01*
X-243758Y514640D01*
X-244091Y514057D01*
X-244174Y513474D01*
X-244091Y512890D01*
X-243758Y512390D01*
X-243258Y511974D01*
X-242591Y511807D01*
X-242008Y511974D01*
X-241508Y512307D01*
G01X-238491Y514057D02*
X-235824D01*
X-236074Y514640D01*
X-236491Y514974D01*
X-237074Y515140D01*
X-237658Y515057D01*
X-238158Y514807D01*
X-238491Y514224D01*
X-238658Y513724D01*
Y513224D01*
X-238491Y512724D01*
X-238074Y512224D01*
X-237574Y511890D01*
X-236991Y511807D01*
X-236408Y511974D01*
X-235824Y512474D01*
G01X-227791D02*
X-227124Y512057D01*
X-226374Y511807D01*
X-225708D01*
X-225041Y512057D01*
X-224541Y512474D01*
X-224291Y513057D01*
X-224458Y513640D01*
X-224874Y514140D01*
X-225624Y514474D01*
X-226624Y514640D01*
X-227208Y514974D01*
X-227458Y515557D01*
X-227291Y516140D01*
X-226874Y516557D01*
X-226291Y516807D01*
X-225708D01*
X-225124Y516640D01*
X-224624Y516224D01*
G01X-221941Y510140D02*
Y515140D01*
G01Y514390D02*
X-221524Y514807D01*
X-221108Y515057D01*
X-220441Y515140D01*
X-219858Y515057D01*
X-219274Y514640D01*
X-219024Y514057D01*
X-218941Y513474D01*
X-219024Y512890D01*
X-219274Y512307D01*
X-219774Y511974D01*
X-220441Y511807D01*
X-221024Y511890D01*
X-221608Y512140D01*
X-221941Y512474D01*
G01X-216091Y514057D02*
X-213424D01*
X-213674Y514640D01*
X-214091Y514974D01*
X-214674Y515140D01*
X-215258Y515057D01*
X-215758Y514807D01*
X-216091Y514224D01*
X-216258Y513724D01*
Y513224D01*
X-216091Y512724D01*
X-215674Y512224D01*
X-215174Y511890D01*
X-214591Y511807D01*
X-214008Y511974D01*
X-213424Y512474D01*
G01X-207908Y514724D02*
X-208491Y515057D01*
X-208991Y515140D01*
X-209658Y514974D01*
X-210158Y514640D01*
X-210491Y514057D01*
X-210574Y513474D01*
X-210491Y512890D01*
X-210158Y512390D01*
X-209658Y511974D01*
X-208991Y511807D01*
X-208408Y511974D01*
X-207908Y512307D01*
G01X-203641Y515140D02*
Y511807D01*
G01Y516474D02*
X-203808Y516557D01*
Y516724D01*
X-203641Y516807D01*
X-203474Y516724D01*
Y516557D01*
X-203641Y516474D01*
G01X-198541Y511807D02*
Y516057D01*
X-198374Y516474D01*
X-198041Y516724D01*
X-197541Y516807D01*
X-197041Y516640D01*
X-196791Y516224D01*
G01X-197791Y514807D02*
X-199458D01*
G01X-192441Y515140D02*
Y511807D01*
G01Y516474D02*
X-192608Y516557D01*
Y516724D01*
X-192441Y516807D01*
X-192274Y516724D01*
Y516557D01*
X-192441Y516474D01*
G01X-185508Y514724D02*
X-186091Y515057D01*
X-186591Y515140D01*
X-187258Y514974D01*
X-187758Y514640D01*
X-188091Y514057D01*
X-188174Y513474D01*
X-188091Y512890D01*
X-187758Y512390D01*
X-187258Y511974D01*
X-186591Y511807D01*
X-186008Y511974D01*
X-185508Y512307D01*
G01X-179741Y511807D02*
Y515140D01*
G01Y514557D02*
X-180074Y514890D01*
X-180574Y515057D01*
X-181158Y515140D01*
X-181741Y514974D01*
X-182241Y514640D01*
X-182574Y514140D01*
X-182741Y513474D01*
X-182574Y512807D01*
X-182241Y512307D01*
X-181741Y511974D01*
X-181158Y511807D01*
X-180574Y511890D01*
X-180074Y512140D01*
X-179741Y512474D01*
G01X-175641Y516807D02*
Y511807D01*
G01X-176808Y515140D02*
X-174474D01*
G01X-170041D02*
Y511807D01*
G01Y516474D02*
X-170208Y516557D01*
Y516724D01*
X-170041Y516807D01*
X-169874Y516724D01*
Y516557D01*
X-170041Y516474D01*
G01X-164441Y511807D02*
X-164941Y511890D01*
X-165441Y512224D01*
X-165774Y512807D01*
X-165941Y513474D01*
X-165774Y514140D01*
X-165441Y514724D01*
X-164941Y515057D01*
X-164441Y515140D01*
X-163941Y515057D01*
X-163441Y514724D01*
X-163108Y514140D01*
X-163024Y513474D01*
X-163108Y512807D01*
X-163441Y512224D01*
X-163941Y511890D01*
X-164441Y511807D01*
G01X-160258D02*
Y515140D01*
G01Y514307D02*
X-159924Y514724D01*
X-159424Y515057D01*
X-158758Y515140D01*
X-158174Y515057D01*
X-157674Y514724D01*
X-157424Y514140D01*
Y511807D01*
G01X-148141D02*
Y516057D01*
X-147974Y516474D01*
X-147641Y516724D01*
X-147141Y516807D01*
X-146641Y516640D01*
X-146391Y516224D01*
G01X-147391Y514807D02*
X-149058D01*
G01X-142041Y511807D02*
X-142541Y511890D01*
X-143041Y512224D01*
X-143374Y512807D01*
X-143541Y513474D01*
X-143374Y514140D01*
X-143041Y514724D01*
X-142541Y515057D01*
X-142041Y515140D01*
X-141541Y515057D01*
X-141041Y514724D01*
X-140708Y514140D01*
X-140624Y513474D01*
X-140708Y512807D01*
X-141041Y512224D01*
X-141541Y511890D01*
X-142041Y511807D01*
G01X-137608D02*
Y515140D01*
G01Y514474D02*
X-137191Y514807D01*
X-136774Y515057D01*
X-136191Y515140D01*
X-135774Y515057D01*
X-135274Y514807D01*
G01X-126991Y511807D02*
Y516807D01*
G01X-123491D02*
Y511807D01*
G01Y514307D02*
X-126991D01*
G01X-119641Y515140D02*
Y511807D01*
G01Y516474D02*
X-119808Y516557D01*
Y516724D01*
X-119641Y516807D01*
X-119474Y516724D01*
Y516557D01*
X-119641Y516474D01*
G01X-115208Y510557D02*
X-114624Y510224D01*
X-113958Y510140D01*
X-113374Y510224D01*
X-112874Y510640D01*
X-112541Y511224D01*
Y515140D01*
G01Y514474D02*
X-112874Y514807D01*
X-113374Y515057D01*
X-113958Y515140D01*
X-114624Y514974D01*
X-115041Y514640D01*
X-115374Y514057D01*
X-115541Y513474D01*
X-115458Y512974D01*
X-115124Y512390D01*
X-114624Y511974D01*
X-113958Y511807D01*
X-113458Y511890D01*
X-112874Y512224D01*
X-112541Y512557D01*
G01X-109858Y511807D02*
Y516807D01*
G01Y514390D02*
X-109441Y514807D01*
X-109024Y515057D01*
X-108358Y515140D01*
X-107858Y515057D01*
X-107274Y514724D01*
X-107024Y514224D01*
Y511807D01*
G01X-99074D02*
Y516807D01*
X-97408D01*
X-96741Y516557D01*
X-96241Y516224D01*
X-95824Y515724D01*
X-95491Y515140D01*
X-95408Y514307D01*
X-95491Y513474D01*
X-95824Y512890D01*
X-96241Y512390D01*
X-96741Y512057D01*
X-97408Y511807D01*
X-99074D01*
G01X-92891Y514057D02*
X-90224D01*
X-90474Y514640D01*
X-90891Y514974D01*
X-91474Y515140D01*
X-92058Y515057D01*
X-92558Y514807D01*
X-92891Y514224D01*
X-93058Y513724D01*
Y513224D01*
X-92891Y512724D01*
X-92474Y512224D01*
X-91974Y511890D01*
X-91391Y511807D01*
X-90808Y511974D01*
X-90224Y512474D01*
G01X-87458Y511807D02*
Y515140D01*
G01Y514307D02*
X-87124Y514724D01*
X-86624Y515057D01*
X-85958Y515140D01*
X-85374Y515057D01*
X-84874Y514724D01*
X-84624Y514140D01*
Y511807D01*
G01X-81691Y512390D02*
X-81274Y512057D01*
X-80691Y511807D01*
X-80191D01*
X-79691Y511974D01*
X-79358Y512224D01*
X-79191Y512557D01*
X-79274Y513057D01*
X-79608Y513307D01*
X-81108Y513807D01*
X-81441Y514390D01*
X-81274Y514807D01*
X-80941Y515057D01*
X-80441Y515140D01*
X-79941Y515057D01*
X-79441Y514807D01*
G01X-74841Y515140D02*
Y511807D01*
G01Y516474D02*
X-75008Y516557D01*
Y516724D01*
X-74841Y516807D01*
X-74674Y516724D01*
Y516557D01*
X-74841Y516474D01*
G01X-69241Y516807D02*
Y511807D01*
G01X-70408Y515140D02*
X-68074D01*
G01X-65391Y510307D02*
X-64891Y510140D01*
X-64224Y510307D01*
X-63808Y510640D01*
X-63474Y511057D01*
X-62974Y512390D01*
X-61891Y515140D01*
G01X-64558D02*
X-62974Y512390D01*
G01X-53441Y516807D02*
X-51441D01*
G01X-52441D02*
Y511807D01*
G01X-53441D02*
X-51441D01*
G01X-48258D02*
Y515140D01*
G01Y514307D02*
X-47924Y514724D01*
X-47424Y515057D01*
X-46758Y515140D01*
X-46174Y515057D01*
X-45674Y514724D01*
X-45424Y514140D01*
Y511807D01*
G01X-41241Y516807D02*
Y511807D01*
G01X-42408Y515140D02*
X-40074D01*
G01X-36891Y514057D02*
X-34224D01*
X-34474Y514640D01*
X-34891Y514974D01*
X-35474Y515140D01*
X-36058Y515057D01*
X-36558Y514807D01*
X-36891Y514224D01*
X-37058Y513724D01*
Y513224D01*
X-36891Y512724D01*
X-36474Y512224D01*
X-35974Y511890D01*
X-35391Y511807D01*
X-34808Y511974D01*
X-34224Y512474D01*
G01X-31208Y511807D02*
Y515140D01*
G01Y514474D02*
X-30791Y514807D01*
X-30374Y515057D01*
X-29791Y515140D01*
X-29374Y515057D01*
X-28874Y514807D01*
G01X-23108Y514724D02*
X-23691Y515057D01*
X-24191Y515140D01*
X-24858Y514974D01*
X-25358Y514640D01*
X-25691Y514057D01*
X-25774Y513474D01*
X-25691Y512890D01*
X-25358Y512390D01*
X-24858Y511974D01*
X-24191Y511807D01*
X-23608Y511974D01*
X-23108Y512307D01*
G01X-18841Y511807D02*
X-19341Y511890D01*
X-19841Y512224D01*
X-20174Y512807D01*
X-20341Y513474D01*
X-20174Y514140D01*
X-19841Y514724D01*
X-19341Y515057D01*
X-18841Y515140D01*
X-18341Y515057D01*
X-17841Y514724D01*
X-17508Y514140D01*
X-17424Y513474D01*
X-17508Y512807D01*
X-17841Y512224D01*
X-18341Y511890D01*
X-18841Y511807D01*
G01X-14658D02*
Y515140D01*
G01Y514307D02*
X-14324Y514724D01*
X-13824Y515057D01*
X-13158Y515140D01*
X-12574Y515057D01*
X-12074Y514724D01*
X-11824Y514140D01*
Y511807D01*
G01X-9058D02*
Y515140D01*
G01Y514307D02*
X-8724Y514724D01*
X-8224Y515057D01*
X-7558Y515140D01*
X-6974Y515057D01*
X-6474Y514724D01*
X-6224Y514140D01*
Y511807D01*
G01X-3291Y514057D02*
X-624D01*
X-874Y514640D01*
X-1291Y514974D01*
X-1874Y515140D01*
X-2458Y515057D01*
X-2958Y514807D01*
X-3291Y514224D01*
X-3458Y513724D01*
Y513224D01*
X-3291Y512724D01*
X-2874Y512224D01*
X-2374Y511890D01*
X-1791Y511807D01*
X-1208Y511974D01*
X-624Y512474D01*
G01X4892Y514724D02*
X4309Y515057D01*
X3809Y515140D01*
X3142Y514974D01*
X2642Y514640D01*
X2309Y514057D01*
X2226Y513474D01*
X2309Y512890D01*
X2642Y512390D01*
X3142Y511974D01*
X3809Y511807D01*
X4392Y511974D01*
X4892Y512307D01*
G01X9159Y516807D02*
Y511807D01*
G01X7992Y515140D02*
X10326D01*
G01X14342Y510140D02*
X13509Y510974D01*
X13092Y511807D01*
Y515140D01*
X13509Y515974D01*
X14342Y516807D01*
G01X18609Y511807D02*
Y516807D01*
G01X22109D02*
Y511807D01*
G01Y514307D02*
X18609D01*
G01X24126Y511807D02*
Y516807D01*
X25792D01*
X26459Y516557D01*
X26959Y516224D01*
X27376Y515724D01*
X27709Y515140D01*
X27792Y514307D01*
X27709Y513474D01*
X27376Y512890D01*
X26959Y512390D01*
X26459Y512057D01*
X25792Y511807D01*
X24126D01*
G01X30559Y516807D02*
X32559D01*
G01X31559D02*
Y511807D01*
G01X30559D02*
X32559D01*
G01X37576Y510140D02*
X38409Y510974D01*
X38826Y511807D01*
Y515140D01*
X38409Y515974D01*
X37576Y516807D01*
G01X46692D02*
Y511807D01*
X50026D01*
G01X55459D02*
Y515140D01*
G01Y514557D02*
X55126Y514890D01*
X54626Y515057D01*
X54042Y515140D01*
X53459Y514974D01*
X52959Y514640D01*
X52626Y514140D01*
X52459Y513474D01*
X52626Y512807D01*
X52959Y512307D01*
X53459Y511974D01*
X54042Y511807D01*
X54626Y511890D01*
X55126Y512140D01*
X55459Y512474D01*
G01X57809Y510307D02*
X58309Y510140D01*
X58976Y510307D01*
X59392Y510640D01*
X59726Y511057D01*
X60226Y512390D01*
X61309Y515140D01*
G01X58642D02*
X60226Y512390D01*
G01X63909Y514057D02*
X66576D01*
X66326Y514640D01*
X65909Y514974D01*
X65326Y515140D01*
X64742Y515057D01*
X64242Y514807D01*
X63909Y514224D01*
X63742Y513724D01*
Y513224D01*
X63909Y512724D01*
X64326Y512224D01*
X64826Y511890D01*
X65409Y511807D01*
X65992Y511974D01*
X66576Y512474D01*
G01X69592Y511807D02*
Y515140D01*
G01Y514474D02*
X70009Y514807D01*
X70426Y515057D01*
X71009Y515140D01*
X71426Y515057D01*
X71926Y514807D01*
G01X75109Y512390D02*
X75526Y512057D01*
X76109Y511807D01*
X76609D01*
X77109Y511974D01*
X77442Y512224D01*
X77609Y512557D01*
X77526Y513057D01*
X77192Y513307D01*
X75692Y513807D01*
X75359Y514390D01*
X75526Y514807D01*
X75859Y515057D01*
X76359Y515140D01*
X76859Y515057D01*
X77359Y514807D01*
G01X87559Y511807D02*
X87059Y511890D01*
X86559Y512224D01*
X86226Y512807D01*
X86059Y513474D01*
X86226Y514140D01*
X86559Y514724D01*
X87059Y515057D01*
X87559Y515140D01*
X88059Y515057D01*
X88559Y514724D01*
X88892Y514140D01*
X88976Y513474D01*
X88892Y512807D01*
X88559Y512224D01*
X88059Y511890D01*
X87559Y511807D01*
G01X91992D02*
Y515140D01*
G01Y514474D02*
X92409Y514807D01*
X92826Y515057D01*
X93409Y515140D01*
X93826Y515057D01*
X94326Y514807D01*
G01X105026Y514474D02*
X105359Y514724D01*
X105609Y515140D01*
X105776Y515724D01*
X105609Y516224D01*
X105276Y516557D01*
X104692Y516807D01*
X102442D01*
Y511807D01*
X105192D01*
X105776Y512140D01*
X106109Y512640D01*
X106276Y513224D01*
X106109Y513807D01*
X105609Y514307D01*
X105026Y514474D01*
X102442D01*
G01X109959Y511807D02*
X109459Y511890D01*
X108959Y512224D01*
X108626Y512807D01*
X108459Y513474D01*
X108626Y514140D01*
X108959Y514724D01*
X109459Y515057D01*
X109959Y515140D01*
X110459Y515057D01*
X110959Y514724D01*
X111292Y514140D01*
X111376Y513474D01*
X111292Y512807D01*
X110959Y512224D01*
X110459Y511890D01*
X109959Y511807D01*
G01X117059D02*
Y515140D01*
G01Y514557D02*
X116726Y514890D01*
X116226Y515057D01*
X115642Y515140D01*
X115059Y514974D01*
X114559Y514640D01*
X114226Y514140D01*
X114059Y513474D01*
X114226Y512807D01*
X114559Y512307D01*
X115059Y511974D01*
X115642Y511807D01*
X116226Y511890D01*
X116726Y512140D01*
X117059Y512474D01*
G01X119992Y511807D02*
Y515140D01*
G01Y514474D02*
X120409Y514807D01*
X120826Y515057D01*
X121409Y515140D01*
X121826Y515057D01*
X122326Y514807D01*
G01X128259Y516807D02*
Y511807D01*
G01Y512557D02*
X127926Y512140D01*
X127426Y511890D01*
X126842Y511807D01*
X126176Y511974D01*
X125676Y512390D01*
X125342Y512890D01*
X125259Y513474D01*
X125342Y514057D01*
X125676Y514557D01*
X126176Y514974D01*
X126842Y515140D01*
X127426Y515057D01*
X127842Y514890D01*
X128259Y514557D01*
G01X131109Y512390D02*
X131526Y512057D01*
X132109Y511807D01*
X132609D01*
X133109Y511974D01*
X133442Y512224D01*
X133609Y512557D01*
X133526Y513057D01*
X133192Y513307D01*
X131692Y513807D01*
X131359Y514390D01*
X131526Y514807D01*
X131859Y515057D01*
X132359Y515140D01*
X132859Y515057D01*
X133359Y514807D01*
G01X138376Y510140D02*
X139209Y510974D01*
X139626Y511807D01*
Y515140D01*
X139209Y515974D01*
X138376Y516807D01*
G01X-434241Y525807D02*
X-432241D01*
G01X-433241D02*
Y520807D01*
G01X-434241D02*
X-432241D01*
G01X-429308D02*
Y525807D01*
X-427308D01*
X-426641Y525557D01*
X-426141Y524974D01*
X-425974Y524307D01*
X-426141Y523640D01*
X-426558Y523140D01*
X-427308Y522890D01*
X-429308D01*
G01X-420208Y525390D02*
X-420708Y525640D01*
X-421291Y525807D01*
X-421958D01*
X-422708Y525557D01*
X-423291Y525140D01*
X-423708Y524640D01*
X-424041Y523807D01*
X-424124Y523057D01*
X-423958Y522307D01*
X-423708Y521807D01*
X-423208Y521307D01*
X-422624Y520974D01*
X-422041Y520807D01*
X-421458D01*
X-420874Y520974D01*
X-420374Y521224D01*
X-419958Y521557D01*
G01X-417524Y522474D02*
X-415358D01*
G01X-412424Y522890D02*
X-411841Y523474D01*
X-411341Y523807D01*
X-410674Y523974D01*
X-410091Y523807D01*
X-409674Y523474D01*
X-409341Y522974D01*
X-409258Y522390D01*
X-409341Y521890D01*
X-409674Y521390D01*
X-410174Y520974D01*
X-410758Y520807D01*
X-411424Y520974D01*
X-412008Y521474D01*
X-412341Y522224D01*
X-412424Y523057D01*
X-412258Y524140D01*
X-412008Y524724D01*
X-411591Y525307D01*
X-411008Y525724D01*
X-410424Y525807D01*
X-409841Y525640D01*
X-409424Y525224D01*
G01X-405241Y525807D02*
X-405908Y525640D01*
X-406408Y525224D01*
X-406741Y524724D01*
X-406991Y524057D01*
X-407074Y523307D01*
X-406991Y522557D01*
X-406741Y521890D01*
X-406408Y521390D01*
X-405908Y520974D01*
X-405241Y520807D01*
X-404574Y520974D01*
X-404074Y521390D01*
X-403741Y521890D01*
X-403491Y522557D01*
X-403408Y523307D01*
X-403491Y524057D01*
X-403741Y524724D01*
X-404074Y525224D01*
X-404574Y525640D01*
X-405241Y525807D01*
G01X-399641Y520807D02*
Y525807D01*
X-400641Y524807D01*
G01Y520807D02*
X-398641D01*
G01X-395624Y524974D02*
X-395124Y525474D01*
X-394541Y525724D01*
X-393874Y525807D01*
X-393041Y525640D01*
X-392458Y525224D01*
X-392291Y524724D01*
X-392374Y524224D01*
X-392708Y523807D01*
X-394374Y522974D01*
X-395124Y522390D01*
X-395624Y521557D01*
X-395791Y520807D01*
X-392291D01*
G01X-382841D02*
X-383508Y520890D01*
X-384091Y521224D01*
X-384591Y521724D01*
X-384924Y522307D01*
X-385091Y522974D01*
Y523640D01*
X-384924Y524307D01*
X-384591Y524890D01*
X-384091Y525390D01*
X-383508Y525724D01*
X-382841Y525807D01*
X-382174Y525724D01*
X-381591Y525390D01*
X-381091Y524890D01*
X-380758Y524307D01*
X-380591Y523640D01*
Y522974D01*
X-380758Y522307D01*
X-381091Y521724D01*
X-381591Y521224D01*
X-382174Y520890D01*
X-382841Y520807D01*
G01X-382174Y522140D02*
X-381174Y520807D01*
G01X-378658Y524140D02*
Y521807D01*
X-378324Y521224D01*
X-377824Y520890D01*
X-377241Y520807D01*
X-376658Y520890D01*
X-376158Y521224D01*
X-375824Y521807D01*
G01Y520807D02*
Y524140D01*
G01X-370141Y520807D02*
Y524140D01*
G01Y523557D02*
X-370474Y523890D01*
X-370974Y524057D01*
X-371558Y524140D01*
X-372141Y523974D01*
X-372641Y523640D01*
X-372974Y523140D01*
X-373141Y522474D01*
X-372974Y521807D01*
X-372641Y521307D01*
X-372141Y520974D01*
X-371558Y520807D01*
X-370974Y520890D01*
X-370474Y521140D01*
X-370141Y521474D01*
G01X-366041Y520807D02*
Y525807D01*
G01X-360441Y524140D02*
Y520807D01*
G01Y525474D02*
X-360608Y525557D01*
Y525724D01*
X-360441Y525807D01*
X-360274Y525724D01*
Y525557D01*
X-360441Y525474D01*
G01X-355341Y520807D02*
Y525057D01*
X-355174Y525474D01*
X-354841Y525724D01*
X-354341Y525807D01*
X-353841Y525640D01*
X-353591Y525224D01*
G01X-354591Y523807D02*
X-356258D01*
G01X-349241Y524140D02*
Y520807D01*
G01Y525474D02*
X-349408Y525557D01*
Y525724D01*
X-349241Y525807D01*
X-349074Y525724D01*
Y525557D01*
X-349241Y525474D01*
G01X-342308Y523724D02*
X-342891Y524057D01*
X-343391Y524140D01*
X-344058Y523974D01*
X-344558Y523640D01*
X-344891Y523057D01*
X-344974Y522474D01*
X-344891Y521890D01*
X-344558Y521390D01*
X-344058Y520974D01*
X-343391Y520807D01*
X-342808Y520974D01*
X-342308Y521307D01*
G01X-336541Y520807D02*
Y524140D01*
G01Y523557D02*
X-336874Y523890D01*
X-337374Y524057D01*
X-337958Y524140D01*
X-338541Y523974D01*
X-339041Y523640D01*
X-339374Y523140D01*
X-339541Y522474D01*
X-339374Y521807D01*
X-339041Y521307D01*
X-338541Y520974D01*
X-337958Y520807D01*
X-337374Y520890D01*
X-336874Y521140D01*
X-336541Y521474D01*
G01X-332441Y525807D02*
Y520807D01*
G01X-333608Y524140D02*
X-331274D01*
G01X-326841D02*
Y520807D01*
G01Y525474D02*
X-327008Y525557D01*
Y525724D01*
X-326841Y525807D01*
X-326674Y525724D01*
Y525557D01*
X-326841Y525474D01*
G01X-321241Y520807D02*
X-321741Y520890D01*
X-322241Y521224D01*
X-322574Y521807D01*
X-322741Y522474D01*
X-322574Y523140D01*
X-322241Y523724D01*
X-321741Y524057D01*
X-321241Y524140D01*
X-320741Y524057D01*
X-320241Y523724D01*
X-319908Y523140D01*
X-319824Y522474D01*
X-319908Y521807D01*
X-320241Y521224D01*
X-320741Y520890D01*
X-321241Y520807D01*
G01X-317058D02*
Y524140D01*
G01Y523307D02*
X-316724Y523724D01*
X-316224Y524057D01*
X-315558Y524140D01*
X-314974Y524057D01*
X-314474Y523724D01*
X-314224Y523140D01*
Y520807D01*
G01X-302941D02*
Y524140D01*
G01Y523557D02*
X-303274Y523890D01*
X-303774Y524057D01*
X-304358Y524140D01*
X-304941Y523974D01*
X-305441Y523640D01*
X-305774Y523140D01*
X-305941Y522474D01*
X-305774Y521807D01*
X-305441Y521307D01*
X-304941Y520974D01*
X-304358Y520807D01*
X-303774Y520890D01*
X-303274Y521140D01*
X-302941Y521474D01*
G01X-300258Y520807D02*
Y524140D01*
G01Y523307D02*
X-299924Y523724D01*
X-299424Y524057D01*
X-298758Y524140D01*
X-298174Y524057D01*
X-297674Y523724D01*
X-297424Y523140D01*
Y520807D01*
G01X-291741Y525807D02*
Y520807D01*
G01Y521557D02*
X-292074Y521140D01*
X-292574Y520890D01*
X-293158Y520807D01*
X-293824Y520974D01*
X-294324Y521390D01*
X-294658Y521890D01*
X-294741Y522474D01*
X-294658Y523057D01*
X-294324Y523557D01*
X-293824Y523974D01*
X-293158Y524140D01*
X-292574Y524057D01*
X-292158Y523890D01*
X-291741Y523557D01*
G01X-283708Y520807D02*
Y525807D01*
X-281708D01*
X-281041Y525557D01*
X-280541Y524974D01*
X-280374Y524307D01*
X-280541Y523640D01*
X-280958Y523140D01*
X-281708Y522890D01*
X-283708D01*
G01X-277691Y523057D02*
X-275024D01*
X-275274Y523640D01*
X-275691Y523974D01*
X-276274Y524140D01*
X-276858Y524057D01*
X-277358Y523807D01*
X-277691Y523224D01*
X-277858Y522724D01*
Y522224D01*
X-277691Y521724D01*
X-277274Y521224D01*
X-276774Y520890D01*
X-276191Y520807D01*
X-275608Y520974D01*
X-275024Y521474D01*
G01X-272008Y520807D02*
Y524140D01*
G01Y523474D02*
X-271591Y523807D01*
X-271174Y524057D01*
X-270591Y524140D01*
X-270174Y524057D01*
X-269674Y523807D01*
G01X-265741Y520807D02*
Y525057D01*
X-265574Y525474D01*
X-265241Y525724D01*
X-264741Y525807D01*
X-264241Y525640D01*
X-263991Y525224D01*
G01X-264991Y523807D02*
X-266658D01*
G01X-259641Y520807D02*
X-260141Y520890D01*
X-260641Y521224D01*
X-260974Y521807D01*
X-261141Y522474D01*
X-260974Y523140D01*
X-260641Y523724D01*
X-260141Y524057D01*
X-259641Y524140D01*
X-259141Y524057D01*
X-258641Y523724D01*
X-258308Y523140D01*
X-258224Y522474D01*
X-258308Y521807D01*
X-258641Y521224D01*
X-259141Y520890D01*
X-259641Y520807D01*
G01X-255208D02*
Y524140D01*
G01Y523474D02*
X-254791Y523807D01*
X-254374Y524057D01*
X-253791Y524140D01*
X-253374Y524057D01*
X-252874Y523807D01*
G01X-250941Y520807D02*
Y524140D01*
G01Y523224D02*
X-250691Y523640D01*
X-250274Y523974D01*
X-249691Y524140D01*
X-249108Y523974D01*
X-248691Y523640D01*
X-248441Y523224D01*
Y520807D01*
G01Y523224D02*
X-248191Y523640D01*
X-247774Y523974D01*
X-247191Y524140D01*
X-246608Y523974D01*
X-246191Y523640D01*
X-245941Y523140D01*
Y520807D01*
G01X-241341D02*
Y524140D01*
G01Y523557D02*
X-241674Y523890D01*
X-242174Y524057D01*
X-242758Y524140D01*
X-243341Y523974D01*
X-243841Y523640D01*
X-244174Y523140D01*
X-244341Y522474D01*
X-244174Y521807D01*
X-243841Y521307D01*
X-243341Y520974D01*
X-242758Y520807D01*
X-242174Y520890D01*
X-241674Y521140D01*
X-241341Y521474D01*
G01X-238658Y520807D02*
Y524140D01*
G01Y523307D02*
X-238324Y523724D01*
X-237824Y524057D01*
X-237158Y524140D01*
X-236574Y524057D01*
X-236074Y523724D01*
X-235824Y523140D01*
Y520807D01*
G01X-230308Y523724D02*
X-230891Y524057D01*
X-231391Y524140D01*
X-232058Y523974D01*
X-232558Y523640D01*
X-232891Y523057D01*
X-232974Y522474D01*
X-232891Y521890D01*
X-232558Y521390D01*
X-232058Y520974D01*
X-231391Y520807D01*
X-230808Y520974D01*
X-230308Y521307D01*
G01X-227291Y523057D02*
X-224624D01*
X-224874Y523640D01*
X-225291Y523974D01*
X-225874Y524140D01*
X-226458Y524057D01*
X-226958Y523807D01*
X-227291Y523224D01*
X-227458Y522724D01*
Y522224D01*
X-227291Y521724D01*
X-226874Y521224D01*
X-226374Y520890D01*
X-225791Y520807D01*
X-225208Y520974D01*
X-224624Y521474D01*
G01X-216591D02*
X-215924Y521057D01*
X-215174Y520807D01*
X-214508D01*
X-213841Y521057D01*
X-213341Y521474D01*
X-213091Y522057D01*
X-213258Y522640D01*
X-213674Y523140D01*
X-214424Y523474D01*
X-215424Y523640D01*
X-216008Y523974D01*
X-216258Y524557D01*
X-216091Y525140D01*
X-215674Y525557D01*
X-215091Y525807D01*
X-214508D01*
X-213924Y525640D01*
X-213424Y525224D01*
G01X-210741Y519140D02*
Y524140D01*
G01Y523390D02*
X-210324Y523807D01*
X-209908Y524057D01*
X-209241Y524140D01*
X-208658Y524057D01*
X-208074Y523640D01*
X-207824Y523057D01*
X-207741Y522474D01*
X-207824Y521890D01*
X-208074Y521307D01*
X-208574Y520974D01*
X-209241Y520807D01*
X-209824Y520890D01*
X-210408Y521140D01*
X-210741Y521474D01*
G01X-204891Y523057D02*
X-202224D01*
X-202474Y523640D01*
X-202891Y523974D01*
X-203474Y524140D01*
X-204058Y524057D01*
X-204558Y523807D01*
X-204891Y523224D01*
X-205058Y522724D01*
Y522224D01*
X-204891Y521724D01*
X-204474Y521224D01*
X-203974Y520890D01*
X-203391Y520807D01*
X-202808Y520974D01*
X-202224Y521474D01*
G01X-196708Y523724D02*
X-197291Y524057D01*
X-197791Y524140D01*
X-198458Y523974D01*
X-198958Y523640D01*
X-199291Y523057D01*
X-199374Y522474D01*
X-199291Y521890D01*
X-198958Y521390D01*
X-198458Y520974D01*
X-197791Y520807D01*
X-197208Y520974D01*
X-196708Y521307D01*
G01X-192441Y524140D02*
Y520807D01*
G01Y525474D02*
X-192608Y525557D01*
Y525724D01*
X-192441Y525807D01*
X-192274Y525724D01*
Y525557D01*
X-192441Y525474D01*
G01X-187341Y520807D02*
Y525057D01*
X-187174Y525474D01*
X-186841Y525724D01*
X-186341Y525807D01*
X-185841Y525640D01*
X-185591Y525224D01*
G01X-186591Y523807D02*
X-188258D01*
G01X-181241Y524140D02*
Y520807D01*
G01Y525474D02*
X-181408Y525557D01*
Y525724D01*
X-181241Y525807D01*
X-181074Y525724D01*
Y525557D01*
X-181241Y525474D01*
G01X-174308Y523724D02*
X-174891Y524057D01*
X-175391Y524140D01*
X-176058Y523974D01*
X-176558Y523640D01*
X-176891Y523057D01*
X-176974Y522474D01*
X-176891Y521890D01*
X-176558Y521390D01*
X-176058Y520974D01*
X-175391Y520807D01*
X-174808Y520974D01*
X-174308Y521307D01*
G01X-168541Y520807D02*
Y524140D01*
G01Y523557D02*
X-168874Y523890D01*
X-169374Y524057D01*
X-169958Y524140D01*
X-170541Y523974D01*
X-171041Y523640D01*
X-171374Y523140D01*
X-171541Y522474D01*
X-171374Y521807D01*
X-171041Y521307D01*
X-170541Y520974D01*
X-169958Y520807D01*
X-169374Y520890D01*
X-168874Y521140D01*
X-168541Y521474D01*
G01X-164441Y525807D02*
Y520807D01*
G01X-165608Y524140D02*
X-163274D01*
G01X-158841D02*
Y520807D01*
G01Y525474D02*
X-159008Y525557D01*
Y525724D01*
X-158841Y525807D01*
X-158674Y525724D01*
Y525557D01*
X-158841Y525474D01*
G01X-153241Y520807D02*
X-153741Y520890D01*
X-154241Y521224D01*
X-154574Y521807D01*
X-154741Y522474D01*
X-154574Y523140D01*
X-154241Y523724D01*
X-153741Y524057D01*
X-153241Y524140D01*
X-152741Y524057D01*
X-152241Y523724D01*
X-151908Y523140D01*
X-151824Y522474D01*
X-151908Y521807D01*
X-152241Y521224D01*
X-152741Y520890D01*
X-153241Y520807D01*
G01X-149058D02*
Y524140D01*
G01Y523307D02*
X-148724Y523724D01*
X-148224Y524057D01*
X-147558Y524140D01*
X-146974Y524057D01*
X-146474Y523724D01*
X-146224Y523140D01*
Y520807D01*
G01X-136941D02*
Y525057D01*
X-136774Y525474D01*
X-136441Y525724D01*
X-135941Y525807D01*
X-135441Y525640D01*
X-135191Y525224D01*
G01X-136191Y523807D02*
X-137858D01*
G01X-130841Y520807D02*
X-131341Y520890D01*
X-131841Y521224D01*
X-132174Y521807D01*
X-132341Y522474D01*
X-132174Y523140D01*
X-131841Y523724D01*
X-131341Y524057D01*
X-130841Y524140D01*
X-130341Y524057D01*
X-129841Y523724D01*
X-129508Y523140D01*
X-129424Y522474D01*
X-129508Y521807D01*
X-129841Y521224D01*
X-130341Y520890D01*
X-130841Y520807D01*
G01X-126408D02*
Y524140D01*
G01Y523474D02*
X-125991Y523807D01*
X-125574Y524057D01*
X-124991Y524140D01*
X-124574Y524057D01*
X-124074Y523807D01*
G01X-115708Y520807D02*
Y525807D01*
X-113624D01*
X-112958Y525557D01*
X-112541Y525224D01*
X-112374Y524557D01*
X-112541Y523890D01*
X-113041Y523474D01*
X-113624Y523224D01*
X-115708D01*
G01X-113624D02*
X-112374Y520807D01*
G01X-108441Y524140D02*
Y520807D01*
G01Y525474D02*
X-108608Y525557D01*
Y525724D01*
X-108441Y525807D01*
X-108274Y525724D01*
Y525557D01*
X-108441Y525474D01*
G01X-104008Y519557D02*
X-103424Y519224D01*
X-102758Y519140D01*
X-102174Y519224D01*
X-101674Y519640D01*
X-101341Y520224D01*
Y524140D01*
G01Y523474D02*
X-101674Y523807D01*
X-102174Y524057D01*
X-102758Y524140D01*
X-103424Y523974D01*
X-103841Y523640D01*
X-104174Y523057D01*
X-104341Y522474D01*
X-104258Y521974D01*
X-103924Y521390D01*
X-103424Y520974D01*
X-102758Y520807D01*
X-102258Y520890D01*
X-101674Y521224D01*
X-101341Y521557D01*
G01X-97241Y524140D02*
Y520807D01*
G01Y525474D02*
X-97408Y525557D01*
Y525724D01*
X-97241Y525807D01*
X-97074Y525724D01*
Y525557D01*
X-97241Y525474D01*
G01X-90141Y525807D02*
Y520807D01*
G01Y521557D02*
X-90474Y521140D01*
X-90974Y520890D01*
X-91558Y520807D01*
X-92224Y520974D01*
X-92724Y521390D01*
X-93058Y521890D01*
X-93141Y522474D01*
X-93058Y523057D01*
X-92724Y523557D01*
X-92224Y523974D01*
X-91558Y524140D01*
X-90974Y524057D01*
X-90558Y523890D01*
X-90141Y523557D01*
G01X-82108Y520807D02*
Y525807D01*
X-80108D01*
X-79441Y525557D01*
X-78941Y524974D01*
X-78774Y524307D01*
X-78941Y523640D01*
X-79358Y523140D01*
X-80108Y522890D01*
X-82108D01*
G01X-76008Y520807D02*
Y524140D01*
G01Y523474D02*
X-75591Y523807D01*
X-75174Y524057D01*
X-74591Y524140D01*
X-74174Y524057D01*
X-73674Y523807D01*
G01X-69241Y524140D02*
Y520807D01*
G01Y525474D02*
X-69408Y525557D01*
Y525724D01*
X-69241Y525807D01*
X-69074Y525724D01*
Y525557D01*
X-69241Y525474D01*
G01X-65058Y520807D02*
Y524140D01*
G01Y523307D02*
X-64724Y523724D01*
X-64224Y524057D01*
X-63558Y524140D01*
X-62974Y524057D01*
X-62474Y523724D01*
X-62224Y523140D01*
Y520807D01*
G01X-58041Y525807D02*
Y520807D01*
G01X-59208Y524140D02*
X-56874D01*
G01X-53691Y523057D02*
X-51024D01*
X-51274Y523640D01*
X-51691Y523974D01*
X-52274Y524140D01*
X-52858Y524057D01*
X-53358Y523807D01*
X-53691Y523224D01*
X-53858Y522724D01*
Y522224D01*
X-53691Y521724D01*
X-53274Y521224D01*
X-52774Y520890D01*
X-52191Y520807D01*
X-51608Y520974D01*
X-51024Y521474D01*
G01X-45341Y525807D02*
Y520807D01*
G01Y521557D02*
X-45674Y521140D01*
X-46174Y520890D01*
X-46758Y520807D01*
X-47424Y520974D01*
X-47924Y521390D01*
X-48258Y521890D01*
X-48341Y522474D01*
X-48258Y523057D01*
X-47924Y523557D01*
X-47424Y523974D01*
X-46758Y524140D01*
X-46174Y524057D01*
X-45758Y523890D01*
X-45341Y523557D01*
G01X-34974Y523474D02*
X-34641Y523724D01*
X-34391Y524140D01*
X-34224Y524724D01*
X-34391Y525224D01*
X-34724Y525557D01*
X-35308Y525807D01*
X-37558D01*
Y520807D01*
X-34808D01*
X-34224Y521140D01*
X-33891Y521640D01*
X-33724Y522224D01*
X-33891Y522807D01*
X-34391Y523307D01*
X-34974Y523474D01*
X-37558D01*
G01X-30041Y520807D02*
X-30541Y520890D01*
X-31041Y521224D01*
X-31374Y521807D01*
X-31541Y522474D01*
X-31374Y523140D01*
X-31041Y523724D01*
X-30541Y524057D01*
X-30041Y524140D01*
X-29541Y524057D01*
X-29041Y523724D01*
X-28708Y523140D01*
X-28624Y522474D01*
X-28708Y521807D01*
X-29041Y521224D01*
X-29541Y520890D01*
X-30041Y520807D01*
G01X-22941D02*
Y524140D01*
G01Y523557D02*
X-23274Y523890D01*
X-23774Y524057D01*
X-24358Y524140D01*
X-24941Y523974D01*
X-25441Y523640D01*
X-25774Y523140D01*
X-25941Y522474D01*
X-25774Y521807D01*
X-25441Y521307D01*
X-24941Y520974D01*
X-24358Y520807D01*
X-23774Y520890D01*
X-23274Y521140D01*
X-22941Y521474D01*
G01X-20008Y520807D02*
Y524140D01*
G01Y523474D02*
X-19591Y523807D01*
X-19174Y524057D01*
X-18591Y524140D01*
X-18174Y524057D01*
X-17674Y523807D01*
G01X-11741Y525807D02*
Y520807D01*
G01Y521557D02*
X-12074Y521140D01*
X-12574Y520890D01*
X-13158Y520807D01*
X-13824Y520974D01*
X-14324Y521390D01*
X-14658Y521890D01*
X-14741Y522474D01*
X-14658Y523057D01*
X-14324Y523557D01*
X-13824Y523974D01*
X-13158Y524140D01*
X-12574Y524057D01*
X-12158Y523890D01*
X-11741Y523557D01*
G01X-8891Y521390D02*
X-8474Y521057D01*
X-7891Y520807D01*
X-7391D01*
X-6891Y520974D01*
X-6558Y521224D01*
X-6391Y521557D01*
X-6474Y522057D01*
X-6808Y522307D01*
X-8308Y522807D01*
X-8641Y523390D01*
X-8474Y523807D01*
X-8141Y524057D01*
X-7641Y524140D01*
X-7141Y524057D01*
X-6641Y523807D01*
G01X-438241Y485640D02*
X-438408Y485724D01*
Y485890D01*
X-438241Y485974D01*
X-438074Y485890D01*
Y485724D01*
X-438241Y485640D01*
G01Y476640D02*
X-438408Y476724D01*
Y476890D01*
X-438241Y476974D01*
X-438074Y476890D01*
Y476724D01*
X-438241Y476640D01*
G01X-448241Y553707D02*
X-446241D01*
G01X-447241D02*
Y548707D01*
G01X-448241D02*
X-446241D01*
G01X-442141D02*
Y552957D01*
X-441974Y553374D01*
X-441641Y553624D01*
X-441141Y553707D01*
X-440641Y553540D01*
X-440391Y553124D01*
G01X-441391Y551707D02*
X-443058D01*
G01X-430441Y553707D02*
Y548707D01*
G01X-431608Y552040D02*
X-429274D01*
G01X-426258Y548707D02*
Y553707D01*
G01Y551290D02*
X-425841Y551707D01*
X-425424Y551957D01*
X-424758Y552040D01*
X-424258Y551957D01*
X-423674Y551624D01*
X-423424Y551124D01*
Y548707D01*
G01X-420491Y550957D02*
X-417824D01*
X-418074Y551540D01*
X-418491Y551874D01*
X-419074Y552040D01*
X-419658Y551957D01*
X-420158Y551707D01*
X-420491Y551124D01*
X-420658Y550624D01*
Y550124D01*
X-420491Y549624D01*
X-420074Y549124D01*
X-419574Y548790D01*
X-418991Y548707D01*
X-418408Y548874D01*
X-417824Y549374D01*
G01X-406708Y551624D02*
X-407291Y551957D01*
X-407791Y552040D01*
X-408458Y551874D01*
X-408958Y551540D01*
X-409291Y550957D01*
X-409374Y550374D01*
X-409291Y549790D01*
X-408958Y549290D01*
X-408458Y548874D01*
X-407791Y548707D01*
X-407208Y548874D01*
X-406708Y549207D01*
G01X-403608Y548707D02*
Y552040D01*
G01Y551374D02*
X-403191Y551707D01*
X-402774Y551957D01*
X-402191Y552040D01*
X-401774Y551957D01*
X-401274Y551707D01*
G01X-396841Y552040D02*
Y548707D01*
G01Y553374D02*
X-397008Y553457D01*
Y553624D01*
X-396841Y553707D01*
X-396674Y553624D01*
Y553457D01*
X-396841Y553374D01*
G01X-391241Y553707D02*
Y548707D01*
G01X-392408Y552040D02*
X-390074D01*
G01X-386891Y550957D02*
X-384224D01*
X-384474Y551540D01*
X-384891Y551874D01*
X-385474Y552040D01*
X-386058Y551957D01*
X-386558Y551707D01*
X-386891Y551124D01*
X-387058Y550624D01*
Y550124D01*
X-386891Y549624D01*
X-386474Y549124D01*
X-385974Y548790D01*
X-385391Y548707D01*
X-384808Y548874D01*
X-384224Y549374D01*
G01X-381208Y548707D02*
Y552040D01*
G01Y551374D02*
X-380791Y551707D01*
X-380374Y551957D01*
X-379791Y552040D01*
X-379374Y551957D01*
X-378874Y551707D01*
G01X-374441Y552040D02*
Y548707D01*
G01Y553374D02*
X-374608Y553457D01*
Y553624D01*
X-374441Y553707D01*
X-374274Y553624D01*
Y553457D01*
X-374441Y553374D01*
G01X-367341Y548707D02*
Y552040D01*
G01Y551457D02*
X-367674Y551790D01*
X-368174Y551957D01*
X-368758Y552040D01*
X-369341Y551874D01*
X-369841Y551540D01*
X-370174Y551040D01*
X-370341Y550374D01*
X-370174Y549707D01*
X-369841Y549207D01*
X-369341Y548874D01*
X-368758Y548707D01*
X-368174Y548790D01*
X-367674Y549040D01*
X-367341Y549374D01*
G01X-357641Y552040D02*
Y548707D01*
G01Y553374D02*
X-357808Y553457D01*
Y553624D01*
X-357641Y553707D01*
X-357474Y553624D01*
Y553457D01*
X-357641Y553374D01*
G01X-353291Y549290D02*
X-352874Y548957D01*
X-352291Y548707D01*
X-351791D01*
X-351291Y548874D01*
X-350958Y549124D01*
X-350791Y549457D01*
X-350874Y549957D01*
X-351208Y550207D01*
X-352708Y550707D01*
X-353041Y551290D01*
X-352874Y551707D01*
X-352541Y551957D01*
X-352041Y552040D01*
X-351541Y551957D01*
X-351041Y551707D01*
G01X-342258Y548707D02*
Y552040D01*
G01Y551207D02*
X-341924Y551624D01*
X-341424Y551957D01*
X-340758Y552040D01*
X-340174Y551957D01*
X-339674Y551624D01*
X-339424Y551040D01*
Y548707D01*
G01X-335241D02*
X-335741Y548790D01*
X-336241Y549124D01*
X-336574Y549707D01*
X-336741Y550374D01*
X-336574Y551040D01*
X-336241Y551624D01*
X-335741Y551957D01*
X-335241Y552040D01*
X-334741Y551957D01*
X-334241Y551624D01*
X-333908Y551040D01*
X-333824Y550374D01*
X-333908Y549707D01*
X-334241Y549124D01*
X-334741Y548790D01*
X-335241Y548707D01*
G01X-329641Y553707D02*
Y548707D01*
G01X-330808Y552040D02*
X-328474D01*
G01X-319691Y549290D02*
X-319274Y548957D01*
X-318691Y548707D01*
X-318191D01*
X-317691Y548874D01*
X-317358Y549124D01*
X-317191Y549457D01*
X-317274Y549957D01*
X-317608Y550207D01*
X-319108Y550707D01*
X-319441Y551290D01*
X-319274Y551707D01*
X-318941Y551957D01*
X-318441Y552040D01*
X-317941Y551957D01*
X-317441Y551707D01*
G01X-314341Y547040D02*
Y552040D01*
G01Y551290D02*
X-313924Y551707D01*
X-313508Y551957D01*
X-312841Y552040D01*
X-312258Y551957D01*
X-311674Y551540D01*
X-311424Y550957D01*
X-311341Y550374D01*
X-311424Y549790D01*
X-311674Y549207D01*
X-312174Y548874D01*
X-312841Y548707D01*
X-313424Y548790D01*
X-314008Y549040D01*
X-314341Y549374D01*
G01X-308491Y550957D02*
X-305824D01*
X-306074Y551540D01*
X-306491Y551874D01*
X-307074Y552040D01*
X-307658Y551957D01*
X-308158Y551707D01*
X-308491Y551124D01*
X-308658Y550624D01*
Y550124D01*
X-308491Y549624D01*
X-308074Y549124D01*
X-307574Y548790D01*
X-306991Y548707D01*
X-306408Y548874D01*
X-305824Y549374D01*
G01X-300308Y551624D02*
X-300891Y551957D01*
X-301391Y552040D01*
X-302058Y551874D01*
X-302558Y551540D01*
X-302891Y550957D01*
X-302974Y550374D01*
X-302891Y549790D01*
X-302558Y549290D01*
X-302058Y548874D01*
X-301391Y548707D01*
X-300808Y548874D01*
X-300308Y549207D01*
G01X-296041Y552040D02*
Y548707D01*
G01Y553374D02*
X-296208Y553457D01*
Y553624D01*
X-296041Y553707D01*
X-295874Y553624D01*
Y553457D01*
X-296041Y553374D01*
G01X-290941Y548707D02*
Y552957D01*
X-290774Y553374D01*
X-290441Y553624D01*
X-289941Y553707D01*
X-289441Y553540D01*
X-289191Y553124D01*
G01X-290191Y551707D02*
X-291858D01*
G01X-284841Y552040D02*
Y548707D01*
G01Y553374D02*
X-285008Y553457D01*
Y553624D01*
X-284841Y553707D01*
X-284674Y553624D01*
Y553457D01*
X-284841Y553374D01*
G01X-280491Y550957D02*
X-277824D01*
X-278074Y551540D01*
X-278491Y551874D01*
X-279074Y552040D01*
X-279658Y551957D01*
X-280158Y551707D01*
X-280491Y551124D01*
X-280658Y550624D01*
Y550124D01*
X-280491Y549624D01*
X-280074Y549124D01*
X-279574Y548790D01*
X-278991Y548707D01*
X-278408Y548874D01*
X-277824Y549374D01*
G01X-272141Y553707D02*
Y548707D01*
G01Y549457D02*
X-272474Y549040D01*
X-272974Y548790D01*
X-273558Y548707D01*
X-274224Y548874D01*
X-274724Y549290D01*
X-275058Y549790D01*
X-275141Y550374D01*
X-275058Y550957D01*
X-274724Y551457D01*
X-274224Y551874D01*
X-273558Y552040D01*
X-272974Y551957D01*
X-272558Y551790D01*
X-272141Y551457D01*
G01X-262441Y552040D02*
Y548707D01*
G01Y553374D02*
X-262608Y553457D01*
Y553624D01*
X-262441Y553707D01*
X-262274Y553624D01*
Y553457D01*
X-262441Y553374D01*
G01X-258258Y548707D02*
Y552040D01*
G01Y551207D02*
X-257924Y551624D01*
X-257424Y551957D01*
X-256758Y552040D01*
X-256174Y551957D01*
X-255674Y551624D01*
X-255424Y551040D01*
Y548707D01*
G01X-245641Y553707D02*
Y548707D01*
G01X-246808Y552040D02*
X-244474D01*
G01X-241458Y548707D02*
Y553707D01*
G01Y551290D02*
X-241041Y551707D01*
X-240624Y551957D01*
X-239958Y552040D01*
X-239458Y551957D01*
X-238874Y551624D01*
X-238624Y551124D01*
Y548707D01*
G01X-235691Y550957D02*
X-233024D01*
X-233274Y551540D01*
X-233691Y551874D01*
X-234274Y552040D01*
X-234858Y551957D01*
X-235358Y551707D01*
X-235691Y551124D01*
X-235858Y550624D01*
Y550124D01*
X-235691Y549624D01*
X-235274Y549124D01*
X-234774Y548790D01*
X-234191Y548707D01*
X-233608Y548874D01*
X-233024Y549374D01*
G01X-223241Y553707D02*
Y548707D01*
G01X-224408Y552040D02*
X-222074D01*
G01X-216141Y548707D02*
Y552040D01*
G01Y551457D02*
X-216474Y551790D01*
X-216974Y551957D01*
X-217558Y552040D01*
X-218141Y551874D01*
X-218641Y551540D01*
X-218974Y551040D01*
X-219141Y550374D01*
X-218974Y549707D01*
X-218641Y549207D01*
X-218141Y548874D01*
X-217558Y548707D01*
X-216974Y548790D01*
X-216474Y549040D01*
X-216141Y549374D01*
G01X-213541Y548707D02*
Y553707D01*
G01Y551207D02*
X-213124Y551707D01*
X-212624Y551957D01*
X-212124Y552040D01*
X-211374Y551874D01*
X-210874Y551540D01*
X-210541Y550957D01*
Y550290D01*
X-210708Y549624D01*
X-211041Y549124D01*
X-211624Y548790D01*
X-212124Y548707D01*
X-212624Y548790D01*
X-213124Y549040D01*
X-213541Y549457D01*
G01X-206441Y548707D02*
Y553707D01*
G01X-202091Y550957D02*
X-199424D01*
X-199674Y551540D01*
X-200091Y551874D01*
X-200674Y552040D01*
X-201258Y551957D01*
X-201758Y551707D01*
X-202091Y551124D01*
X-202258Y550624D01*
Y550124D01*
X-202091Y549624D01*
X-201674Y549124D01*
X-201174Y548790D01*
X-200591Y548707D01*
X-200008Y548874D01*
X-199424Y549374D01*
G01X-195241Y548540D02*
X-195408Y548624D01*
Y548790D01*
X-195241Y548874D01*
X-195074Y548790D01*
Y548624D01*
X-195241Y548540D01*
G01Y550790D02*
X-195408Y550874D01*
Y551040D01*
X-195241Y551124D01*
X-195074Y551040D01*
Y550874D01*
X-195241Y550790D01*
G01X-438241Y537540D02*
X-438408Y537624D01*
Y537790D01*
X-438241Y537874D01*
X-438074Y537790D01*
Y537624D01*
X-438241Y537540D01*
G01Y530640D02*
X-438408Y530724D01*
Y530890D01*
X-438241Y530974D01*
X-438074Y530890D01*
Y530724D01*
X-438241Y530640D01*
G01X-434241Y534807D02*
X-432241D01*
G01X-433241D02*
Y529807D01*
G01X-434241D02*
X-432241D01*
G01X-429308D02*
Y534807D01*
X-427308D01*
X-426641Y534557D01*
X-426141Y533974D01*
X-425974Y533307D01*
X-426141Y532640D01*
X-426558Y532140D01*
X-427308Y531890D01*
X-429308D01*
G01X-420208Y534390D02*
X-420708Y534640D01*
X-421291Y534807D01*
X-421958D01*
X-422708Y534557D01*
X-423291Y534140D01*
X-423708Y533640D01*
X-424041Y532807D01*
X-424124Y532057D01*
X-423958Y531307D01*
X-423708Y530807D01*
X-423208Y530307D01*
X-422624Y529974D01*
X-422041Y529807D01*
X-421458D01*
X-420874Y529974D01*
X-420374Y530224D01*
X-419958Y530557D01*
G01X-417524Y531474D02*
X-415358D01*
G01X-412424Y531890D02*
X-411841Y532474D01*
X-411341Y532807D01*
X-410674Y532974D01*
X-410091Y532807D01*
X-409674Y532474D01*
X-409341Y531974D01*
X-409258Y531390D01*
X-409341Y530890D01*
X-409674Y530390D01*
X-410174Y529974D01*
X-410758Y529807D01*
X-411424Y529974D01*
X-412008Y530474D01*
X-412341Y531224D01*
X-412424Y532057D01*
X-412258Y533140D01*
X-412008Y533724D01*
X-411591Y534307D01*
X-411008Y534724D01*
X-410424Y534807D01*
X-409841Y534640D01*
X-409424Y534224D01*
G01X-405241Y534807D02*
X-405908Y534640D01*
X-406408Y534224D01*
X-406741Y533724D01*
X-406991Y533057D01*
X-407074Y532307D01*
X-406991Y531557D01*
X-406741Y530890D01*
X-406408Y530390D01*
X-405908Y529974D01*
X-405241Y529807D01*
X-404574Y529974D01*
X-404074Y530390D01*
X-403741Y530890D01*
X-403491Y531557D01*
X-403408Y532307D01*
X-403491Y533057D01*
X-403741Y533724D01*
X-404074Y534224D01*
X-404574Y534640D01*
X-405241Y534807D01*
G01X-399641Y529807D02*
Y534807D01*
X-400641Y533807D01*
G01Y529807D02*
X-398641D01*
G01X-394041D02*
Y534807D01*
X-395041Y533807D01*
G01Y529807D02*
X-393041D01*
G01X-382341Y532307D02*
X-380674D01*
Y530807D01*
X-381174Y530307D01*
X-381758Y529974D01*
X-382591Y529807D01*
X-383424Y529974D01*
X-384008Y530307D01*
X-384508Y530807D01*
X-384841Y531390D01*
X-385008Y532057D01*
Y532640D01*
X-384841Y533140D01*
X-384508Y533724D01*
X-384008Y534224D01*
X-383508Y534557D01*
X-382841Y534807D01*
X-382258D01*
X-381591Y534640D01*
X-381091Y534307D01*
G01X-378491Y532057D02*
X-375824D01*
X-376074Y532640D01*
X-376491Y532974D01*
X-377074Y533140D01*
X-377658Y533057D01*
X-378158Y532807D01*
X-378491Y532224D01*
X-378658Y531724D01*
Y531224D01*
X-378491Y530724D01*
X-378074Y530224D01*
X-377574Y529890D01*
X-376991Y529807D01*
X-376408Y529974D01*
X-375824Y530474D01*
G01X-373058Y529807D02*
Y533140D01*
G01Y532307D02*
X-372724Y532724D01*
X-372224Y533057D01*
X-371558Y533140D01*
X-370974Y533057D01*
X-370474Y532724D01*
X-370224Y532140D01*
Y529807D01*
G01X-367291Y532057D02*
X-364624D01*
X-364874Y532640D01*
X-365291Y532974D01*
X-365874Y533140D01*
X-366458Y533057D01*
X-366958Y532807D01*
X-367291Y532224D01*
X-367458Y531724D01*
Y531224D01*
X-367291Y530724D01*
X-366874Y530224D01*
X-366374Y529890D01*
X-365791Y529807D01*
X-365208Y529974D01*
X-364624Y530474D01*
G01X-361608Y529807D02*
Y533140D01*
G01Y532474D02*
X-361191Y532807D01*
X-360774Y533057D01*
X-360191Y533140D01*
X-359774Y533057D01*
X-359274Y532807D01*
G01X-354841Y533140D02*
Y529807D01*
G01Y534474D02*
X-355008Y534557D01*
Y534724D01*
X-354841Y534807D01*
X-354674Y534724D01*
Y534557D01*
X-354841Y534474D01*
G01X-347908Y532724D02*
X-348491Y533057D01*
X-348991Y533140D01*
X-349658Y532974D01*
X-350158Y532640D01*
X-350491Y532057D01*
X-350574Y531474D01*
X-350491Y530890D01*
X-350158Y530390D01*
X-349658Y529974D01*
X-348991Y529807D01*
X-348408Y529974D01*
X-347908Y530307D01*
G01X-339708Y529807D02*
Y534807D01*
X-337708D01*
X-337041Y534557D01*
X-336541Y533974D01*
X-336374Y533307D01*
X-336541Y532640D01*
X-336958Y532140D01*
X-337708Y531890D01*
X-339708D01*
G01X-333691Y532057D02*
X-331024D01*
X-331274Y532640D01*
X-331691Y532974D01*
X-332274Y533140D01*
X-332858Y533057D01*
X-333358Y532807D01*
X-333691Y532224D01*
X-333858Y531724D01*
Y531224D01*
X-333691Y530724D01*
X-333274Y530224D01*
X-332774Y529890D01*
X-332191Y529807D01*
X-331608Y529974D01*
X-331024Y530474D01*
G01X-328008Y529807D02*
Y533140D01*
G01Y532474D02*
X-327591Y532807D01*
X-327174Y533057D01*
X-326591Y533140D01*
X-326174Y533057D01*
X-325674Y532807D01*
G01X-321741Y529807D02*
Y534057D01*
X-321574Y534474D01*
X-321241Y534724D01*
X-320741Y534807D01*
X-320241Y534640D01*
X-319991Y534224D01*
G01X-320991Y532807D02*
X-322658D01*
G01X-315641Y529807D02*
X-316141Y529890D01*
X-316641Y530224D01*
X-316974Y530807D01*
X-317141Y531474D01*
X-316974Y532140D01*
X-316641Y532724D01*
X-316141Y533057D01*
X-315641Y533140D01*
X-315141Y533057D01*
X-314641Y532724D01*
X-314308Y532140D01*
X-314224Y531474D01*
X-314308Y530807D01*
X-314641Y530224D01*
X-315141Y529890D01*
X-315641Y529807D01*
G01X-311208D02*
Y533140D01*
G01Y532474D02*
X-310791Y532807D01*
X-310374Y533057D01*
X-309791Y533140D01*
X-309374Y533057D01*
X-308874Y532807D01*
G01X-306941Y529807D02*
Y533140D01*
G01Y532224D02*
X-306691Y532640D01*
X-306274Y532974D01*
X-305691Y533140D01*
X-305108Y532974D01*
X-304691Y532640D01*
X-304441Y532224D01*
Y529807D01*
G01Y532224D02*
X-304191Y532640D01*
X-303774Y532974D01*
X-303191Y533140D01*
X-302608Y532974D01*
X-302191Y532640D01*
X-301941Y532140D01*
Y529807D01*
G01X-297341D02*
Y533140D01*
G01Y532557D02*
X-297674Y532890D01*
X-298174Y533057D01*
X-298758Y533140D01*
X-299341Y532974D01*
X-299841Y532640D01*
X-300174Y532140D01*
X-300341Y531474D01*
X-300174Y530807D01*
X-299841Y530307D01*
X-299341Y529974D01*
X-298758Y529807D01*
X-298174Y529890D01*
X-297674Y530140D01*
X-297341Y530474D01*
G01X-294658Y529807D02*
Y533140D01*
G01Y532307D02*
X-294324Y532724D01*
X-293824Y533057D01*
X-293158Y533140D01*
X-292574Y533057D01*
X-292074Y532724D01*
X-291824Y532140D01*
Y529807D01*
G01X-286308Y532724D02*
X-286891Y533057D01*
X-287391Y533140D01*
X-288058Y532974D01*
X-288558Y532640D01*
X-288891Y532057D01*
X-288974Y531474D01*
X-288891Y530890D01*
X-288558Y530390D01*
X-288058Y529974D01*
X-287391Y529807D01*
X-286808Y529974D01*
X-286308Y530307D01*
G01X-283291Y532057D02*
X-280624D01*
X-280874Y532640D01*
X-281291Y532974D01*
X-281874Y533140D01*
X-282458Y533057D01*
X-282958Y532807D01*
X-283291Y532224D01*
X-283458Y531724D01*
Y531224D01*
X-283291Y530724D01*
X-282874Y530224D01*
X-282374Y529890D01*
X-281791Y529807D01*
X-281208Y529974D01*
X-280624Y530474D01*
G01X-272591D02*
X-271924Y530057D01*
X-271174Y529807D01*
X-270508D01*
X-269841Y530057D01*
X-269341Y530474D01*
X-269091Y531057D01*
X-269258Y531640D01*
X-269674Y532140D01*
X-270424Y532474D01*
X-271424Y532640D01*
X-272008Y532974D01*
X-272258Y533557D01*
X-272091Y534140D01*
X-271674Y534557D01*
X-271091Y534807D01*
X-270508D01*
X-269924Y534640D01*
X-269424Y534224D01*
G01X-266741Y528140D02*
Y533140D01*
G01Y532390D02*
X-266324Y532807D01*
X-265908Y533057D01*
X-265241Y533140D01*
X-264658Y533057D01*
X-264074Y532640D01*
X-263824Y532057D01*
X-263741Y531474D01*
X-263824Y530890D01*
X-264074Y530307D01*
X-264574Y529974D01*
X-265241Y529807D01*
X-265824Y529890D01*
X-266408Y530140D01*
X-266741Y530474D01*
G01X-260891Y532057D02*
X-258224D01*
X-258474Y532640D01*
X-258891Y532974D01*
X-259474Y533140D01*
X-260058Y533057D01*
X-260558Y532807D01*
X-260891Y532224D01*
X-261058Y531724D01*
Y531224D01*
X-260891Y530724D01*
X-260474Y530224D01*
X-259974Y529890D01*
X-259391Y529807D01*
X-258808Y529974D01*
X-258224Y530474D01*
G01X-252708Y532724D02*
X-253291Y533057D01*
X-253791Y533140D01*
X-254458Y532974D01*
X-254958Y532640D01*
X-255291Y532057D01*
X-255374Y531474D01*
X-255291Y530890D01*
X-254958Y530390D01*
X-254458Y529974D01*
X-253791Y529807D01*
X-253208Y529974D01*
X-252708Y530307D01*
G01X-248441Y533140D02*
Y529807D01*
G01Y534474D02*
X-248608Y534557D01*
Y534724D01*
X-248441Y534807D01*
X-248274Y534724D01*
Y534557D01*
X-248441Y534474D01*
G01X-243341Y529807D02*
Y534057D01*
X-243174Y534474D01*
X-242841Y534724D01*
X-242341Y534807D01*
X-241841Y534640D01*
X-241591Y534224D01*
G01X-242591Y532807D02*
X-244258D01*
G01X-237241Y533140D02*
Y529807D01*
G01Y534474D02*
X-237408Y534557D01*
Y534724D01*
X-237241Y534807D01*
X-237074Y534724D01*
Y534557D01*
X-237241Y534474D01*
G01X-230308Y532724D02*
X-230891Y533057D01*
X-231391Y533140D01*
X-232058Y532974D01*
X-232558Y532640D01*
X-232891Y532057D01*
X-232974Y531474D01*
X-232891Y530890D01*
X-232558Y530390D01*
X-232058Y529974D01*
X-231391Y529807D01*
X-230808Y529974D01*
X-230308Y530307D01*
G01X-224541Y529807D02*
Y533140D01*
G01Y532557D02*
X-224874Y532890D01*
X-225374Y533057D01*
X-225958Y533140D01*
X-226541Y532974D01*
X-227041Y532640D01*
X-227374Y532140D01*
X-227541Y531474D01*
X-227374Y530807D01*
X-227041Y530307D01*
X-226541Y529974D01*
X-225958Y529807D01*
X-225374Y529890D01*
X-224874Y530140D01*
X-224541Y530474D01*
G01X-220441Y534807D02*
Y529807D01*
G01X-221608Y533140D02*
X-219274D01*
G01X-214841D02*
Y529807D01*
G01Y534474D02*
X-215008Y534557D01*
Y534724D01*
X-214841Y534807D01*
X-214674Y534724D01*
Y534557D01*
X-214841Y534474D01*
G01X-209241Y529807D02*
X-209741Y529890D01*
X-210241Y530224D01*
X-210574Y530807D01*
X-210741Y531474D01*
X-210574Y532140D01*
X-210241Y532724D01*
X-209741Y533057D01*
X-209241Y533140D01*
X-208741Y533057D01*
X-208241Y532724D01*
X-207908Y532140D01*
X-207824Y531474D01*
X-207908Y530807D01*
X-208241Y530224D01*
X-208741Y529890D01*
X-209241Y529807D01*
G01X-205058D02*
Y533140D01*
G01Y532307D02*
X-204724Y532724D01*
X-204224Y533057D01*
X-203558Y533140D01*
X-202974Y533057D01*
X-202474Y532724D01*
X-202224Y532140D01*
Y529807D01*
G01X-192941D02*
Y534057D01*
X-192774Y534474D01*
X-192441Y534724D01*
X-191941Y534807D01*
X-191441Y534640D01*
X-191191Y534224D01*
G01X-192191Y532807D02*
X-193858D01*
G01X-186841Y529807D02*
X-187341Y529890D01*
X-187841Y530224D01*
X-188174Y530807D01*
X-188341Y531474D01*
X-188174Y532140D01*
X-187841Y532724D01*
X-187341Y533057D01*
X-186841Y533140D01*
X-186341Y533057D01*
X-185841Y532724D01*
X-185508Y532140D01*
X-185424Y531474D01*
X-185508Y530807D01*
X-185841Y530224D01*
X-186341Y529890D01*
X-186841Y529807D01*
G01X-182408D02*
Y533140D01*
G01Y532474D02*
X-181991Y532807D01*
X-181574Y533057D01*
X-180991Y533140D01*
X-180574Y533057D01*
X-180074Y532807D01*
G01X-171708Y529807D02*
Y534807D01*
X-169708D01*
X-169041Y534557D01*
X-168541Y533974D01*
X-168374Y533307D01*
X-168541Y532640D01*
X-168958Y532140D01*
X-169708Y531890D01*
X-171708D01*
G01X-165608Y529807D02*
Y533140D01*
G01Y532474D02*
X-165191Y532807D01*
X-164774Y533057D01*
X-164191Y533140D01*
X-163774Y533057D01*
X-163274Y532807D01*
G01X-158841Y533140D02*
Y529807D01*
G01Y534474D02*
X-159008Y534557D01*
Y534724D01*
X-158841Y534807D01*
X-158674Y534724D01*
Y534557D01*
X-158841Y534474D01*
G01X-154658Y529807D02*
Y533140D01*
G01Y532307D02*
X-154324Y532724D01*
X-153824Y533057D01*
X-153158Y533140D01*
X-152574Y533057D01*
X-152074Y532724D01*
X-151824Y532140D01*
Y529807D01*
G01X-147641Y534807D02*
Y529807D01*
G01X-148808Y533140D02*
X-146474D01*
G01X-143291Y532057D02*
X-140624D01*
X-140874Y532640D01*
X-141291Y532974D01*
X-141874Y533140D01*
X-142458Y533057D01*
X-142958Y532807D01*
X-143291Y532224D01*
X-143458Y531724D01*
Y531224D01*
X-143291Y530724D01*
X-142874Y530224D01*
X-142374Y529890D01*
X-141791Y529807D01*
X-141208Y529974D01*
X-140624Y530474D01*
G01X-134941Y534807D02*
Y529807D01*
G01Y530557D02*
X-135274Y530140D01*
X-135774Y529890D01*
X-136358Y529807D01*
X-137024Y529974D01*
X-137524Y530390D01*
X-137858Y530890D01*
X-137941Y531474D01*
X-137858Y532057D01*
X-137524Y532557D01*
X-137024Y532974D01*
X-136358Y533140D01*
X-135774Y533057D01*
X-135358Y532890D01*
X-134941Y532557D01*
G01X-124574Y532474D02*
X-124241Y532724D01*
X-123991Y533140D01*
X-123824Y533724D01*
X-123991Y534224D01*
X-124324Y534557D01*
X-124908Y534807D01*
X-127158D01*
Y529807D01*
X-124408D01*
X-123824Y530140D01*
X-123491Y530640D01*
X-123324Y531224D01*
X-123491Y531807D01*
X-123991Y532307D01*
X-124574Y532474D01*
X-127158D01*
G01X-119641Y529807D02*
X-120141Y529890D01*
X-120641Y530224D01*
X-120974Y530807D01*
X-121141Y531474D01*
X-120974Y532140D01*
X-120641Y532724D01*
X-120141Y533057D01*
X-119641Y533140D01*
X-119141Y533057D01*
X-118641Y532724D01*
X-118308Y532140D01*
X-118224Y531474D01*
X-118308Y530807D01*
X-118641Y530224D01*
X-119141Y529890D01*
X-119641Y529807D01*
G01X-112541D02*
Y533140D01*
G01Y532557D02*
X-112874Y532890D01*
X-113374Y533057D01*
X-113958Y533140D01*
X-114541Y532974D01*
X-115041Y532640D01*
X-115374Y532140D01*
X-115541Y531474D01*
X-115374Y530807D01*
X-115041Y530307D01*
X-114541Y529974D01*
X-113958Y529807D01*
X-113374Y529890D01*
X-112874Y530140D01*
X-112541Y530474D01*
G01X-109608Y529807D02*
Y533140D01*
G01Y532474D02*
X-109191Y532807D01*
X-108774Y533057D01*
X-108191Y533140D01*
X-107774Y533057D01*
X-107274Y532807D01*
G01X-101341Y534807D02*
Y529807D01*
G01Y530557D02*
X-101674Y530140D01*
X-102174Y529890D01*
X-102758Y529807D01*
X-103424Y529974D01*
X-103924Y530390D01*
X-104258Y530890D01*
X-104341Y531474D01*
X-104258Y532057D01*
X-103924Y532557D01*
X-103424Y532974D01*
X-102758Y533140D01*
X-102174Y533057D01*
X-101758Y532890D01*
X-101341Y532557D01*
G01X-98491Y530390D02*
X-98074Y530057D01*
X-97491Y529807D01*
X-96991D01*
X-96491Y529974D01*
X-96158Y530224D01*
X-95991Y530557D01*
X-96074Y531057D01*
X-96408Y531307D01*
X-97908Y531807D01*
X-98241Y532390D01*
X-98074Y532807D01*
X-97741Y533057D01*
X-97241Y533140D01*
X-96741Y533057D01*
X-96241Y532807D01*
G01X-434241Y542707D02*
X-432241D01*
G01X-433241D02*
Y537707D01*
G01X-434241D02*
X-432241D01*
G01X-429308D02*
Y542707D01*
X-427308D01*
X-426641Y542457D01*
X-426141Y541874D01*
X-425974Y541207D01*
X-426141Y540540D01*
X-426558Y540040D01*
X-427308Y539790D01*
X-429308D01*
G01X-420208Y542290D02*
X-420708Y542540D01*
X-421291Y542707D01*
X-421958D01*
X-422708Y542457D01*
X-423291Y542040D01*
X-423708Y541540D01*
X-424041Y540707D01*
X-424124Y539957D01*
X-423958Y539207D01*
X-423708Y538707D01*
X-423208Y538207D01*
X-422624Y537874D01*
X-422041Y537707D01*
X-421458D01*
X-420874Y537874D01*
X-420374Y538124D01*
X-419958Y538457D01*
G01X-417524Y539374D02*
X-415358D01*
G01X-412924Y537707D02*
X-410841Y542707D01*
X-408758Y537707D01*
G01X-409508Y539457D02*
X-412174D01*
G01X-406324Y539374D02*
X-404158D01*
G01X-401224Y539790D02*
X-400641Y540374D01*
X-400141Y540707D01*
X-399474Y540874D01*
X-398891Y540707D01*
X-398474Y540374D01*
X-398141Y539874D01*
X-398058Y539290D01*
X-398141Y538790D01*
X-398474Y538290D01*
X-398974Y537874D01*
X-399558Y537707D01*
X-400224Y537874D01*
X-400808Y538374D01*
X-401141Y539124D01*
X-401224Y539957D01*
X-401058Y541040D01*
X-400808Y541624D01*
X-400391Y542207D01*
X-399808Y542624D01*
X-399224Y542707D01*
X-398641Y542540D01*
X-398224Y542124D01*
G01X-394041Y542707D02*
X-394708Y542540D01*
X-395208Y542124D01*
X-395541Y541624D01*
X-395791Y540957D01*
X-395874Y540207D01*
X-395791Y539457D01*
X-395541Y538790D01*
X-395208Y538290D01*
X-394708Y537874D01*
X-394041Y537707D01*
X-393374Y537874D01*
X-392874Y538290D01*
X-392541Y538790D01*
X-392291Y539457D01*
X-392208Y540207D01*
X-392291Y540957D01*
X-392541Y541624D01*
X-392874Y542124D01*
X-393374Y542540D01*
X-394041Y542707D01*
G01X-388441D02*
X-389108Y542540D01*
X-389608Y542124D01*
X-389941Y541624D01*
X-390191Y540957D01*
X-390274Y540207D01*
X-390191Y539457D01*
X-389941Y538790D01*
X-389608Y538290D01*
X-389108Y537874D01*
X-388441Y537707D01*
X-387774Y537874D01*
X-387274Y538290D01*
X-386941Y538790D01*
X-386691Y539457D01*
X-386608Y540207D01*
X-386691Y540957D01*
X-386941Y541624D01*
X-387274Y542124D01*
X-387774Y542540D01*
X-388441Y542707D01*
G01X-379324Y537707D02*
X-377241Y542707D01*
X-375158Y537707D01*
G01X-375908Y539457D02*
X-378574D01*
G01X-370308Y540624D02*
X-370891Y540957D01*
X-371391Y541040D01*
X-372058Y540874D01*
X-372558Y540540D01*
X-372891Y539957D01*
X-372974Y539374D01*
X-372891Y538790D01*
X-372558Y538290D01*
X-372058Y537874D01*
X-371391Y537707D01*
X-370808Y537874D01*
X-370308Y538207D01*
G01X-364708Y540624D02*
X-365291Y540957D01*
X-365791Y541040D01*
X-366458Y540874D01*
X-366958Y540540D01*
X-367291Y539957D01*
X-367374Y539374D01*
X-367291Y538790D01*
X-366958Y538290D01*
X-366458Y537874D01*
X-365791Y537707D01*
X-365208Y537874D01*
X-364708Y538207D01*
G01X-361691Y539957D02*
X-359024D01*
X-359274Y540540D01*
X-359691Y540874D01*
X-360274Y541040D01*
X-360858Y540957D01*
X-361358Y540707D01*
X-361691Y540124D01*
X-361858Y539624D01*
Y539124D01*
X-361691Y538624D01*
X-361274Y538124D01*
X-360774Y537790D01*
X-360191Y537707D01*
X-359608Y537874D01*
X-359024Y538374D01*
G01X-356341Y536040D02*
Y541040D01*
G01Y540290D02*
X-355924Y540707D01*
X-355508Y540957D01*
X-354841Y541040D01*
X-354258Y540957D01*
X-353674Y540540D01*
X-353424Y539957D01*
X-353341Y539374D01*
X-353424Y538790D01*
X-353674Y538207D01*
X-354174Y537874D01*
X-354841Y537707D01*
X-355424Y537790D01*
X-356008Y538040D01*
X-356341Y538374D01*
G01X-349241Y542707D02*
Y537707D01*
G01X-350408Y541040D02*
X-348074D01*
G01X-342141Y537707D02*
Y541040D01*
G01Y540457D02*
X-342474Y540790D01*
X-342974Y540957D01*
X-343558Y541040D01*
X-344141Y540874D01*
X-344641Y540540D01*
X-344974Y540040D01*
X-345141Y539374D01*
X-344974Y538707D01*
X-344641Y538207D01*
X-344141Y537874D01*
X-343558Y537707D01*
X-342974Y537790D01*
X-342474Y538040D01*
X-342141Y538374D01*
G01X-339541Y537707D02*
Y542707D01*
G01Y540207D02*
X-339124Y540707D01*
X-338624Y540957D01*
X-338124Y541040D01*
X-337374Y540874D01*
X-336874Y540540D01*
X-336541Y539957D01*
Y539290D01*
X-336708Y538624D01*
X-337041Y538124D01*
X-337624Y537790D01*
X-338124Y537707D01*
X-338624Y537790D01*
X-339124Y538040D01*
X-339541Y538457D01*
G01X-332441Y541040D02*
Y537707D01*
G01Y542374D02*
X-332608Y542457D01*
Y542624D01*
X-332441Y542707D01*
X-332274Y542624D01*
Y542457D01*
X-332441Y542374D01*
G01X-326841Y537707D02*
Y542707D01*
G01X-321241Y541040D02*
Y537707D01*
G01Y542374D02*
X-321408Y542457D01*
Y542624D01*
X-321241Y542707D01*
X-321074Y542624D01*
Y542457D01*
X-321241Y542374D01*
G01X-315641Y542707D02*
Y537707D01*
G01X-316808Y541040D02*
X-314474D01*
G01X-311791Y536207D02*
X-311291Y536040D01*
X-310624Y536207D01*
X-310208Y536540D01*
X-309874Y536957D01*
X-309374Y538290D01*
X-308291Y541040D01*
G01X-310958D02*
X-309374Y538290D01*
G01X-298841Y537707D02*
X-299341Y537790D01*
X-299841Y538124D01*
X-300174Y538707D01*
X-300341Y539374D01*
X-300174Y540040D01*
X-299841Y540624D01*
X-299341Y540957D01*
X-298841Y541040D01*
X-298341Y540957D01*
X-297841Y540624D01*
X-297508Y540040D01*
X-297424Y539374D01*
X-297508Y538707D01*
X-297841Y538124D01*
X-298341Y537790D01*
X-298841Y537707D01*
G01X-293741D02*
Y541957D01*
X-293574Y542374D01*
X-293241Y542624D01*
X-292741Y542707D01*
X-292241Y542540D01*
X-291991Y542124D01*
G01X-292991Y540707D02*
X-294658D01*
G01X-283708Y537707D02*
Y542707D01*
X-281708D01*
X-281041Y542457D01*
X-280541Y541874D01*
X-280374Y541207D01*
X-280541Y540540D01*
X-280958Y540040D01*
X-281708Y539790D01*
X-283708D01*
G01X-277608Y537707D02*
Y541040D01*
G01Y540374D02*
X-277191Y540707D01*
X-276774Y540957D01*
X-276191Y541040D01*
X-275774Y540957D01*
X-275274Y540707D01*
G01X-270841Y541040D02*
Y537707D01*
G01Y542374D02*
X-271008Y542457D01*
Y542624D01*
X-270841Y542707D01*
X-270674Y542624D01*
Y542457D01*
X-270841Y542374D01*
G01X-266658Y537707D02*
Y541040D01*
G01Y540207D02*
X-266324Y540624D01*
X-265824Y540957D01*
X-265158Y541040D01*
X-264574Y540957D01*
X-264074Y540624D01*
X-263824Y540040D01*
Y537707D01*
G01X-259641Y542707D02*
Y537707D01*
G01X-260808Y541040D02*
X-258474D01*
G01X-255291Y539957D02*
X-252624D01*
X-252874Y540540D01*
X-253291Y540874D01*
X-253874Y541040D01*
X-254458Y540957D01*
X-254958Y540707D01*
X-255291Y540124D01*
X-255458Y539624D01*
Y539124D01*
X-255291Y538624D01*
X-254874Y538124D01*
X-254374Y537790D01*
X-253791Y537707D01*
X-253208Y537874D01*
X-252624Y538374D01*
G01X-246941Y542707D02*
Y537707D01*
G01Y538457D02*
X-247274Y538040D01*
X-247774Y537790D01*
X-248358Y537707D01*
X-249024Y537874D01*
X-249524Y538290D01*
X-249858Y538790D01*
X-249941Y539374D01*
X-249858Y539957D01*
X-249524Y540457D01*
X-249024Y540874D01*
X-248358Y541040D01*
X-247774Y540957D01*
X-247358Y540790D01*
X-246941Y540457D01*
G01X-236574Y540374D02*
X-236241Y540624D01*
X-235991Y541040D01*
X-235824Y541624D01*
X-235991Y542124D01*
X-236324Y542457D01*
X-236908Y542707D01*
X-239158D01*
Y537707D01*
X-236408D01*
X-235824Y538040D01*
X-235491Y538540D01*
X-235324Y539124D01*
X-235491Y539707D01*
X-235991Y540207D01*
X-236574Y540374D01*
X-239158D01*
G01X-231641Y537707D02*
X-232141Y537790D01*
X-232641Y538124D01*
X-232974Y538707D01*
X-233141Y539374D01*
X-232974Y540040D01*
X-232641Y540624D01*
X-232141Y540957D01*
X-231641Y541040D01*
X-231141Y540957D01*
X-230641Y540624D01*
X-230308Y540040D01*
X-230224Y539374D01*
X-230308Y538707D01*
X-230641Y538124D01*
X-231141Y537790D01*
X-231641Y537707D01*
G01X-224541D02*
Y541040D01*
G01Y540457D02*
X-224874Y540790D01*
X-225374Y540957D01*
X-225958Y541040D01*
X-226541Y540874D01*
X-227041Y540540D01*
X-227374Y540040D01*
X-227541Y539374D01*
X-227374Y538707D01*
X-227041Y538207D01*
X-226541Y537874D01*
X-225958Y537707D01*
X-225374Y537790D01*
X-224874Y538040D01*
X-224541Y538374D01*
G01X-221608Y537707D02*
Y541040D01*
G01Y540374D02*
X-221191Y540707D01*
X-220774Y540957D01*
X-220191Y541040D01*
X-219774Y540957D01*
X-219274Y540707D01*
G01X-213341Y542707D02*
Y537707D01*
G01Y538457D02*
X-213674Y538040D01*
X-214174Y537790D01*
X-214758Y537707D01*
X-215424Y537874D01*
X-215924Y538290D01*
X-216258Y538790D01*
X-216341Y539374D01*
X-216258Y539957D01*
X-215924Y540457D01*
X-215424Y540874D01*
X-214758Y541040D01*
X-214174Y540957D01*
X-213758Y540790D01*
X-213341Y540457D01*
G01X-210491Y538290D02*
X-210074Y537957D01*
X-209491Y537707D01*
X-208991D01*
X-208491Y537874D01*
X-208158Y538124D01*
X-207991Y538457D01*
X-208074Y538957D01*
X-208408Y539207D01*
X-209908Y539707D01*
X-210241Y540290D01*
X-210074Y540707D01*
X-209741Y540957D01*
X-209241Y541040D01*
X-208741Y540957D01*
X-208241Y540707D01*
G01X-447408Y557707D02*
Y562707D01*
X-445408D01*
X-444741Y562457D01*
X-444241Y561874D01*
X-444074Y561207D01*
X-444241Y560540D01*
X-444658Y560040D01*
X-445408Y559790D01*
X-447408D01*
G01X-440141Y557707D02*
Y562707D01*
G01X-435791Y559957D02*
X-433124D01*
X-433374Y560540D01*
X-433791Y560874D01*
X-434374Y561040D01*
X-434958Y560957D01*
X-435458Y560707D01*
X-435791Y560124D01*
X-435958Y559624D01*
Y559124D01*
X-435791Y558624D01*
X-435374Y558124D01*
X-434874Y557790D01*
X-434291Y557707D01*
X-433708Y557874D01*
X-433124Y558374D01*
G01X-427441Y557707D02*
Y561040D01*
G01Y560457D02*
X-427774Y560790D01*
X-428274Y560957D01*
X-428858Y561040D01*
X-429441Y560874D01*
X-429941Y560540D01*
X-430274Y560040D01*
X-430441Y559374D01*
X-430274Y558707D01*
X-429941Y558207D01*
X-429441Y557874D01*
X-428858Y557707D01*
X-428274Y557790D01*
X-427774Y558040D01*
X-427441Y558374D01*
G01X-424591Y558290D02*
X-424174Y557957D01*
X-423591Y557707D01*
X-423091D01*
X-422591Y557874D01*
X-422258Y558124D01*
X-422091Y558457D01*
X-422174Y558957D01*
X-422508Y559207D01*
X-424008Y559707D01*
X-424341Y560290D01*
X-424174Y560707D01*
X-423841Y560957D01*
X-423341Y561040D01*
X-422841Y560957D01*
X-422341Y560707D01*
G01X-418991Y559957D02*
X-416324D01*
X-416574Y560540D01*
X-416991Y560874D01*
X-417574Y561040D01*
X-418158Y560957D01*
X-418658Y560707D01*
X-418991Y560124D01*
X-419158Y559624D01*
Y559124D01*
X-418991Y558624D01*
X-418574Y558124D01*
X-418074Y557790D01*
X-417491Y557707D01*
X-416908Y557874D01*
X-416324Y558374D01*
G01X-407041Y557707D02*
Y561957D01*
X-406874Y562374D01*
X-406541Y562624D01*
X-406041Y562707D01*
X-405541Y562540D01*
X-405291Y562124D01*
G01X-406291Y560707D02*
X-407958D01*
G01X-400941Y557707D02*
X-401441Y557790D01*
X-401941Y558124D01*
X-402274Y558707D01*
X-402441Y559374D01*
X-402274Y560040D01*
X-401941Y560624D01*
X-401441Y560957D01*
X-400941Y561040D01*
X-400441Y560957D01*
X-399941Y560624D01*
X-399608Y560040D01*
X-399524Y559374D01*
X-399608Y558707D01*
X-399941Y558124D01*
X-400441Y557790D01*
X-400941Y557707D01*
G01X-395341D02*
Y562707D01*
G01X-389741Y557707D02*
Y562707D01*
G01X-384141Y557707D02*
X-384641Y557790D01*
X-385141Y558124D01*
X-385474Y558707D01*
X-385641Y559374D01*
X-385474Y560040D01*
X-385141Y560624D01*
X-384641Y560957D01*
X-384141Y561040D01*
X-383641Y560957D01*
X-383141Y560624D01*
X-382808Y560040D01*
X-382724Y559374D01*
X-382808Y558707D01*
X-383141Y558124D01*
X-383641Y557790D01*
X-384141Y557707D01*
G01X-380624Y561040D02*
X-379624Y557707D01*
X-378541Y561040D01*
X-377458Y557707D01*
X-376458Y561040D01*
G01X-367341Y562707D02*
Y557707D01*
G01X-368508Y561040D02*
X-366174D01*
G01X-363158Y557707D02*
Y562707D01*
G01Y560290D02*
X-362741Y560707D01*
X-362324Y560957D01*
X-361658Y561040D01*
X-361158Y560957D01*
X-360574Y560624D01*
X-360324Y560124D01*
Y557707D01*
G01X-357391Y559957D02*
X-354724D01*
X-354974Y560540D01*
X-355391Y560874D01*
X-355974Y561040D01*
X-356558Y560957D01*
X-357058Y560707D01*
X-357391Y560124D01*
X-357558Y559624D01*
Y559124D01*
X-357391Y558624D01*
X-356974Y558124D01*
X-356474Y557790D01*
X-355891Y557707D01*
X-355308Y557874D01*
X-354724Y558374D01*
G01X-346191Y558290D02*
X-345774Y557957D01*
X-345191Y557707D01*
X-344691D01*
X-344191Y557874D01*
X-343858Y558124D01*
X-343691Y558457D01*
X-343774Y558957D01*
X-344108Y559207D01*
X-345608Y559707D01*
X-345941Y560290D01*
X-345774Y560707D01*
X-345441Y560957D01*
X-344941Y561040D01*
X-344441Y560957D01*
X-343941Y560707D01*
G01X-340841Y556040D02*
Y561040D01*
G01Y560290D02*
X-340424Y560707D01*
X-340008Y560957D01*
X-339341Y561040D01*
X-338758Y560957D01*
X-338174Y560540D01*
X-337924Y559957D01*
X-337841Y559374D01*
X-337924Y558790D01*
X-338174Y558207D01*
X-338674Y557874D01*
X-339341Y557707D01*
X-339924Y557790D01*
X-340508Y558040D01*
X-340841Y558374D01*
G01X-334991Y559957D02*
X-332324D01*
X-332574Y560540D01*
X-332991Y560874D01*
X-333574Y561040D01*
X-334158Y560957D01*
X-334658Y560707D01*
X-334991Y560124D01*
X-335158Y559624D01*
Y559124D01*
X-334991Y558624D01*
X-334574Y558124D01*
X-334074Y557790D01*
X-333491Y557707D01*
X-332908Y557874D01*
X-332324Y558374D01*
G01X-326808Y560624D02*
X-327391Y560957D01*
X-327891Y561040D01*
X-328558Y560874D01*
X-329058Y560540D01*
X-329391Y559957D01*
X-329474Y559374D01*
X-329391Y558790D01*
X-329058Y558290D01*
X-328558Y557874D01*
X-327891Y557707D01*
X-327308Y557874D01*
X-326808Y558207D01*
G01X-322541Y561040D02*
Y557707D01*
G01Y562374D02*
X-322708Y562457D01*
Y562624D01*
X-322541Y562707D01*
X-322374Y562624D01*
Y562457D01*
X-322541Y562374D01*
G01X-317441Y557707D02*
Y561957D01*
X-317274Y562374D01*
X-316941Y562624D01*
X-316441Y562707D01*
X-315941Y562540D01*
X-315691Y562124D01*
G01X-316691Y560707D02*
X-318358D01*
G01X-311341Y561040D02*
Y557707D01*
G01Y562374D02*
X-311508Y562457D01*
Y562624D01*
X-311341Y562707D01*
X-311174Y562624D01*
Y562457D01*
X-311341Y562374D01*
G01X-304408Y560624D02*
X-304991Y560957D01*
X-305491Y561040D01*
X-306158Y560874D01*
X-306658Y560540D01*
X-306991Y559957D01*
X-307074Y559374D01*
X-306991Y558790D01*
X-306658Y558290D01*
X-306158Y557874D01*
X-305491Y557707D01*
X-304908Y557874D01*
X-304408Y558207D01*
G01X-298641Y557707D02*
Y561040D01*
G01Y560457D02*
X-298974Y560790D01*
X-299474Y560957D01*
X-300058Y561040D01*
X-300641Y560874D01*
X-301141Y560540D01*
X-301474Y560040D01*
X-301641Y559374D01*
X-301474Y558707D01*
X-301141Y558207D01*
X-300641Y557874D01*
X-300058Y557707D01*
X-299474Y557790D01*
X-298974Y558040D01*
X-298641Y558374D01*
G01X-294541Y562707D02*
Y557707D01*
G01X-295708Y561040D02*
X-293374D01*
G01X-288941D02*
Y557707D01*
G01Y562374D02*
X-289108Y562457D01*
Y562624D01*
X-288941Y562707D01*
X-288774Y562624D01*
Y562457D01*
X-288941Y562374D01*
G01X-283341Y557707D02*
X-283841Y557790D01*
X-284341Y558124D01*
X-284674Y558707D01*
X-284841Y559374D01*
X-284674Y560040D01*
X-284341Y560624D01*
X-283841Y560957D01*
X-283341Y561040D01*
X-282841Y560957D01*
X-282341Y560624D01*
X-282008Y560040D01*
X-281924Y559374D01*
X-282008Y558707D01*
X-282341Y558124D01*
X-282841Y557790D01*
X-283341Y557707D01*
G01X-279158D02*
Y561040D01*
G01Y560207D02*
X-278824Y560624D01*
X-278324Y560957D01*
X-277658Y561040D01*
X-277074Y560957D01*
X-276574Y560624D01*
X-276324Y560040D01*
Y557707D01*
G01X-265041Y562707D02*
Y557707D01*
G01Y558457D02*
X-265374Y558040D01*
X-265874Y557790D01*
X-266458Y557707D01*
X-267124Y557874D01*
X-267624Y558290D01*
X-267958Y558790D01*
X-268041Y559374D01*
X-267958Y559957D01*
X-267624Y560457D01*
X-267124Y560874D01*
X-266458Y561040D01*
X-265874Y560957D01*
X-265458Y560790D01*
X-265041Y560457D01*
G01X-260941Y557707D02*
X-261441Y557790D01*
X-261941Y558124D01*
X-262274Y558707D01*
X-262441Y559374D01*
X-262274Y560040D01*
X-261941Y560624D01*
X-261441Y560957D01*
X-260941Y561040D01*
X-260441Y560957D01*
X-259941Y560624D01*
X-259608Y560040D01*
X-259524Y559374D01*
X-259608Y558707D01*
X-259941Y558124D01*
X-260441Y557790D01*
X-260941Y557707D01*
G01X-254008Y560624D02*
X-254591Y560957D01*
X-255091Y561040D01*
X-255758Y560874D01*
X-256258Y560540D01*
X-256591Y559957D01*
X-256674Y559374D01*
X-256591Y558790D01*
X-256258Y558290D01*
X-255758Y557874D01*
X-255091Y557707D01*
X-254508Y557874D01*
X-254008Y558207D01*
G01X-251158Y561040D02*
Y558707D01*
X-250824Y558124D01*
X-250324Y557790D01*
X-249741Y557707D01*
X-249158Y557790D01*
X-248658Y558124D01*
X-248324Y558707D01*
G01Y557707D02*
Y561040D01*
G01X-246641Y557707D02*
Y561040D01*
G01Y560124D02*
X-246391Y560540D01*
X-245974Y560874D01*
X-245391Y561040D01*
X-244808Y560874D01*
X-244391Y560540D01*
X-244141Y560124D01*
Y557707D01*
G01Y560124D02*
X-243891Y560540D01*
X-243474Y560874D01*
X-242891Y561040D01*
X-242308Y560874D01*
X-241891Y560540D01*
X-241641Y560040D01*
Y557707D01*
G01X-239791Y559957D02*
X-237124D01*
X-237374Y560540D01*
X-237791Y560874D01*
X-238374Y561040D01*
X-238958Y560957D01*
X-239458Y560707D01*
X-239791Y560124D01*
X-239958Y559624D01*
Y559124D01*
X-239791Y558624D01*
X-239374Y558124D01*
X-238874Y557790D01*
X-238291Y557707D01*
X-237708Y557874D01*
X-237124Y558374D01*
G01X-234358Y557707D02*
Y561040D01*
G01Y560207D02*
X-234024Y560624D01*
X-233524Y560957D01*
X-232858Y561040D01*
X-232274Y560957D01*
X-231774Y560624D01*
X-231524Y560040D01*
Y557707D01*
G01X-227341Y562707D02*
Y557707D01*
G01X-228508Y561040D02*
X-226174D01*
G01X-222991Y558290D02*
X-222574Y557957D01*
X-221991Y557707D01*
X-221491D01*
X-220991Y557874D01*
X-220658Y558124D01*
X-220491Y558457D01*
X-220574Y558957D01*
X-220908Y559207D01*
X-222408Y559707D01*
X-222741Y560290D01*
X-222574Y560707D01*
X-222241Y560957D01*
X-221741Y561040D01*
X-221241Y560957D01*
X-220741Y560707D01*
G01X-210541Y561040D02*
Y557707D01*
G01Y562374D02*
X-210708Y562457D01*
Y562624D01*
X-210541Y562707D01*
X-210374Y562624D01*
Y562457D01*
X-210541Y562374D01*
G01X-206358Y557707D02*
Y561040D01*
G01Y560207D02*
X-206024Y560624D01*
X-205524Y560957D01*
X-204858Y561040D01*
X-204274Y560957D01*
X-203774Y560624D01*
X-203524Y560040D01*
Y557707D01*
G01X-192408Y560624D02*
X-192991Y560957D01*
X-193491Y561040D01*
X-194158Y560874D01*
X-194658Y560540D01*
X-194991Y559957D01*
X-195074Y559374D01*
X-194991Y558790D01*
X-194658Y558290D01*
X-194158Y557874D01*
X-193491Y557707D01*
X-192908Y557874D01*
X-192408Y558207D01*
G01X-188141Y557707D02*
Y562707D01*
G01X-181041Y557707D02*
Y561040D01*
G01Y560457D02*
X-181374Y560790D01*
X-181874Y560957D01*
X-182458Y561040D01*
X-183041Y560874D01*
X-183541Y560540D01*
X-183874Y560040D01*
X-184041Y559374D01*
X-183874Y558707D01*
X-183541Y558207D01*
X-183041Y557874D01*
X-182458Y557707D01*
X-181874Y557790D01*
X-181374Y558040D01*
X-181041Y558374D01*
G01X-178191Y558290D02*
X-177774Y557957D01*
X-177191Y557707D01*
X-176691D01*
X-176191Y557874D01*
X-175858Y558124D01*
X-175691Y558457D01*
X-175774Y558957D01*
X-176108Y559207D01*
X-177608Y559707D01*
X-177941Y560290D01*
X-177774Y560707D01*
X-177441Y560957D01*
X-176941Y561040D01*
X-176441Y560957D01*
X-175941Y560707D01*
G01X-172591Y558290D02*
X-172174Y557957D01*
X-171591Y557707D01*
X-171091D01*
X-170591Y557874D01*
X-170258Y558124D01*
X-170091Y558457D01*
X-170174Y558957D01*
X-170508Y559207D01*
X-172008Y559707D01*
X-172341Y560290D01*
X-172174Y560707D01*
X-171841Y560957D01*
X-171341Y561040D01*
X-170841Y560957D01*
X-170341Y560707D01*
G01X-161724Y561874D02*
X-161224Y562374D01*
X-160641Y562624D01*
X-159974Y562707D01*
X-159141Y562540D01*
X-158558Y562124D01*
X-158391Y561624D01*
X-158474Y561124D01*
X-158808Y560707D01*
X-160474Y559874D01*
X-161224Y559290D01*
X-161724Y558457D01*
X-161891Y557707D01*
X-158391D01*
G01X-147441D02*
Y561040D01*
G01Y560457D02*
X-147774Y560790D01*
X-148274Y560957D01*
X-148858Y561040D01*
X-149441Y560874D01*
X-149941Y560540D01*
X-150274Y560040D01*
X-150441Y559374D01*
X-150274Y558707D01*
X-149941Y558207D01*
X-149441Y557874D01*
X-148858Y557707D01*
X-148274Y557790D01*
X-147774Y558040D01*
X-147441Y558374D01*
G01X-144758Y557707D02*
Y561040D01*
G01Y560207D02*
X-144424Y560624D01*
X-143924Y560957D01*
X-143258Y561040D01*
X-142674Y560957D01*
X-142174Y560624D01*
X-141924Y560040D01*
Y557707D01*
G01X-136241Y562707D02*
Y557707D01*
G01Y558457D02*
X-136574Y558040D01*
X-137074Y557790D01*
X-137658Y557707D01*
X-138324Y557874D01*
X-138824Y558290D01*
X-139158Y558790D01*
X-139241Y559374D01*
X-139158Y559957D01*
X-138824Y560457D01*
X-138324Y560874D01*
X-137658Y561040D01*
X-137074Y560957D01*
X-136658Y560790D01*
X-136241Y560457D01*
G01X-126541Y562707D02*
Y557707D01*
G01X-127708Y561040D02*
X-125374D01*
G01X-122358Y557707D02*
Y562707D01*
G01Y560290D02*
X-121941Y560707D01*
X-121524Y560957D01*
X-120858Y561040D01*
X-120358Y560957D01*
X-119774Y560624D01*
X-119524Y560124D01*
Y557707D01*
G01X-116591Y559957D02*
X-113924D01*
X-114174Y560540D01*
X-114591Y560874D01*
X-115174Y561040D01*
X-115758Y560957D01*
X-116258Y560707D01*
X-116591Y560124D01*
X-116758Y559624D01*
Y559124D01*
X-116591Y558624D01*
X-116174Y558124D01*
X-115674Y557790D01*
X-115091Y557707D01*
X-114508Y557874D01*
X-113924Y558374D01*
G01X-104141Y557707D02*
Y562707D01*
G01X-97041Y557707D02*
Y561040D01*
G01Y560457D02*
X-97374Y560790D01*
X-97874Y560957D01*
X-98458Y561040D01*
X-99041Y560874D01*
X-99541Y560540D01*
X-99874Y560040D01*
X-100041Y559374D01*
X-99874Y558707D01*
X-99541Y558207D01*
X-99041Y557874D01*
X-98458Y557707D01*
X-97874Y557790D01*
X-97374Y558040D01*
X-97041Y558374D01*
G01X-92941Y562707D02*
Y557707D01*
G01X-94108Y561040D02*
X-91774D01*
G01X-88591Y559957D02*
X-85924D01*
X-86174Y560540D01*
X-86591Y560874D01*
X-87174Y561040D01*
X-87758Y560957D01*
X-88258Y560707D01*
X-88591Y560124D01*
X-88758Y559624D01*
Y559124D01*
X-88591Y558624D01*
X-88174Y558124D01*
X-87674Y557790D01*
X-87091Y557707D01*
X-86508Y557874D01*
X-85924Y558374D01*
G01X-82991Y558290D02*
X-82574Y557957D01*
X-81991Y557707D01*
X-81491D01*
X-80991Y557874D01*
X-80658Y558124D01*
X-80491Y558457D01*
X-80574Y558957D01*
X-80908Y559207D01*
X-82408Y559707D01*
X-82741Y560290D01*
X-82574Y560707D01*
X-82241Y560957D01*
X-81741Y561040D01*
X-81241Y560957D01*
X-80741Y560707D01*
G01X-76141Y562707D02*
Y557707D01*
G01X-77308Y561040D02*
X-74974D01*
G01X-66441D02*
X-64941Y557707D01*
X-63441Y561040D01*
G01X-60591Y559957D02*
X-57924D01*
X-58174Y560540D01*
X-58591Y560874D01*
X-59174Y561040D01*
X-59758Y560957D01*
X-60258Y560707D01*
X-60591Y560124D01*
X-60758Y559624D01*
Y559124D01*
X-60591Y558624D01*
X-60174Y558124D01*
X-59674Y557790D01*
X-59091Y557707D01*
X-58508Y557874D01*
X-57924Y558374D01*
G01X-54908Y557707D02*
Y561040D01*
G01Y560374D02*
X-54491Y560707D01*
X-54074Y560957D01*
X-53491Y561040D01*
X-53074Y560957D01*
X-52574Y560707D01*
G01X-49391Y558290D02*
X-48974Y557957D01*
X-48391Y557707D01*
X-47891D01*
X-47391Y557874D01*
X-47058Y558124D01*
X-46891Y558457D01*
X-46974Y558957D01*
X-47308Y559207D01*
X-48808Y559707D01*
X-49141Y560290D01*
X-48974Y560707D01*
X-48641Y560957D01*
X-48141Y561040D01*
X-47641Y560957D01*
X-47141Y560707D01*
G01X-42541Y561040D02*
Y557707D01*
G01Y562374D02*
X-42708Y562457D01*
Y562624D01*
X-42541Y562707D01*
X-42374Y562624D01*
Y562457D01*
X-42541Y562374D01*
G01X-36941Y557707D02*
X-37441Y557790D01*
X-37941Y558124D01*
X-38274Y558707D01*
X-38441Y559374D01*
X-38274Y560040D01*
X-37941Y560624D01*
X-37441Y560957D01*
X-36941Y561040D01*
X-36441Y560957D01*
X-35941Y560624D01*
X-35608Y560040D01*
X-35524Y559374D01*
X-35608Y558707D01*
X-35941Y558124D01*
X-36441Y557790D01*
X-36941Y557707D01*
G01X-32758D02*
Y561040D01*
G01Y560207D02*
X-32424Y560624D01*
X-31924Y560957D01*
X-31258Y561040D01*
X-30674Y560957D01*
X-30174Y560624D01*
X-29924Y560040D01*
Y557707D01*
G01X-20141Y561040D02*
Y557707D01*
G01Y562374D02*
X-20308Y562457D01*
Y562624D01*
X-20141Y562707D01*
X-19974Y562624D01*
Y562457D01*
X-20141Y562374D01*
G01X-15791Y558290D02*
X-15374Y557957D01*
X-14791Y557707D01*
X-14291D01*
X-13791Y557874D01*
X-13458Y558124D01*
X-13291Y558457D01*
X-13374Y558957D01*
X-13708Y559207D01*
X-15208Y559707D01*
X-15541Y560290D01*
X-15374Y560707D01*
X-15041Y560957D01*
X-14541Y561040D01*
X-14041Y560957D01*
X-13541Y560707D01*
G01X-4508Y557707D02*
Y561040D01*
G01Y560374D02*
X-4091Y560707D01*
X-3674Y560957D01*
X-3091Y561040D01*
X-2674Y560957D01*
X-2174Y560707D01*
G01X1009Y559957D02*
X3676D01*
X3426Y560540D01*
X3009Y560874D01*
X2426Y561040D01*
X1842Y560957D01*
X1342Y560707D01*
X1009Y560124D01*
X842Y559624D01*
Y559124D01*
X1009Y558624D01*
X1426Y558124D01*
X1926Y557790D01*
X2509Y557707D01*
X3092Y557874D01*
X3676Y558374D01*
G01X9359Y556040D02*
Y561040D01*
G01Y560290D02*
X8942Y560707D01*
X8442Y560957D01*
X7859Y561040D01*
X7359Y560957D01*
X6776Y560540D01*
X6442Y559957D01*
X6359Y559374D01*
X6442Y558790D01*
X6776Y558207D01*
X7359Y557790D01*
X7859Y557707D01*
X8442Y557790D01*
X8942Y558040D01*
X9359Y558457D01*
G01X12042Y561040D02*
Y558707D01*
X12376Y558124D01*
X12876Y557790D01*
X13459Y557707D01*
X14042Y557790D01*
X14542Y558124D01*
X14876Y558707D01*
G01Y557707D02*
Y561040D01*
G01X19059D02*
Y557707D01*
G01Y562374D02*
X18892Y562457D01*
Y562624D01*
X19059Y562707D01*
X19226Y562624D01*
Y562457D01*
X19059Y562374D01*
G01X23492Y557707D02*
Y561040D01*
G01Y560374D02*
X23909Y560707D01*
X24326Y560957D01*
X24909Y561040D01*
X25326Y560957D01*
X25826Y560707D01*
G01X29009Y559957D02*
X31676D01*
X31426Y560540D01*
X31009Y560874D01*
X30426Y561040D01*
X29842Y560957D01*
X29342Y560707D01*
X29009Y560124D01*
X28842Y559624D01*
Y559124D01*
X29009Y558624D01*
X29426Y558124D01*
X29926Y557790D01*
X30509Y557707D01*
X31092Y557874D01*
X31676Y558374D01*
G01X37359Y562707D02*
Y557707D01*
G01Y558457D02*
X37026Y558040D01*
X36526Y557790D01*
X35942Y557707D01*
X35276Y557874D01*
X34776Y558290D01*
X34442Y558790D01*
X34359Y559374D01*
X34442Y559957D01*
X34776Y560457D01*
X35276Y560874D01*
X35942Y561040D01*
X36526Y560957D01*
X36942Y560790D01*
X37359Y560457D01*
G01X41292Y556790D02*
X41626Y557874D01*
G01X-344908Y419290D02*
X-345408Y419540D01*
X-345991Y419707D01*
X-346658D01*
X-347408Y419457D01*
X-347991Y419040D01*
X-348408Y418540D01*
X-348741Y417707D01*
X-348824Y416957D01*
X-348658Y416207D01*
X-348408Y415707D01*
X-347908Y415207D01*
X-347324Y414874D01*
X-346741Y414707D01*
X-346158D01*
X-345574Y414874D01*
X-345074Y415124D01*
X-344658Y415457D01*
G01X-341141Y414707D02*
Y419707D01*
G01X-334041Y414707D02*
Y418040D01*
G01Y417457D02*
X-334374Y417790D01*
X-334874Y417957D01*
X-335458Y418040D01*
X-336041Y417874D01*
X-336541Y417540D01*
X-336874Y417040D01*
X-337041Y416374D01*
X-336874Y415707D01*
X-336541Y415207D01*
X-336041Y414874D01*
X-335458Y414707D01*
X-334874Y414790D01*
X-334374Y415040D01*
X-334041Y415374D01*
G01X-331191Y415290D02*
X-330774Y414957D01*
X-330191Y414707D01*
X-329691D01*
X-329191Y414874D01*
X-328858Y415124D01*
X-328691Y415457D01*
X-328774Y415957D01*
X-329108Y416207D01*
X-330608Y416707D01*
X-330941Y417290D01*
X-330774Y417707D01*
X-330441Y417957D01*
X-329941Y418040D01*
X-329441Y417957D01*
X-328941Y417707D01*
G01X-325591Y415290D02*
X-325174Y414957D01*
X-324591Y414707D01*
X-324091D01*
X-323591Y414874D01*
X-323258Y415124D01*
X-323091Y415457D01*
X-323174Y415957D01*
X-323508Y416207D01*
X-325008Y416707D01*
X-325341Y417290D01*
X-325174Y417707D01*
X-324841Y417957D01*
X-324341Y418040D01*
X-323841Y417957D01*
X-323341Y417707D01*
G01X-318741Y418040D02*
Y414707D01*
G01Y419374D02*
X-318908Y419457D01*
Y419624D01*
X-318741Y419707D01*
X-318574Y419624D01*
Y419457D01*
X-318741Y419374D01*
G01X-313641Y414707D02*
Y418957D01*
X-313474Y419374D01*
X-313141Y419624D01*
X-312641Y419707D01*
X-312141Y419540D01*
X-311891Y419124D01*
G01X-312891Y417707D02*
X-314558D01*
G01X-309291Y413207D02*
X-308791Y413040D01*
X-308124Y413207D01*
X-307708Y413540D01*
X-307374Y413957D01*
X-306874Y415290D01*
X-305791Y418040D01*
G01X-308458D02*
X-306874Y415290D01*
G01X-231241Y-312293D02*
Y-308960D01*
G01Y-309543D02*
X-231574Y-309210D01*
X-232074Y-309043D01*
X-232658Y-308960D01*
X-233241Y-309126D01*
X-233741Y-309460D01*
X-234074Y-309960D01*
X-234241Y-310626D01*
X-234074Y-311293D01*
X-233741Y-311793D01*
X-233241Y-312126D01*
X-232658Y-312293D01*
X-232074Y-312210D01*
X-231574Y-311960D01*
X-231241Y-311626D01*
G01X-225641Y-307293D02*
Y-312293D01*
G01Y-311543D02*
X-225974Y-311960D01*
X-226474Y-312210D01*
X-227058Y-312293D01*
X-227724Y-312126D01*
X-228224Y-311710D01*
X-228558Y-311210D01*
X-228641Y-310626D01*
X-228558Y-310043D01*
X-228224Y-309543D01*
X-227724Y-309126D01*
X-227058Y-308960D01*
X-226474Y-309043D01*
X-226058Y-309210D01*
X-225641Y-309543D01*
G01X-220041Y-307293D02*
Y-312293D01*
G01Y-311543D02*
X-220374Y-311960D01*
X-220874Y-312210D01*
X-221458Y-312293D01*
X-222124Y-312126D01*
X-222624Y-311710D01*
X-222958Y-311210D01*
X-223041Y-310626D01*
X-222958Y-310043D01*
X-222624Y-309543D01*
X-222124Y-309126D01*
X-221458Y-308960D01*
X-220874Y-309043D01*
X-220458Y-309210D01*
X-220041Y-309543D01*
G01X-211591Y-311710D02*
X-211174Y-312043D01*
X-210591Y-312293D01*
X-210091D01*
X-209591Y-312126D01*
X-209258Y-311876D01*
X-209091Y-311543D01*
X-209174Y-311043D01*
X-209508Y-310793D01*
X-211008Y-310293D01*
X-211341Y-309710D01*
X-211174Y-309293D01*
X-210841Y-309043D01*
X-210341Y-308960D01*
X-209841Y-309043D01*
X-209341Y-309293D01*
G01X-206158Y-308960D02*
Y-311293D01*
X-205824Y-311876D01*
X-205324Y-312210D01*
X-204741Y-312293D01*
X-204158Y-312210D01*
X-203658Y-311876D01*
X-203324Y-311293D01*
G01Y-312293D02*
Y-308960D01*
G01X-200641Y-313960D02*
Y-308960D01*
G01Y-309710D02*
X-200224Y-309293D01*
X-199808Y-309043D01*
X-199141Y-308960D01*
X-198558Y-309043D01*
X-197974Y-309460D01*
X-197724Y-310043D01*
X-197641Y-310626D01*
X-197724Y-311210D01*
X-197974Y-311793D01*
X-198474Y-312126D01*
X-199141Y-312293D01*
X-199724Y-312210D01*
X-200308Y-311960D01*
X-200641Y-311626D01*
G01X-195041Y-313960D02*
Y-308960D01*
G01Y-309710D02*
X-194624Y-309293D01*
X-194208Y-309043D01*
X-193541Y-308960D01*
X-192958Y-309043D01*
X-192374Y-309460D01*
X-192124Y-310043D01*
X-192041Y-310626D01*
X-192124Y-311210D01*
X-192374Y-311793D01*
X-192874Y-312126D01*
X-193541Y-312293D01*
X-194124Y-312210D01*
X-194708Y-311960D01*
X-195041Y-311626D01*
G01X-187941Y-312293D02*
Y-307293D01*
G01X-182341Y-308960D02*
Y-312293D01*
G01Y-307626D02*
X-182508Y-307543D01*
Y-307376D01*
X-182341Y-307293D01*
X-182174Y-307376D01*
Y-307543D01*
X-182341Y-307626D01*
G01X-177991Y-310043D02*
X-175324D01*
X-175574Y-309460D01*
X-175991Y-309126D01*
X-176574Y-308960D01*
X-177158Y-309043D01*
X-177658Y-309293D01*
X-177991Y-309876D01*
X-178158Y-310376D01*
Y-310876D01*
X-177991Y-311376D01*
X-177574Y-311876D01*
X-177074Y-312210D01*
X-176491Y-312293D01*
X-175908Y-312126D01*
X-175324Y-311626D01*
G01X-172308Y-312293D02*
Y-308960D01*
G01Y-309626D02*
X-171891Y-309293D01*
X-171474Y-309043D01*
X-170891Y-308960D01*
X-170474Y-309043D01*
X-169974Y-309293D01*
G01X-165541Y-308960D02*
X-164708Y-307918D01*
Y-307293D01*
X-165333D01*
Y-307918D01*
X-164708D01*
G01X-161191Y-311710D02*
X-160774Y-312043D01*
X-160191Y-312293D01*
X-159691D01*
X-159191Y-312126D01*
X-158858Y-311876D01*
X-158691Y-311543D01*
X-158774Y-311043D01*
X-159108Y-310793D01*
X-160608Y-310293D01*
X-160941Y-309710D01*
X-160774Y-309293D01*
X-160441Y-309043D01*
X-159941Y-308960D01*
X-159441Y-309043D01*
X-158941Y-309293D01*
G01X-150408Y-307293D02*
Y-312293D01*
X-147074D01*
G01X-143141D02*
X-143641Y-312210D01*
X-144141Y-311876D01*
X-144474Y-311293D01*
X-144641Y-310626D01*
X-144474Y-309960D01*
X-144141Y-309376D01*
X-143641Y-309043D01*
X-143141Y-308960D01*
X-142641Y-309043D01*
X-142141Y-309376D01*
X-141808Y-309960D01*
X-141724Y-310626D01*
X-141808Y-311293D01*
X-142141Y-311876D01*
X-142641Y-312210D01*
X-143141Y-312293D01*
G01X-138708Y-313543D02*
X-138124Y-313876D01*
X-137458Y-313960D01*
X-136874Y-313876D01*
X-136374Y-313460D01*
X-136041Y-312876D01*
Y-308960D01*
G01Y-309626D02*
X-136374Y-309293D01*
X-136874Y-309043D01*
X-137458Y-308960D01*
X-138124Y-309126D01*
X-138541Y-309460D01*
X-138874Y-310043D01*
X-139041Y-310626D01*
X-138958Y-311126D01*
X-138624Y-311710D01*
X-138124Y-312126D01*
X-137458Y-312293D01*
X-136958Y-312210D01*
X-136374Y-311876D01*
X-136041Y-311543D01*
G01X-131941Y-312293D02*
X-132441Y-312210D01*
X-132941Y-311876D01*
X-133274Y-311293D01*
X-133441Y-310626D01*
X-133274Y-309960D01*
X-132941Y-309376D01*
X-132441Y-309043D01*
X-131941Y-308960D01*
X-131441Y-309043D01*
X-130941Y-309376D01*
X-130608Y-309960D01*
X-130524Y-310626D01*
X-130608Y-311293D01*
X-130941Y-311876D01*
X-131441Y-312210D01*
X-131941Y-312293D01*
G01X-119241D02*
Y-308960D01*
G01Y-309543D02*
X-119574Y-309210D01*
X-120074Y-309043D01*
X-120658Y-308960D01*
X-121241Y-309126D01*
X-121741Y-309460D01*
X-122074Y-309960D01*
X-122241Y-310626D01*
X-122074Y-311293D01*
X-121741Y-311793D01*
X-121241Y-312126D01*
X-120658Y-312293D01*
X-120074Y-312210D01*
X-119574Y-311960D01*
X-119241Y-311626D01*
G01X-116558Y-312293D02*
Y-308960D01*
G01Y-309793D02*
X-116224Y-309376D01*
X-115724Y-309043D01*
X-115058Y-308960D01*
X-114474Y-309043D01*
X-113974Y-309376D01*
X-113724Y-309960D01*
Y-312293D01*
G01X-108041Y-307293D02*
Y-312293D01*
G01Y-311543D02*
X-108374Y-311960D01*
X-108874Y-312210D01*
X-109458Y-312293D01*
X-110124Y-312126D01*
X-110624Y-311710D01*
X-110958Y-311210D01*
X-111041Y-310626D01*
X-110958Y-310043D01*
X-110624Y-309543D01*
X-110124Y-309126D01*
X-109458Y-308960D01*
X-108874Y-309043D01*
X-108458Y-309210D01*
X-108041Y-309543D01*
G01X-100174Y-307293D02*
Y-310876D01*
X-99841Y-311626D01*
X-99174Y-312126D01*
X-98341Y-312293D01*
X-97508Y-312126D01*
X-96841Y-311626D01*
X-96508Y-310876D01*
Y-307293D01*
G01X-94408D02*
Y-312293D01*
X-91074D01*
G01X-82041D02*
Y-308043D01*
X-81874Y-307626D01*
X-81541Y-307376D01*
X-81041Y-307293D01*
X-80541Y-307460D01*
X-80291Y-307876D01*
G01X-81291Y-309293D02*
X-82958D01*
G01X-75941Y-308960D02*
Y-312293D01*
G01Y-307626D02*
X-76108Y-307543D01*
Y-307376D01*
X-75941Y-307293D01*
X-75774Y-307376D01*
Y-307543D01*
X-75941Y-307626D01*
G01X-70341Y-312293D02*
Y-307293D01*
G01X-65991Y-310043D02*
X-63324D01*
X-63574Y-309460D01*
X-63991Y-309126D01*
X-64574Y-308960D01*
X-65158Y-309043D01*
X-65658Y-309293D01*
X-65991Y-309876D01*
X-66158Y-310376D01*
Y-310876D01*
X-65991Y-311376D01*
X-65574Y-311876D01*
X-65074Y-312210D01*
X-64491Y-312293D01*
X-63908Y-312126D01*
X-63324Y-311626D01*
G01X-55458Y-312293D02*
Y-307293D01*
X-51624Y-312293D01*
Y-307293D01*
G01X-49358Y-308960D02*
Y-311293D01*
X-49024Y-311876D01*
X-48524Y-312210D01*
X-47941Y-312293D01*
X-47358Y-312210D01*
X-46858Y-311876D01*
X-46524Y-311293D01*
G01Y-312293D02*
Y-308960D01*
G01X-44841Y-312293D02*
Y-308960D01*
G01Y-309876D02*
X-44591Y-309460D01*
X-44174Y-309126D01*
X-43591Y-308960D01*
X-43008Y-309126D01*
X-42591Y-309460D01*
X-42341Y-309876D01*
Y-312293D01*
G01Y-309876D02*
X-42091Y-309460D01*
X-41674Y-309126D01*
X-41091Y-308960D01*
X-40508Y-309126D01*
X-40091Y-309460D01*
X-39841Y-309960D01*
Y-312293D01*
G01X-38241D02*
Y-307293D01*
G01Y-309793D02*
X-37824Y-309293D01*
X-37324Y-309043D01*
X-36824Y-308960D01*
X-36074Y-309126D01*
X-35574Y-309460D01*
X-35241Y-310043D01*
Y-310710D01*
X-35408Y-311376D01*
X-35741Y-311876D01*
X-36324Y-312210D01*
X-36824Y-312293D01*
X-37324Y-312210D01*
X-37824Y-311960D01*
X-38241Y-311543D01*
G01X-32391Y-310043D02*
X-29724D01*
X-29974Y-309460D01*
X-30391Y-309126D01*
X-30974Y-308960D01*
X-31558Y-309043D01*
X-32058Y-309293D01*
X-32391Y-309876D01*
X-32558Y-310376D01*
Y-310876D01*
X-32391Y-311376D01*
X-31974Y-311876D01*
X-31474Y-312210D01*
X-30891Y-312293D01*
X-30308Y-312126D01*
X-29724Y-311626D01*
G01X-26708Y-312293D02*
Y-308960D01*
G01Y-309626D02*
X-26291Y-309293D01*
X-25874Y-309043D01*
X-25291Y-308960D01*
X-24874Y-309043D01*
X-24374Y-309293D01*
G01X-14341Y-308960D02*
Y-312293D01*
G01Y-307626D02*
X-14508Y-307543D01*
Y-307376D01*
X-14341Y-307293D01*
X-14174Y-307376D01*
Y-307543D01*
X-14341Y-307626D01*
G01X-10158Y-312293D02*
Y-308960D01*
G01Y-309793D02*
X-9824Y-309376D01*
X-9324Y-309043D01*
X-8658Y-308960D01*
X-8074Y-309043D01*
X-7574Y-309376D01*
X-7324Y-309960D01*
Y-312293D01*
G01X1209Y-311710D02*
X1626Y-312043D01*
X2209Y-312293D01*
X2709D01*
X3209Y-312126D01*
X3542Y-311876D01*
X3709Y-311543D01*
X3626Y-311043D01*
X3292Y-310793D01*
X1792Y-310293D01*
X1459Y-309710D01*
X1626Y-309293D01*
X1959Y-309043D01*
X2459Y-308960D01*
X2959Y-309043D01*
X3459Y-309293D01*
G01X8059Y-308960D02*
Y-312293D01*
G01Y-307626D02*
X7892Y-307543D01*
Y-307376D01*
X8059Y-307293D01*
X8226Y-307376D01*
Y-307543D01*
X8059Y-307626D01*
G01X13659Y-312293D02*
Y-307293D01*
G01X17842Y-312293D02*
Y-307293D01*
G01X20509Y-308960D02*
X17842Y-310876D01*
G01X18926Y-310126D02*
X20676Y-312293D01*
G01X23609Y-311710D02*
X24026Y-312043D01*
X24609Y-312293D01*
X25109D01*
X25609Y-312126D01*
X25942Y-311876D01*
X26109Y-311543D01*
X26026Y-311043D01*
X25692Y-310793D01*
X24192Y-310293D01*
X23859Y-309710D01*
X24026Y-309293D01*
X24359Y-309043D01*
X24859Y-308960D01*
X25359Y-309043D01*
X25859Y-309293D01*
G01X31792Y-309376D02*
X31209Y-309043D01*
X30709Y-308960D01*
X30042Y-309126D01*
X29542Y-309460D01*
X29209Y-310043D01*
X29126Y-310626D01*
X29209Y-311210D01*
X29542Y-311710D01*
X30042Y-312126D01*
X30709Y-312293D01*
X31292Y-312126D01*
X31792Y-311793D01*
G01X34892Y-312293D02*
Y-308960D01*
G01Y-309626D02*
X35309Y-309293D01*
X35726Y-309043D01*
X36309Y-308960D01*
X36726Y-309043D01*
X37226Y-309293D01*
G01X40409Y-310043D02*
X43076D01*
X42826Y-309460D01*
X42409Y-309126D01*
X41826Y-308960D01*
X41242Y-309043D01*
X40742Y-309293D01*
X40409Y-309876D01*
X40242Y-310376D01*
Y-310876D01*
X40409Y-311376D01*
X40826Y-311876D01*
X41326Y-312210D01*
X41909Y-312293D01*
X42492Y-312126D01*
X43076Y-311626D01*
G01X46009Y-310043D02*
X48676D01*
X48426Y-309460D01*
X48009Y-309126D01*
X47426Y-308960D01*
X46842Y-309043D01*
X46342Y-309293D01*
X46009Y-309876D01*
X45842Y-310376D01*
Y-310876D01*
X46009Y-311376D01*
X46426Y-311876D01*
X46926Y-312210D01*
X47509Y-312293D01*
X48092Y-312126D01*
X48676Y-311626D01*
G01X51442Y-312293D02*
Y-308960D01*
G01Y-309793D02*
X51776Y-309376D01*
X52276Y-309043D01*
X52942Y-308960D01*
X53526Y-309043D01*
X54026Y-309376D01*
X54276Y-309960D01*
Y-312293D01*
G01X-242741Y-318293D02*
Y190207D01*
G01X-234491Y-296626D02*
X-233824Y-297043D01*
X-233074Y-297293D01*
X-232408D01*
X-231741Y-297043D01*
X-231241Y-296626D01*
X-230991Y-296043D01*
X-231158Y-295460D01*
X-231574Y-294960D01*
X-232324Y-294626D01*
X-233324Y-294460D01*
X-233908Y-294126D01*
X-234158Y-293543D01*
X-233991Y-292960D01*
X-233574Y-292543D01*
X-232991Y-292293D01*
X-232408D01*
X-231824Y-292460D01*
X-231324Y-292876D01*
G01X-227141Y-297293D02*
X-227641Y-297210D01*
X-228141Y-296876D01*
X-228474Y-296293D01*
X-228641Y-295626D01*
X-228474Y-294960D01*
X-228141Y-294376D01*
X-227641Y-294043D01*
X-227141Y-293960D01*
X-226641Y-294043D01*
X-226141Y-294376D01*
X-225808Y-294960D01*
X-225724Y-295626D01*
X-225808Y-296293D01*
X-226141Y-296876D01*
X-226641Y-297210D01*
X-227141Y-297293D01*
G01X-221541D02*
Y-292293D01*
G01X-214441D02*
Y-297293D01*
G01Y-296543D02*
X-214774Y-296960D01*
X-215274Y-297210D01*
X-215858Y-297293D01*
X-216524Y-297126D01*
X-217024Y-296710D01*
X-217358Y-296210D01*
X-217441Y-295626D01*
X-217358Y-295043D01*
X-217024Y-294543D01*
X-216524Y-294126D01*
X-215858Y-293960D01*
X-215274Y-294043D01*
X-214858Y-294210D01*
X-214441Y-294543D01*
G01X-211591Y-295043D02*
X-208924D01*
X-209174Y-294460D01*
X-209591Y-294126D01*
X-210174Y-293960D01*
X-210758Y-294043D01*
X-211258Y-294293D01*
X-211591Y-294876D01*
X-211758Y-295376D01*
Y-295876D01*
X-211591Y-296376D01*
X-211174Y-296876D01*
X-210674Y-297210D01*
X-210091Y-297293D01*
X-209508Y-297126D01*
X-208924Y-296626D01*
G01X-205908Y-297293D02*
Y-293960D01*
G01Y-294626D02*
X-205491Y-294293D01*
X-205074Y-294043D01*
X-204491Y-293960D01*
X-204074Y-294043D01*
X-203574Y-294293D01*
G01X-196041Y-297293D02*
Y-293960D01*
G01Y-294876D02*
X-195791Y-294460D01*
X-195374Y-294126D01*
X-194791Y-293960D01*
X-194208Y-294126D01*
X-193791Y-294460D01*
X-193541Y-294876D01*
Y-297293D01*
G01Y-294876D02*
X-193291Y-294460D01*
X-192874Y-294126D01*
X-192291Y-293960D01*
X-191708Y-294126D01*
X-191291Y-294460D01*
X-191041Y-294960D01*
Y-297293D01*
G01X-186441D02*
Y-293960D01*
G01Y-294543D02*
X-186774Y-294210D01*
X-187274Y-294043D01*
X-187858Y-293960D01*
X-188441Y-294126D01*
X-188941Y-294460D01*
X-189274Y-294960D01*
X-189441Y-295626D01*
X-189274Y-296293D01*
X-188941Y-296793D01*
X-188441Y-297126D01*
X-187858Y-297293D01*
X-187274Y-297210D01*
X-186774Y-296960D01*
X-186441Y-296626D01*
G01X-183591Y-296710D02*
X-183174Y-297043D01*
X-182591Y-297293D01*
X-182091D01*
X-181591Y-297126D01*
X-181258Y-296876D01*
X-181091Y-296543D01*
X-181174Y-296043D01*
X-181508Y-295793D01*
X-183008Y-295293D01*
X-183341Y-294710D01*
X-183174Y-294293D01*
X-182841Y-294043D01*
X-182341Y-293960D01*
X-181841Y-294043D01*
X-181341Y-294293D01*
G01X-178158Y-297293D02*
Y-292293D01*
G01X-175491Y-293960D02*
X-178158Y-295876D01*
G01X-177074Y-295126D02*
X-175324Y-297293D01*
G01X-165541Y-292293D02*
Y-297293D01*
G01X-166708Y-293960D02*
X-164374D01*
G01X-161358Y-297293D02*
Y-292293D01*
G01Y-294710D02*
X-160941Y-294293D01*
X-160524Y-294043D01*
X-159858Y-293960D01*
X-159358Y-294043D01*
X-158774Y-294376D01*
X-158524Y-294876D01*
Y-297293D01*
G01X-154341Y-293960D02*
Y-297293D01*
G01Y-292626D02*
X-154508Y-292543D01*
Y-292376D01*
X-154341Y-292293D01*
X-154174Y-292376D01*
Y-292543D01*
X-154341Y-292626D01*
G01X-147408Y-294376D02*
X-147991Y-294043D01*
X-148491Y-293960D01*
X-149158Y-294126D01*
X-149658Y-294460D01*
X-149991Y-295043D01*
X-150074Y-295626D01*
X-149991Y-296210D01*
X-149658Y-296710D01*
X-149158Y-297126D01*
X-148491Y-297293D01*
X-147908Y-297126D01*
X-147408Y-296793D01*
G01X-144558Y-297293D02*
Y-292293D01*
G01X-141891Y-293960D02*
X-144558Y-295876D01*
G01X-143474Y-295126D02*
X-141724Y-297293D01*
G01X-138958D02*
Y-293960D01*
G01Y-294793D02*
X-138624Y-294376D01*
X-138124Y-294043D01*
X-137458Y-293960D01*
X-136874Y-294043D01*
X-136374Y-294376D01*
X-136124Y-294960D01*
Y-297293D01*
G01X-133191Y-295043D02*
X-130524D01*
X-130774Y-294460D01*
X-131191Y-294126D01*
X-131774Y-293960D01*
X-132358Y-294043D01*
X-132858Y-294293D01*
X-133191Y-294876D01*
X-133358Y-295376D01*
Y-295876D01*
X-133191Y-296376D01*
X-132774Y-296876D01*
X-132274Y-297210D01*
X-131691Y-297293D01*
X-131108Y-297126D01*
X-130524Y-296626D01*
G01X-127591Y-296710D02*
X-127174Y-297043D01*
X-126591Y-297293D01*
X-126091D01*
X-125591Y-297126D01*
X-125258Y-296876D01*
X-125091Y-296543D01*
X-125174Y-296043D01*
X-125508Y-295793D01*
X-127008Y-295293D01*
X-127341Y-294710D01*
X-127174Y-294293D01*
X-126841Y-294043D01*
X-126341Y-293960D01*
X-125841Y-294043D01*
X-125341Y-294293D01*
G01X-121991Y-296710D02*
X-121574Y-297043D01*
X-120991Y-297293D01*
X-120491D01*
X-119991Y-297126D01*
X-119658Y-296876D01*
X-119491Y-296543D01*
X-119574Y-296043D01*
X-119908Y-295793D01*
X-121408Y-295293D01*
X-121741Y-294710D01*
X-121574Y-294293D01*
X-121241Y-294043D01*
X-120741Y-293960D01*
X-120241Y-294043D01*
X-119741Y-294293D01*
G01X-111041Y-298960D02*
Y-293960D01*
G01Y-294710D02*
X-110624Y-294293D01*
X-110208Y-294043D01*
X-109541Y-293960D01*
X-108958Y-294043D01*
X-108374Y-294460D01*
X-108124Y-295043D01*
X-108041Y-295626D01*
X-108124Y-296210D01*
X-108374Y-296793D01*
X-108874Y-297126D01*
X-109541Y-297293D01*
X-110124Y-297210D01*
X-110708Y-296960D01*
X-111041Y-296626D01*
G01X-103941Y-297293D02*
Y-292293D01*
G01X-99758Y-293960D02*
Y-296293D01*
X-99424Y-296876D01*
X-98924Y-297210D01*
X-98341Y-297293D01*
X-97758Y-297210D01*
X-97258Y-296876D01*
X-96924Y-296293D01*
G01Y-297293D02*
Y-293960D01*
G01X-93991Y-296710D02*
X-93574Y-297043D01*
X-92991Y-297293D01*
X-92491D01*
X-91991Y-297126D01*
X-91658Y-296876D01*
X-91491Y-296543D01*
X-91574Y-296043D01*
X-91908Y-295793D01*
X-93408Y-295293D01*
X-93741Y-294710D01*
X-93574Y-294293D01*
X-93241Y-294043D01*
X-92741Y-293960D01*
X-92241Y-294043D01*
X-91741Y-294293D01*
G01X-81541Y-297293D02*
Y-292293D01*
G01X-77191Y-295043D02*
X-74524D01*
X-74774Y-294460D01*
X-75191Y-294126D01*
X-75774Y-293960D01*
X-76358Y-294043D01*
X-76858Y-294293D01*
X-77191Y-294876D01*
X-77358Y-295376D01*
Y-295876D01*
X-77191Y-296376D01*
X-76774Y-296876D01*
X-76274Y-297210D01*
X-75691Y-297293D01*
X-75108Y-297126D01*
X-74524Y-296626D01*
G01X-71508Y-298543D02*
X-70924Y-298876D01*
X-70258Y-298960D01*
X-69674Y-298876D01*
X-69174Y-298460D01*
X-68841Y-297876D01*
Y-293960D01*
G01Y-294626D02*
X-69174Y-294293D01*
X-69674Y-294043D01*
X-70258Y-293960D01*
X-70924Y-294126D01*
X-71341Y-294460D01*
X-71674Y-295043D01*
X-71841Y-295626D01*
X-71758Y-296126D01*
X-71424Y-296710D01*
X-70924Y-297126D01*
X-70258Y-297293D01*
X-69758Y-297210D01*
X-69174Y-296876D01*
X-68841Y-296543D01*
G01X-65991Y-295043D02*
X-63324D01*
X-63574Y-294460D01*
X-63991Y-294126D01*
X-64574Y-293960D01*
X-65158Y-294043D01*
X-65658Y-294293D01*
X-65991Y-294876D01*
X-66158Y-295376D01*
Y-295876D01*
X-65991Y-296376D01*
X-65574Y-296876D01*
X-65074Y-297210D01*
X-64491Y-297293D01*
X-63908Y-297126D01*
X-63324Y-296626D01*
G01X-60558Y-297293D02*
Y-293960D01*
G01Y-294793D02*
X-60224Y-294376D01*
X-59724Y-294043D01*
X-59058Y-293960D01*
X-58474Y-294043D01*
X-57974Y-294376D01*
X-57724Y-294960D01*
Y-297293D01*
G01X-52041Y-292293D02*
Y-297293D01*
G01Y-296543D02*
X-52374Y-296960D01*
X-52874Y-297210D01*
X-53458Y-297293D01*
X-54124Y-297126D01*
X-54624Y-296710D01*
X-54958Y-296210D01*
X-55041Y-295626D01*
X-54958Y-295043D01*
X-54624Y-294543D01*
X-54124Y-294126D01*
X-53458Y-293960D01*
X-52874Y-294043D01*
X-52458Y-294210D01*
X-52041Y-294543D01*
G01X-42341Y-292293D02*
Y-297293D01*
G01X-43508Y-293960D02*
X-41174D01*
G01X-38158Y-297293D02*
Y-292293D01*
G01Y-294710D02*
X-37741Y-294293D01*
X-37324Y-294043D01*
X-36658Y-293960D01*
X-36158Y-294043D01*
X-35574Y-294376D01*
X-35324Y-294876D01*
Y-297293D01*
G01X-31141Y-293960D02*
Y-297293D01*
G01Y-292626D02*
X-31308Y-292543D01*
Y-292376D01*
X-31141Y-292293D01*
X-30974Y-292376D01*
Y-292543D01*
X-31141Y-292626D01*
G01X-24208Y-294376D02*
X-24791Y-294043D01*
X-25291Y-293960D01*
X-25958Y-294126D01*
X-26458Y-294460D01*
X-26791Y-295043D01*
X-26874Y-295626D01*
X-26791Y-296210D01*
X-26458Y-296710D01*
X-25958Y-297126D01*
X-25291Y-297293D01*
X-24708Y-297126D01*
X-24208Y-296793D01*
G01X-21358Y-297293D02*
Y-292293D01*
G01X-18691Y-293960D02*
X-21358Y-295876D01*
G01X-20274Y-295126D02*
X-18524Y-297293D01*
G01X-15758D02*
Y-293960D01*
G01Y-294793D02*
X-15424Y-294376D01*
X-14924Y-294043D01*
X-14258Y-293960D01*
X-13674Y-294043D01*
X-13174Y-294376D01*
X-12924Y-294960D01*
Y-297293D01*
G01X-9991Y-295043D02*
X-7324D01*
X-7574Y-294460D01*
X-7991Y-294126D01*
X-8574Y-293960D01*
X-9158Y-294043D01*
X-9658Y-294293D01*
X-9991Y-294876D01*
X-10158Y-295376D01*
Y-295876D01*
X-9991Y-296376D01*
X-9574Y-296876D01*
X-9074Y-297210D01*
X-8491Y-297293D01*
X-7908Y-297126D01*
X-7324Y-296626D01*
G01X-4391Y-296710D02*
X-3974Y-297043D01*
X-3391Y-297293D01*
X-2891D01*
X-2391Y-297126D01*
X-2058Y-296876D01*
X-1891Y-296543D01*
X-1974Y-296043D01*
X-2308Y-295793D01*
X-3808Y-295293D01*
X-4141Y-294710D01*
X-3974Y-294293D01*
X-3641Y-294043D01*
X-3141Y-293960D01*
X-2641Y-294043D01*
X-2141Y-294293D01*
G01X1209Y-296710D02*
X1626Y-297043D01*
X2209Y-297293D01*
X2709D01*
X3209Y-297126D01*
X3542Y-296876D01*
X3709Y-296543D01*
X3626Y-296043D01*
X3292Y-295793D01*
X1792Y-295293D01*
X1459Y-294710D01*
X1626Y-294293D01*
X1959Y-294043D01*
X2459Y-293960D01*
X2959Y-294043D01*
X3459Y-294293D01*
G01X13659Y-297293D02*
X13159Y-297210D01*
X12659Y-296876D01*
X12326Y-296293D01*
X12159Y-295626D01*
X12326Y-294960D01*
X12659Y-294376D01*
X13159Y-294043D01*
X13659Y-293960D01*
X14159Y-294043D01*
X14659Y-294376D01*
X14992Y-294960D01*
X15076Y-295626D01*
X14992Y-296293D01*
X14659Y-296876D01*
X14159Y-297210D01*
X13659Y-297293D01*
G01X17842D02*
Y-293960D01*
G01Y-294793D02*
X18176Y-294376D01*
X18676Y-294043D01*
X19342Y-293960D01*
X19926Y-294043D01*
X20426Y-294376D01*
X20676Y-294960D01*
Y-297293D01*
G01X30459Y-292293D02*
Y-297293D01*
G01X29292Y-293960D02*
X31626D01*
G01X34892Y-297293D02*
Y-293960D01*
G01Y-294626D02*
X35309Y-294293D01*
X35726Y-294043D01*
X36309Y-293960D01*
X36726Y-294043D01*
X37226Y-294293D01*
G01X43159Y-297293D02*
Y-293960D01*
G01Y-294543D02*
X42826Y-294210D01*
X42326Y-294043D01*
X41742Y-293960D01*
X41159Y-294126D01*
X40659Y-294460D01*
X40326Y-294960D01*
X40159Y-295626D01*
X40326Y-296293D01*
X40659Y-296793D01*
X41159Y-297126D01*
X41742Y-297293D01*
X42326Y-297210D01*
X42826Y-296960D01*
X43159Y-296626D01*
G01X48592Y-294376D02*
X48009Y-294043D01*
X47509Y-293960D01*
X46842Y-294126D01*
X46342Y-294460D01*
X46009Y-295043D01*
X45926Y-295626D01*
X46009Y-296210D01*
X46342Y-296710D01*
X46842Y-297126D01*
X47509Y-297293D01*
X48092Y-297126D01*
X48592Y-296793D01*
G01X51609Y-295043D02*
X54276D01*
X54026Y-294460D01*
X53609Y-294126D01*
X53026Y-293960D01*
X52442Y-294043D01*
X51942Y-294293D01*
X51609Y-294876D01*
X51442Y-295376D01*
Y-295876D01*
X51609Y-296376D01*
X52026Y-296876D01*
X52526Y-297210D01*
X53109Y-297293D01*
X53692Y-297126D01*
X54276Y-296626D01*
G01X58459Y-297460D02*
X58292Y-297376D01*
Y-297210D01*
X58459Y-297126D01*
X58626Y-297210D01*
Y-297376D01*
X58459Y-297460D01*
G01X-232741Y-282293D02*
Y-277293D01*
G01X-228391Y-280043D02*
X-225724D01*
X-225974Y-279460D01*
X-226391Y-279126D01*
X-226974Y-278960D01*
X-227558Y-279043D01*
X-228058Y-279293D01*
X-228391Y-279876D01*
X-228558Y-280376D01*
Y-280876D01*
X-228391Y-281376D01*
X-227974Y-281876D01*
X-227474Y-282210D01*
X-226891Y-282293D01*
X-226308Y-282126D01*
X-225724Y-281626D01*
G01X-222708Y-283543D02*
X-222124Y-283876D01*
X-221458Y-283960D01*
X-220874Y-283876D01*
X-220374Y-283460D01*
X-220041Y-282876D01*
Y-278960D01*
G01Y-279626D02*
X-220374Y-279293D01*
X-220874Y-279043D01*
X-221458Y-278960D01*
X-222124Y-279126D01*
X-222541Y-279460D01*
X-222874Y-280043D01*
X-223041Y-280626D01*
X-222958Y-281126D01*
X-222624Y-281710D01*
X-222124Y-282126D01*
X-221458Y-282293D01*
X-220958Y-282210D01*
X-220374Y-281876D01*
X-220041Y-281543D01*
G01X-217191Y-280043D02*
X-214524D01*
X-214774Y-279460D01*
X-215191Y-279126D01*
X-215774Y-278960D01*
X-216358Y-279043D01*
X-216858Y-279293D01*
X-217191Y-279876D01*
X-217358Y-280376D01*
Y-280876D01*
X-217191Y-281376D01*
X-216774Y-281876D01*
X-216274Y-282210D01*
X-215691Y-282293D01*
X-215108Y-282126D01*
X-214524Y-281626D01*
G01X-211758Y-282293D02*
Y-278960D01*
G01Y-279793D02*
X-211424Y-279376D01*
X-210924Y-279043D01*
X-210258Y-278960D01*
X-209674Y-279043D01*
X-209174Y-279376D01*
X-208924Y-279960D01*
Y-282293D01*
G01X-203241Y-277293D02*
Y-282293D01*
G01Y-281543D02*
X-203574Y-281960D01*
X-204074Y-282210D01*
X-204658Y-282293D01*
X-205324Y-282126D01*
X-205824Y-281710D01*
X-206158Y-281210D01*
X-206241Y-280626D01*
X-206158Y-280043D01*
X-205824Y-279543D01*
X-205324Y-279126D01*
X-204658Y-278960D01*
X-204074Y-279043D01*
X-203658Y-279210D01*
X-203241Y-279543D01*
G01X-193541Y-277293D02*
Y-282293D01*
G01X-194708Y-278960D02*
X-192374D01*
G01X-189358Y-282293D02*
Y-277293D01*
G01Y-279710D02*
X-188941Y-279293D01*
X-188524Y-279043D01*
X-187858Y-278960D01*
X-187358Y-279043D01*
X-186774Y-279376D01*
X-186524Y-279876D01*
Y-282293D01*
G01X-182341Y-278960D02*
Y-282293D01*
G01Y-277626D02*
X-182508Y-277543D01*
Y-277376D01*
X-182341Y-277293D01*
X-182174Y-277376D01*
Y-277543D01*
X-182341Y-277626D01*
G01X-175408Y-279376D02*
X-175991Y-279043D01*
X-176491Y-278960D01*
X-177158Y-279126D01*
X-177658Y-279460D01*
X-177991Y-280043D01*
X-178074Y-280626D01*
X-177991Y-281210D01*
X-177658Y-281710D01*
X-177158Y-282126D01*
X-176491Y-282293D01*
X-175908Y-282126D01*
X-175408Y-281793D01*
G01X-172558Y-282293D02*
Y-277293D01*
G01X-169891Y-278960D02*
X-172558Y-280876D01*
G01X-171474Y-280126D02*
X-169724Y-282293D01*
G01X-166958D02*
Y-278960D01*
G01Y-279793D02*
X-166624Y-279376D01*
X-166124Y-279043D01*
X-165458Y-278960D01*
X-164874Y-279043D01*
X-164374Y-279376D01*
X-164124Y-279960D01*
Y-282293D01*
G01X-161191Y-280043D02*
X-158524D01*
X-158774Y-279460D01*
X-159191Y-279126D01*
X-159774Y-278960D01*
X-160358Y-279043D01*
X-160858Y-279293D01*
X-161191Y-279876D01*
X-161358Y-280376D01*
Y-280876D01*
X-161191Y-281376D01*
X-160774Y-281876D01*
X-160274Y-282210D01*
X-159691Y-282293D01*
X-159108Y-282126D01*
X-158524Y-281626D01*
G01X-155591Y-281710D02*
X-155174Y-282043D01*
X-154591Y-282293D01*
X-154091D01*
X-153591Y-282126D01*
X-153258Y-281876D01*
X-153091Y-281543D01*
X-153174Y-281043D01*
X-153508Y-280793D01*
X-155008Y-280293D01*
X-155341Y-279710D01*
X-155174Y-279293D01*
X-154841Y-279043D01*
X-154341Y-278960D01*
X-153841Y-279043D01*
X-153341Y-279293D01*
G01X-149991Y-281710D02*
X-149574Y-282043D01*
X-148991Y-282293D01*
X-148491D01*
X-147991Y-282126D01*
X-147658Y-281876D01*
X-147491Y-281543D01*
X-147574Y-281043D01*
X-147908Y-280793D01*
X-149408Y-280293D01*
X-149741Y-279710D01*
X-149574Y-279293D01*
X-149241Y-279043D01*
X-148741Y-278960D01*
X-148241Y-279043D01*
X-147741Y-279293D01*
G01X-137541Y-282293D02*
X-138041Y-282210D01*
X-138541Y-281876D01*
X-138874Y-281293D01*
X-139041Y-280626D01*
X-138874Y-279960D01*
X-138541Y-279376D01*
X-138041Y-279043D01*
X-137541Y-278960D01*
X-137041Y-279043D01*
X-136541Y-279376D01*
X-136208Y-279960D01*
X-136124Y-280626D01*
X-136208Y-281293D01*
X-136541Y-281876D01*
X-137041Y-282210D01*
X-137541Y-282293D01*
G01X-133358D02*
Y-278960D01*
G01Y-279793D02*
X-133024Y-279376D01*
X-132524Y-279043D01*
X-131858Y-278960D01*
X-131274Y-279043D01*
X-130774Y-279376D01*
X-130524Y-279960D01*
Y-282293D01*
G01X-119408Y-279376D02*
X-119991Y-279043D01*
X-120491Y-278960D01*
X-121158Y-279126D01*
X-121658Y-279460D01*
X-121991Y-280043D01*
X-122074Y-280626D01*
X-121991Y-281210D01*
X-121658Y-281710D01*
X-121158Y-282126D01*
X-120491Y-282293D01*
X-119908Y-282126D01*
X-119408Y-281793D01*
G01X-115141Y-282293D02*
X-115641Y-282210D01*
X-116141Y-281876D01*
X-116474Y-281293D01*
X-116641Y-280626D01*
X-116474Y-279960D01*
X-116141Y-279376D01*
X-115641Y-279043D01*
X-115141Y-278960D01*
X-114641Y-279043D01*
X-114141Y-279376D01*
X-113808Y-279960D01*
X-113724Y-280626D01*
X-113808Y-281293D01*
X-114141Y-281876D01*
X-114641Y-282210D01*
X-115141Y-282293D01*
G01X-111041Y-283960D02*
Y-278960D01*
G01Y-279710D02*
X-110624Y-279293D01*
X-110208Y-279043D01*
X-109541Y-278960D01*
X-108958Y-279043D01*
X-108374Y-279460D01*
X-108124Y-280043D01*
X-108041Y-280626D01*
X-108124Y-281210D01*
X-108374Y-281793D01*
X-108874Y-282126D01*
X-109541Y-282293D01*
X-110124Y-282210D01*
X-110708Y-281960D01*
X-111041Y-281626D01*
G01X-105441Y-283960D02*
Y-278960D01*
G01Y-279710D02*
X-105024Y-279293D01*
X-104608Y-279043D01*
X-103941Y-278960D01*
X-103358Y-279043D01*
X-102774Y-279460D01*
X-102524Y-280043D01*
X-102441Y-280626D01*
X-102524Y-281210D01*
X-102774Y-281793D01*
X-103274Y-282126D01*
X-103941Y-282293D01*
X-104524Y-282210D01*
X-105108Y-281960D01*
X-105441Y-281626D01*
G01X-99591Y-280043D02*
X-96924D01*
X-97174Y-279460D01*
X-97591Y-279126D01*
X-98174Y-278960D01*
X-98758Y-279043D01*
X-99258Y-279293D01*
X-99591Y-279876D01*
X-99758Y-280376D01*
Y-280876D01*
X-99591Y-281376D01*
X-99174Y-281876D01*
X-98674Y-282210D01*
X-98091Y-282293D01*
X-97508Y-282126D01*
X-96924Y-281626D01*
G01X-93908Y-282293D02*
Y-278960D01*
G01Y-279626D02*
X-93491Y-279293D01*
X-93074Y-279043D01*
X-92491Y-278960D01*
X-92074Y-279043D01*
X-91574Y-279293D01*
G01X-81958Y-283960D02*
X-82791Y-283126D01*
X-83208Y-282293D01*
Y-278960D01*
X-82791Y-278126D01*
X-81958Y-277293D01*
G01X-78024Y-278960D02*
X-77024Y-282293D01*
X-75941Y-278960D01*
X-74858Y-282293D01*
X-73858Y-278960D01*
G01X-71758Y-282293D02*
Y-277293D01*
G01Y-279710D02*
X-71341Y-279293D01*
X-70924Y-279043D01*
X-70258Y-278960D01*
X-69758Y-279043D01*
X-69174Y-279376D01*
X-68924Y-279876D01*
Y-282293D01*
G01X-64741Y-278960D02*
Y-282293D01*
G01Y-277626D02*
X-64908Y-277543D01*
Y-277376D01*
X-64741Y-277293D01*
X-64574Y-277376D01*
Y-277543D01*
X-64741Y-277626D01*
G01X-57808Y-279376D02*
X-58391Y-279043D01*
X-58891Y-278960D01*
X-59558Y-279126D01*
X-60058Y-279460D01*
X-60391Y-280043D01*
X-60474Y-280626D01*
X-60391Y-281210D01*
X-60058Y-281710D01*
X-59558Y-282126D01*
X-58891Y-282293D01*
X-58308Y-282126D01*
X-57808Y-281793D01*
G01X-54958Y-282293D02*
Y-277293D01*
G01Y-279710D02*
X-54541Y-279293D01*
X-54124Y-279043D01*
X-53458Y-278960D01*
X-52958Y-279043D01*
X-52374Y-279376D01*
X-52124Y-279876D01*
Y-282293D01*
G01X-42341Y-278960D02*
Y-282293D01*
G01Y-277626D02*
X-42508Y-277543D01*
Y-277376D01*
X-42341Y-277293D01*
X-42174Y-277376D01*
Y-277543D01*
X-42341Y-277626D01*
G01X-37991Y-281710D02*
X-37574Y-282043D01*
X-36991Y-282293D01*
X-36491D01*
X-35991Y-282126D01*
X-35658Y-281876D01*
X-35491Y-281543D01*
X-35574Y-281043D01*
X-35908Y-280793D01*
X-37408Y-280293D01*
X-37741Y-279710D01*
X-37574Y-279293D01*
X-37241Y-279043D01*
X-36741Y-278960D01*
X-36241Y-279043D01*
X-35741Y-279293D01*
G01X-27041Y-282293D02*
Y-277293D01*
G01Y-279793D02*
X-26624Y-279293D01*
X-26124Y-279043D01*
X-25624Y-278960D01*
X-24874Y-279126D01*
X-24374Y-279460D01*
X-24041Y-280043D01*
Y-280710D01*
X-24208Y-281376D01*
X-24541Y-281876D01*
X-25124Y-282210D01*
X-25624Y-282293D01*
X-26124Y-282210D01*
X-26624Y-281960D01*
X-27041Y-281543D01*
G01X-21191Y-280043D02*
X-18524D01*
X-18774Y-279460D01*
X-19191Y-279126D01*
X-19774Y-278960D01*
X-20358Y-279043D01*
X-20858Y-279293D01*
X-21191Y-279876D01*
X-21358Y-280376D01*
Y-280876D01*
X-21191Y-281376D01*
X-20774Y-281876D01*
X-20274Y-282210D01*
X-19691Y-282293D01*
X-19108Y-282126D01*
X-18524Y-281626D01*
G01X-14341Y-277293D02*
Y-282293D01*
G01X-15508Y-278960D02*
X-13174D01*
G01X-8741Y-277293D02*
Y-282293D01*
G01X-9908Y-278960D02*
X-7574D01*
G01X-4391Y-280043D02*
X-1724D01*
X-1974Y-279460D01*
X-2391Y-279126D01*
X-2974Y-278960D01*
X-3558Y-279043D01*
X-4058Y-279293D01*
X-4391Y-279876D01*
X-4558Y-280376D01*
Y-280876D01*
X-4391Y-281376D01*
X-3974Y-281876D01*
X-3474Y-282210D01*
X-2891Y-282293D01*
X-2308Y-282126D01*
X-1724Y-281626D01*
G01X1292Y-282293D02*
Y-278960D01*
G01Y-279626D02*
X1709Y-279293D01*
X2126Y-279043D01*
X2709Y-278960D01*
X3126Y-279043D01*
X3626Y-279293D01*
G01X8476Y-283960D02*
X9309Y-283126D01*
X9726Y-282293D01*
Y-278960D01*
X9309Y-278126D01*
X8476Y-277293D01*
G01X-233991Y-268210D02*
X-233574Y-268543D01*
X-232991Y-268793D01*
X-232491D01*
X-231991Y-268626D01*
X-231658Y-268376D01*
X-231491Y-268043D01*
X-231574Y-267543D01*
X-231908Y-267293D01*
X-233408Y-266793D01*
X-233741Y-266210D01*
X-233574Y-265793D01*
X-233241Y-265543D01*
X-232741Y-265460D01*
X-232241Y-265543D01*
X-231741Y-265793D01*
G01X-227141Y-268793D02*
X-227641Y-268710D01*
X-228141Y-268376D01*
X-228474Y-267793D01*
X-228641Y-267126D01*
X-228474Y-266460D01*
X-228141Y-265876D01*
X-227641Y-265543D01*
X-227141Y-265460D01*
X-226641Y-265543D01*
X-226141Y-265876D01*
X-225808Y-266460D01*
X-225724Y-267126D01*
X-225808Y-267793D01*
X-226141Y-268376D01*
X-226641Y-268710D01*
X-227141Y-268793D01*
G01X-221541D02*
Y-263793D01*
G01X-214441D02*
Y-268793D01*
G01Y-268043D02*
X-214774Y-268460D01*
X-215274Y-268710D01*
X-215858Y-268793D01*
X-216524Y-268626D01*
X-217024Y-268210D01*
X-217358Y-267710D01*
X-217441Y-267126D01*
X-217358Y-266543D01*
X-217024Y-266043D01*
X-216524Y-265626D01*
X-215858Y-265460D01*
X-215274Y-265543D01*
X-214858Y-265710D01*
X-214441Y-266043D01*
G01X-211591Y-266543D02*
X-208924D01*
X-209174Y-265960D01*
X-209591Y-265626D01*
X-210174Y-265460D01*
X-210758Y-265543D01*
X-211258Y-265793D01*
X-211591Y-266376D01*
X-211758Y-266876D01*
Y-267376D01*
X-211591Y-267876D01*
X-211174Y-268376D01*
X-210674Y-268710D01*
X-210091Y-268793D01*
X-209508Y-268626D01*
X-208924Y-268126D01*
G01X-205908Y-268793D02*
Y-265460D01*
G01Y-266126D02*
X-205491Y-265793D01*
X-205074Y-265543D01*
X-204491Y-265460D01*
X-204074Y-265543D01*
X-203574Y-265793D01*
G01X-196041Y-268793D02*
Y-265460D01*
G01Y-266376D02*
X-195791Y-265960D01*
X-195374Y-265626D01*
X-194791Y-265460D01*
X-194208Y-265626D01*
X-193791Y-265960D01*
X-193541Y-266376D01*
Y-268793D01*
G01Y-266376D02*
X-193291Y-265960D01*
X-192874Y-265626D01*
X-192291Y-265460D01*
X-191708Y-265626D01*
X-191291Y-265960D01*
X-191041Y-266460D01*
Y-268793D01*
G01X-186441D02*
Y-265460D01*
G01Y-266043D02*
X-186774Y-265710D01*
X-187274Y-265543D01*
X-187858Y-265460D01*
X-188441Y-265626D01*
X-188941Y-265960D01*
X-189274Y-266460D01*
X-189441Y-267126D01*
X-189274Y-267793D01*
X-188941Y-268293D01*
X-188441Y-268626D01*
X-187858Y-268793D01*
X-187274Y-268710D01*
X-186774Y-268460D01*
X-186441Y-268126D01*
G01X-183591Y-268210D02*
X-183174Y-268543D01*
X-182591Y-268793D01*
X-182091D01*
X-181591Y-268626D01*
X-181258Y-268376D01*
X-181091Y-268043D01*
X-181174Y-267543D01*
X-181508Y-267293D01*
X-183008Y-266793D01*
X-183341Y-266210D01*
X-183174Y-265793D01*
X-182841Y-265543D01*
X-182341Y-265460D01*
X-181841Y-265543D01*
X-181341Y-265793D01*
G01X-178158Y-268793D02*
Y-263793D01*
G01X-175491Y-265460D02*
X-178158Y-267376D01*
G01X-177074Y-266626D02*
X-175324Y-268793D01*
G01X-165541Y-263793D02*
Y-268793D01*
G01X-166708Y-265460D02*
X-164374D01*
G01X-161358Y-268793D02*
Y-263793D01*
G01Y-266210D02*
X-160941Y-265793D01*
X-160524Y-265543D01*
X-159858Y-265460D01*
X-159358Y-265543D01*
X-158774Y-265876D01*
X-158524Y-266376D01*
Y-268793D01*
G01X-154341Y-265460D02*
Y-268793D01*
G01Y-264126D02*
X-154508Y-264043D01*
Y-263876D01*
X-154341Y-263793D01*
X-154174Y-263876D01*
Y-264043D01*
X-154341Y-264126D01*
G01X-147408Y-265876D02*
X-147991Y-265543D01*
X-148491Y-265460D01*
X-149158Y-265626D01*
X-149658Y-265960D01*
X-149991Y-266543D01*
X-150074Y-267126D01*
X-149991Y-267710D01*
X-149658Y-268210D01*
X-149158Y-268626D01*
X-148491Y-268793D01*
X-147908Y-268626D01*
X-147408Y-268293D01*
G01X-144558Y-268793D02*
Y-263793D01*
G01X-141891Y-265460D02*
X-144558Y-267376D01*
G01X-143474Y-266626D02*
X-141724Y-268793D01*
G01X-138958D02*
Y-265460D01*
G01Y-266293D02*
X-138624Y-265876D01*
X-138124Y-265543D01*
X-137458Y-265460D01*
X-136874Y-265543D01*
X-136374Y-265876D01*
X-136124Y-266460D01*
Y-268793D01*
G01X-133191Y-266543D02*
X-130524D01*
X-130774Y-265960D01*
X-131191Y-265626D01*
X-131774Y-265460D01*
X-132358Y-265543D01*
X-132858Y-265793D01*
X-133191Y-266376D01*
X-133358Y-266876D01*
Y-267376D01*
X-133191Y-267876D01*
X-132774Y-268376D01*
X-132274Y-268710D01*
X-131691Y-268793D01*
X-131108Y-268626D01*
X-130524Y-268126D01*
G01X-127591Y-268210D02*
X-127174Y-268543D01*
X-126591Y-268793D01*
X-126091D01*
X-125591Y-268626D01*
X-125258Y-268376D01*
X-125091Y-268043D01*
X-125174Y-267543D01*
X-125508Y-267293D01*
X-127008Y-266793D01*
X-127341Y-266210D01*
X-127174Y-265793D01*
X-126841Y-265543D01*
X-126341Y-265460D01*
X-125841Y-265543D01*
X-125341Y-265793D01*
G01X-121991Y-268210D02*
X-121574Y-268543D01*
X-120991Y-268793D01*
X-120491D01*
X-119991Y-268626D01*
X-119658Y-268376D01*
X-119491Y-268043D01*
X-119574Y-267543D01*
X-119908Y-267293D01*
X-121408Y-266793D01*
X-121741Y-266210D01*
X-121574Y-265793D01*
X-121241Y-265543D01*
X-120741Y-265460D01*
X-120241Y-265543D01*
X-119741Y-265793D01*
G01X-232741Y-248793D02*
Y-253793D01*
G01X-234658Y-248793D02*
X-230824D01*
G01X-228558Y-253793D02*
Y-248793D01*
G01Y-251210D02*
X-228141Y-250793D01*
X-227724Y-250543D01*
X-227058Y-250460D01*
X-226558Y-250543D01*
X-225974Y-250876D01*
X-225724Y-251376D01*
Y-253793D01*
G01X-222791Y-251543D02*
X-220124D01*
X-220374Y-250960D01*
X-220791Y-250626D01*
X-221374Y-250460D01*
X-221958Y-250543D01*
X-222458Y-250793D01*
X-222791Y-251376D01*
X-222958Y-251876D01*
Y-252376D01*
X-222791Y-252876D01*
X-222374Y-253376D01*
X-221874Y-253710D01*
X-221291Y-253793D01*
X-220708Y-253626D01*
X-220124Y-253126D01*
G01X-210341Y-253793D02*
Y-248793D01*
G01X-203241Y-253793D02*
Y-250460D01*
G01Y-251043D02*
X-203574Y-250710D01*
X-204074Y-250543D01*
X-204658Y-250460D01*
X-205241Y-250626D01*
X-205741Y-250960D01*
X-206074Y-251460D01*
X-206241Y-252126D01*
X-206074Y-252793D01*
X-205741Y-253293D01*
X-205241Y-253626D01*
X-204658Y-253793D01*
X-204074Y-253710D01*
X-203574Y-253460D01*
X-203241Y-253126D01*
G01X-200308Y-253793D02*
Y-250460D01*
G01Y-251126D02*
X-199891Y-250793D01*
X-199474Y-250543D01*
X-198891Y-250460D01*
X-198474Y-250543D01*
X-197974Y-250793D01*
G01X-194708Y-255043D02*
X-194124Y-255376D01*
X-193458Y-255460D01*
X-192874Y-255376D01*
X-192374Y-254960D01*
X-192041Y-254376D01*
Y-250460D01*
G01Y-251126D02*
X-192374Y-250793D01*
X-192874Y-250543D01*
X-193458Y-250460D01*
X-194124Y-250626D01*
X-194541Y-250960D01*
X-194874Y-251543D01*
X-195041Y-252126D01*
X-194958Y-252626D01*
X-194624Y-253210D01*
X-194124Y-253626D01*
X-193458Y-253793D01*
X-192958Y-253710D01*
X-192374Y-253376D01*
X-192041Y-253043D01*
G01X-189191Y-251543D02*
X-186524D01*
X-186774Y-250960D01*
X-187191Y-250626D01*
X-187774Y-250460D01*
X-188358Y-250543D01*
X-188858Y-250793D01*
X-189191Y-251376D01*
X-189358Y-251876D01*
Y-252376D01*
X-189191Y-252876D01*
X-188774Y-253376D01*
X-188274Y-253710D01*
X-187691Y-253793D01*
X-187108Y-253626D01*
X-186524Y-253126D01*
G01X-183591Y-253210D02*
X-183174Y-253543D01*
X-182591Y-253793D01*
X-182091D01*
X-181591Y-253626D01*
X-181258Y-253376D01*
X-181091Y-253043D01*
X-181174Y-252543D01*
X-181508Y-252293D01*
X-183008Y-251793D01*
X-183341Y-251210D01*
X-183174Y-250793D01*
X-182841Y-250543D01*
X-182341Y-250460D01*
X-181841Y-250543D01*
X-181341Y-250793D01*
G01X-176741Y-248793D02*
Y-253793D01*
G01X-177908Y-250460D02*
X-175574D01*
G01X-164041Y-248793D02*
Y-253793D01*
G01Y-253043D02*
X-164374Y-253460D01*
X-164874Y-253710D01*
X-165458Y-253793D01*
X-166124Y-253626D01*
X-166624Y-253210D01*
X-166958Y-252710D01*
X-167041Y-252126D01*
X-166958Y-251543D01*
X-166624Y-251043D01*
X-166124Y-250626D01*
X-165458Y-250460D01*
X-164874Y-250543D01*
X-164458Y-250710D01*
X-164041Y-251043D01*
G01X-159941Y-250460D02*
Y-253793D01*
G01Y-249126D02*
X-160108Y-249043D01*
Y-248876D01*
X-159941Y-248793D01*
X-159774Y-248876D01*
Y-249043D01*
X-159941Y-249126D01*
G01X-156841Y-253793D02*
Y-250460D01*
G01Y-251376D02*
X-156591Y-250960D01*
X-156174Y-250626D01*
X-155591Y-250460D01*
X-155008Y-250626D01*
X-154591Y-250960D01*
X-154341Y-251376D01*
Y-253793D01*
G01Y-251376D02*
X-154091Y-250960D01*
X-153674Y-250626D01*
X-153091Y-250460D01*
X-152508Y-250626D01*
X-152091Y-250960D01*
X-151841Y-251460D01*
Y-253793D01*
G01X-149991Y-251543D02*
X-147324D01*
X-147574Y-250960D01*
X-147991Y-250626D01*
X-148574Y-250460D01*
X-149158Y-250543D01*
X-149658Y-250793D01*
X-149991Y-251376D01*
X-150158Y-251876D01*
Y-252376D01*
X-149991Y-252876D01*
X-149574Y-253376D01*
X-149074Y-253710D01*
X-148491Y-253793D01*
X-147908Y-253626D01*
X-147324Y-253126D01*
G01X-144558Y-253793D02*
Y-250460D01*
G01Y-251293D02*
X-144224Y-250876D01*
X-143724Y-250543D01*
X-143058Y-250460D01*
X-142474Y-250543D01*
X-141974Y-250876D01*
X-141724Y-251460D01*
Y-253793D01*
G01X-138791Y-253210D02*
X-138374Y-253543D01*
X-137791Y-253793D01*
X-137291D01*
X-136791Y-253626D01*
X-136458Y-253376D01*
X-136291Y-253043D01*
X-136374Y-252543D01*
X-136708Y-252293D01*
X-138208Y-251793D01*
X-138541Y-251210D01*
X-138374Y-250793D01*
X-138041Y-250543D01*
X-137541Y-250460D01*
X-137041Y-250543D01*
X-136541Y-250793D01*
G01X-131941Y-250460D02*
Y-253793D01*
G01Y-249126D02*
X-132108Y-249043D01*
Y-248876D01*
X-131941Y-248793D01*
X-131774Y-248876D01*
Y-249043D01*
X-131941Y-249126D01*
G01X-126341Y-253793D02*
X-126841Y-253710D01*
X-127341Y-253376D01*
X-127674Y-252793D01*
X-127841Y-252126D01*
X-127674Y-251460D01*
X-127341Y-250876D01*
X-126841Y-250543D01*
X-126341Y-250460D01*
X-125841Y-250543D01*
X-125341Y-250876D01*
X-125008Y-251460D01*
X-124924Y-252126D01*
X-125008Y-252793D01*
X-125341Y-253376D01*
X-125841Y-253710D01*
X-126341Y-253793D01*
G01X-122158D02*
Y-250460D01*
G01Y-251293D02*
X-121824Y-250876D01*
X-121324Y-250543D01*
X-120658Y-250460D01*
X-120074Y-250543D01*
X-119574Y-250876D01*
X-119324Y-251460D01*
Y-253793D01*
G01X-109541D02*
X-110041Y-253710D01*
X-110541Y-253376D01*
X-110874Y-252793D01*
X-111041Y-252126D01*
X-110874Y-251460D01*
X-110541Y-250876D01*
X-110041Y-250543D01*
X-109541Y-250460D01*
X-109041Y-250543D01*
X-108541Y-250876D01*
X-108208Y-251460D01*
X-108124Y-252126D01*
X-108208Y-252793D01*
X-108541Y-253376D01*
X-109041Y-253710D01*
X-109541Y-253793D01*
G01X-104441D02*
Y-249543D01*
X-104274Y-249126D01*
X-103941Y-248876D01*
X-103441Y-248793D01*
X-102941Y-248960D01*
X-102691Y-249376D01*
G01X-103691Y-250793D02*
X-105358D01*
G01X-94241Y-255460D02*
Y-250460D01*
G01Y-251210D02*
X-93824Y-250793D01*
X-93408Y-250543D01*
X-92741Y-250460D01*
X-92158Y-250543D01*
X-91574Y-250960D01*
X-91324Y-251543D01*
X-91241Y-252126D01*
X-91324Y-252710D01*
X-91574Y-253293D01*
X-92074Y-253626D01*
X-92741Y-253793D01*
X-93324Y-253710D01*
X-93908Y-253460D01*
X-94241Y-253126D01*
G01X-85641Y-253793D02*
Y-250460D01*
G01Y-251043D02*
X-85974Y-250710D01*
X-86474Y-250543D01*
X-87058Y-250460D01*
X-87641Y-250626D01*
X-88141Y-250960D01*
X-88474Y-251460D01*
X-88641Y-252126D01*
X-88474Y-252793D01*
X-88141Y-253293D01*
X-87641Y-253626D01*
X-87058Y-253793D01*
X-86474Y-253710D01*
X-85974Y-253460D01*
X-85641Y-253126D01*
G01X-80041Y-248793D02*
Y-253793D01*
G01Y-253043D02*
X-80374Y-253460D01*
X-80874Y-253710D01*
X-81458Y-253793D01*
X-82124Y-253626D01*
X-82624Y-253210D01*
X-82958Y-252710D01*
X-83041Y-252126D01*
X-82958Y-251543D01*
X-82624Y-251043D01*
X-82124Y-250626D01*
X-81458Y-250460D01*
X-80874Y-250543D01*
X-80458Y-250710D01*
X-80041Y-251043D01*
G01X-70341Y-253793D02*
X-70841Y-253710D01*
X-71341Y-253376D01*
X-71674Y-252793D01*
X-71841Y-252126D01*
X-71674Y-251460D01*
X-71341Y-250876D01*
X-70841Y-250543D01*
X-70341Y-250460D01*
X-69841Y-250543D01*
X-69341Y-250876D01*
X-69008Y-251460D01*
X-68924Y-252126D01*
X-69008Y-252793D01*
X-69341Y-253376D01*
X-69841Y-253710D01*
X-70341Y-253793D01*
G01X-65908D02*
Y-250460D01*
G01Y-251126D02*
X-65491Y-250793D01*
X-65074Y-250543D01*
X-64491Y-250460D01*
X-64074Y-250543D01*
X-63574Y-250793D01*
G01X-52041Y-248793D02*
Y-253793D01*
G01Y-253043D02*
X-52374Y-253460D01*
X-52874Y-253710D01*
X-53458Y-253793D01*
X-54124Y-253626D01*
X-54624Y-253210D01*
X-54958Y-252710D01*
X-55041Y-252126D01*
X-54958Y-251543D01*
X-54624Y-251043D01*
X-54124Y-250626D01*
X-53458Y-250460D01*
X-52874Y-250543D01*
X-52458Y-250710D01*
X-52041Y-251043D01*
G01X-47941Y-250460D02*
Y-253793D01*
G01Y-249126D02*
X-48108Y-249043D01*
Y-248876D01*
X-47941Y-248793D01*
X-47774Y-248876D01*
Y-249043D01*
X-47941Y-249126D01*
G01X-40841Y-253793D02*
Y-250460D01*
G01Y-251043D02*
X-41174Y-250710D01*
X-41674Y-250543D01*
X-42258Y-250460D01*
X-42841Y-250626D01*
X-43341Y-250960D01*
X-43674Y-251460D01*
X-43841Y-252126D01*
X-43674Y-252793D01*
X-43341Y-253293D01*
X-42841Y-253626D01*
X-42258Y-253793D01*
X-41674Y-253710D01*
X-41174Y-253460D01*
X-40841Y-253126D01*
G01X-39241Y-253793D02*
Y-250460D01*
G01Y-251376D02*
X-38991Y-250960D01*
X-38574Y-250626D01*
X-37991Y-250460D01*
X-37408Y-250626D01*
X-36991Y-250960D01*
X-36741Y-251376D01*
Y-253793D01*
G01Y-251376D02*
X-36491Y-250960D01*
X-36074Y-250626D01*
X-35491Y-250460D01*
X-34908Y-250626D01*
X-34491Y-250960D01*
X-34241Y-251460D01*
Y-253793D01*
G01X-32391Y-251543D02*
X-29724D01*
X-29974Y-250960D01*
X-30391Y-250626D01*
X-30974Y-250460D01*
X-31558Y-250543D01*
X-32058Y-250793D01*
X-32391Y-251376D01*
X-32558Y-251876D01*
Y-252376D01*
X-32391Y-252876D01*
X-31974Y-253376D01*
X-31474Y-253710D01*
X-30891Y-253793D01*
X-30308Y-253626D01*
X-29724Y-253126D01*
G01X-25541Y-248793D02*
Y-253793D01*
G01X-26708Y-250460D02*
X-24374D01*
G01X-21191Y-251543D02*
X-18524D01*
X-18774Y-250960D01*
X-19191Y-250626D01*
X-19774Y-250460D01*
X-20358Y-250543D01*
X-20858Y-250793D01*
X-21191Y-251376D01*
X-21358Y-251876D01*
Y-252376D01*
X-21191Y-252876D01*
X-20774Y-253376D01*
X-20274Y-253710D01*
X-19691Y-253793D01*
X-19108Y-253626D01*
X-18524Y-253126D01*
G01X-15508Y-253793D02*
Y-250460D01*
G01Y-251126D02*
X-15091Y-250793D01*
X-14674Y-250543D01*
X-14091Y-250460D01*
X-13674Y-250543D01*
X-13174Y-250793D01*
G01X-1474Y-253793D02*
X-4808Y-252126D01*
X-1474Y-250460D01*
G01X1376Y-252876D02*
X3542D01*
G01Y-251376D02*
X1376D01*
G01X13659Y-253793D02*
Y-248793D01*
X12659Y-249793D01*
G01Y-253793D02*
X14659D01*
G01X20259D02*
Y-248793D01*
X17176Y-252376D01*
X21342D01*
G01X27959Y-253793D02*
Y-250460D01*
G01Y-251376D02*
X28209Y-250960D01*
X28626Y-250626D01*
X29209Y-250460D01*
X29792Y-250626D01*
X30209Y-250960D01*
X30459Y-251376D01*
Y-253793D01*
G01Y-251376D02*
X30709Y-250960D01*
X31126Y-250626D01*
X31709Y-250460D01*
X32292Y-250626D01*
X32709Y-250960D01*
X32959Y-251460D01*
Y-253793D01*
G01X36059Y-250460D02*
Y-253793D01*
G01Y-249126D02*
X35892Y-249043D01*
Y-248876D01*
X36059Y-248793D01*
X36226Y-248876D01*
Y-249043D01*
X36059Y-249126D01*
G01X41659Y-253793D02*
Y-248793D01*
G01X-232741Y-233793D02*
Y-238793D01*
G01X-234658Y-233793D02*
X-230824D01*
G01X-228558Y-238793D02*
Y-233793D01*
G01Y-236210D02*
X-228141Y-235793D01*
X-227724Y-235543D01*
X-227058Y-235460D01*
X-226558Y-235543D01*
X-225974Y-235876D01*
X-225724Y-236376D01*
Y-238793D01*
G01X-222791Y-236543D02*
X-220124D01*
X-220374Y-235960D01*
X-220791Y-235626D01*
X-221374Y-235460D01*
X-221958Y-235543D01*
X-222458Y-235793D01*
X-222791Y-236376D01*
X-222958Y-236876D01*
Y-237376D01*
X-222791Y-237876D01*
X-222374Y-238376D01*
X-221874Y-238710D01*
X-221291Y-238793D01*
X-220708Y-238626D01*
X-220124Y-238126D01*
G01X-210341Y-238793D02*
Y-233793D01*
G01X-203241Y-238793D02*
Y-235460D01*
G01Y-236043D02*
X-203574Y-235710D01*
X-204074Y-235543D01*
X-204658Y-235460D01*
X-205241Y-235626D01*
X-205741Y-235960D01*
X-206074Y-236460D01*
X-206241Y-237126D01*
X-206074Y-237793D01*
X-205741Y-238293D01*
X-205241Y-238626D01*
X-204658Y-238793D01*
X-204074Y-238710D01*
X-203574Y-238460D01*
X-203241Y-238126D01*
G01X-200308Y-238793D02*
Y-235460D01*
G01Y-236126D02*
X-199891Y-235793D01*
X-199474Y-235543D01*
X-198891Y-235460D01*
X-198474Y-235543D01*
X-197974Y-235793D01*
G01X-194708Y-240043D02*
X-194124Y-240376D01*
X-193458Y-240460D01*
X-192874Y-240376D01*
X-192374Y-239960D01*
X-192041Y-239376D01*
Y-235460D01*
G01Y-236126D02*
X-192374Y-235793D01*
X-192874Y-235543D01*
X-193458Y-235460D01*
X-194124Y-235626D01*
X-194541Y-235960D01*
X-194874Y-236543D01*
X-195041Y-237126D01*
X-194958Y-237626D01*
X-194624Y-238210D01*
X-194124Y-238626D01*
X-193458Y-238793D01*
X-192958Y-238710D01*
X-192374Y-238376D01*
X-192041Y-238043D01*
G01X-189191Y-236543D02*
X-186524D01*
X-186774Y-235960D01*
X-187191Y-235626D01*
X-187774Y-235460D01*
X-188358Y-235543D01*
X-188858Y-235793D01*
X-189191Y-236376D01*
X-189358Y-236876D01*
Y-237376D01*
X-189191Y-237876D01*
X-188774Y-238376D01*
X-188274Y-238710D01*
X-187691Y-238793D01*
X-187108Y-238626D01*
X-186524Y-238126D01*
G01X-183591Y-238210D02*
X-183174Y-238543D01*
X-182591Y-238793D01*
X-182091D01*
X-181591Y-238626D01*
X-181258Y-238376D01*
X-181091Y-238043D01*
X-181174Y-237543D01*
X-181508Y-237293D01*
X-183008Y-236793D01*
X-183341Y-236210D01*
X-183174Y-235793D01*
X-182841Y-235543D01*
X-182341Y-235460D01*
X-181841Y-235543D01*
X-181341Y-235793D01*
G01X-176741Y-233793D02*
Y-238793D01*
G01X-177908Y-235460D02*
X-175574D01*
G01X-164041Y-233793D02*
Y-238793D01*
G01Y-238043D02*
X-164374Y-238460D01*
X-164874Y-238710D01*
X-165458Y-238793D01*
X-166124Y-238626D01*
X-166624Y-238210D01*
X-166958Y-237710D01*
X-167041Y-237126D01*
X-166958Y-236543D01*
X-166624Y-236043D01*
X-166124Y-235626D01*
X-165458Y-235460D01*
X-164874Y-235543D01*
X-164458Y-235710D01*
X-164041Y-236043D01*
G01X-159941Y-235460D02*
Y-238793D01*
G01Y-234126D02*
X-160108Y-234043D01*
Y-233876D01*
X-159941Y-233793D01*
X-159774Y-233876D01*
Y-234043D01*
X-159941Y-234126D01*
G01X-156841Y-238793D02*
Y-235460D01*
G01Y-236376D02*
X-156591Y-235960D01*
X-156174Y-235626D01*
X-155591Y-235460D01*
X-155008Y-235626D01*
X-154591Y-235960D01*
X-154341Y-236376D01*
Y-238793D01*
G01Y-236376D02*
X-154091Y-235960D01*
X-153674Y-235626D01*
X-153091Y-235460D01*
X-152508Y-235626D01*
X-152091Y-235960D01*
X-151841Y-236460D01*
Y-238793D01*
G01X-149991Y-236543D02*
X-147324D01*
X-147574Y-235960D01*
X-147991Y-235626D01*
X-148574Y-235460D01*
X-149158Y-235543D01*
X-149658Y-235793D01*
X-149991Y-236376D01*
X-150158Y-236876D01*
Y-237376D01*
X-149991Y-237876D01*
X-149574Y-238376D01*
X-149074Y-238710D01*
X-148491Y-238793D01*
X-147908Y-238626D01*
X-147324Y-238126D01*
G01X-144558Y-238793D02*
Y-235460D01*
G01Y-236293D02*
X-144224Y-235876D01*
X-143724Y-235543D01*
X-143058Y-235460D01*
X-142474Y-235543D01*
X-141974Y-235876D01*
X-141724Y-236460D01*
Y-238793D01*
G01X-138791Y-238210D02*
X-138374Y-238543D01*
X-137791Y-238793D01*
X-137291D01*
X-136791Y-238626D01*
X-136458Y-238376D01*
X-136291Y-238043D01*
X-136374Y-237543D01*
X-136708Y-237293D01*
X-138208Y-236793D01*
X-138541Y-236210D01*
X-138374Y-235793D01*
X-138041Y-235543D01*
X-137541Y-235460D01*
X-137041Y-235543D01*
X-136541Y-235793D01*
G01X-131941Y-235460D02*
Y-238793D01*
G01Y-234126D02*
X-132108Y-234043D01*
Y-233876D01*
X-131941Y-233793D01*
X-131774Y-233876D01*
Y-234043D01*
X-131941Y-234126D01*
G01X-126341Y-238793D02*
X-126841Y-238710D01*
X-127341Y-238376D01*
X-127674Y-237793D01*
X-127841Y-237126D01*
X-127674Y-236460D01*
X-127341Y-235876D01*
X-126841Y-235543D01*
X-126341Y-235460D01*
X-125841Y-235543D01*
X-125341Y-235876D01*
X-125008Y-236460D01*
X-124924Y-237126D01*
X-125008Y-237793D01*
X-125341Y-238376D01*
X-125841Y-238710D01*
X-126341Y-238793D01*
G01X-122158D02*
Y-235460D01*
G01Y-236293D02*
X-121824Y-235876D01*
X-121324Y-235543D01*
X-120658Y-235460D01*
X-120074Y-235543D01*
X-119574Y-235876D01*
X-119324Y-236460D01*
Y-238793D01*
G01X-109541D02*
X-110041Y-238710D01*
X-110541Y-238376D01*
X-110874Y-237793D01*
X-111041Y-237126D01*
X-110874Y-236460D01*
X-110541Y-235876D01*
X-110041Y-235543D01*
X-109541Y-235460D01*
X-109041Y-235543D01*
X-108541Y-235876D01*
X-108208Y-236460D01*
X-108124Y-237126D01*
X-108208Y-237793D01*
X-108541Y-238376D01*
X-109041Y-238710D01*
X-109541Y-238793D01*
G01X-104441D02*
Y-234543D01*
X-104274Y-234126D01*
X-103941Y-233876D01*
X-103441Y-233793D01*
X-102941Y-233960D01*
X-102691Y-234376D01*
G01X-103691Y-235793D02*
X-105358D01*
G01X-94241Y-240460D02*
Y-235460D01*
G01Y-236210D02*
X-93824Y-235793D01*
X-93408Y-235543D01*
X-92741Y-235460D01*
X-92158Y-235543D01*
X-91574Y-235960D01*
X-91324Y-236543D01*
X-91241Y-237126D01*
X-91324Y-237710D01*
X-91574Y-238293D01*
X-92074Y-238626D01*
X-92741Y-238793D01*
X-93324Y-238710D01*
X-93908Y-238460D01*
X-94241Y-238126D01*
G01X-85641Y-238793D02*
Y-235460D01*
G01Y-236043D02*
X-85974Y-235710D01*
X-86474Y-235543D01*
X-87058Y-235460D01*
X-87641Y-235626D01*
X-88141Y-235960D01*
X-88474Y-236460D01*
X-88641Y-237126D01*
X-88474Y-237793D01*
X-88141Y-238293D01*
X-87641Y-238626D01*
X-87058Y-238793D01*
X-86474Y-238710D01*
X-85974Y-238460D01*
X-85641Y-238126D01*
G01X-80041Y-233793D02*
Y-238793D01*
G01Y-238043D02*
X-80374Y-238460D01*
X-80874Y-238710D01*
X-81458Y-238793D01*
X-82124Y-238626D01*
X-82624Y-238210D01*
X-82958Y-237710D01*
X-83041Y-237126D01*
X-82958Y-236543D01*
X-82624Y-236043D01*
X-82124Y-235626D01*
X-81458Y-235460D01*
X-80874Y-235543D01*
X-80458Y-235710D01*
X-80041Y-236043D01*
G01X-70341Y-238793D02*
X-70841Y-238710D01*
X-71341Y-238376D01*
X-71674Y-237793D01*
X-71841Y-237126D01*
X-71674Y-236460D01*
X-71341Y-235876D01*
X-70841Y-235543D01*
X-70341Y-235460D01*
X-69841Y-235543D01*
X-69341Y-235876D01*
X-69008Y-236460D01*
X-68924Y-237126D01*
X-69008Y-237793D01*
X-69341Y-238376D01*
X-69841Y-238710D01*
X-70341Y-238793D01*
G01X-65908D02*
Y-235460D01*
G01Y-236126D02*
X-65491Y-235793D01*
X-65074Y-235543D01*
X-64491Y-235460D01*
X-64074Y-235543D01*
X-63574Y-235793D01*
G01X-52041Y-233793D02*
Y-238793D01*
G01Y-238043D02*
X-52374Y-238460D01*
X-52874Y-238710D01*
X-53458Y-238793D01*
X-54124Y-238626D01*
X-54624Y-238210D01*
X-54958Y-237710D01*
X-55041Y-237126D01*
X-54958Y-236543D01*
X-54624Y-236043D01*
X-54124Y-235626D01*
X-53458Y-235460D01*
X-52874Y-235543D01*
X-52458Y-235710D01*
X-52041Y-236043D01*
G01X-47941Y-235460D02*
Y-238793D01*
G01Y-234126D02*
X-48108Y-234043D01*
Y-233876D01*
X-47941Y-233793D01*
X-47774Y-233876D01*
Y-234043D01*
X-47941Y-234126D01*
G01X-40841Y-238793D02*
Y-235460D01*
G01Y-236043D02*
X-41174Y-235710D01*
X-41674Y-235543D01*
X-42258Y-235460D01*
X-42841Y-235626D01*
X-43341Y-235960D01*
X-43674Y-236460D01*
X-43841Y-237126D01*
X-43674Y-237793D01*
X-43341Y-238293D01*
X-42841Y-238626D01*
X-42258Y-238793D01*
X-41674Y-238710D01*
X-41174Y-238460D01*
X-40841Y-238126D01*
G01X-39241Y-238793D02*
Y-235460D01*
G01Y-236376D02*
X-38991Y-235960D01*
X-38574Y-235626D01*
X-37991Y-235460D01*
X-37408Y-235626D01*
X-36991Y-235960D01*
X-36741Y-236376D01*
Y-238793D01*
G01Y-236376D02*
X-36491Y-235960D01*
X-36074Y-235626D01*
X-35491Y-235460D01*
X-34908Y-235626D01*
X-34491Y-235960D01*
X-34241Y-236460D01*
Y-238793D01*
G01X-32391Y-236543D02*
X-29724D01*
X-29974Y-235960D01*
X-30391Y-235626D01*
X-30974Y-235460D01*
X-31558Y-235543D01*
X-32058Y-235793D01*
X-32391Y-236376D01*
X-32558Y-236876D01*
Y-237376D01*
X-32391Y-237876D01*
X-31974Y-238376D01*
X-31474Y-238710D01*
X-30891Y-238793D01*
X-30308Y-238626D01*
X-29724Y-238126D01*
G01X-25541Y-233793D02*
Y-238793D01*
G01X-26708Y-235460D02*
X-24374D01*
G01X-21191Y-236543D02*
X-18524D01*
X-18774Y-235960D01*
X-19191Y-235626D01*
X-19774Y-235460D01*
X-20358Y-235543D01*
X-20858Y-235793D01*
X-21191Y-236376D01*
X-21358Y-236876D01*
Y-237376D01*
X-21191Y-237876D01*
X-20774Y-238376D01*
X-20274Y-238710D01*
X-19691Y-238793D01*
X-19108Y-238626D01*
X-18524Y-238126D01*
G01X-15508Y-238793D02*
Y-235460D01*
G01Y-236126D02*
X-15091Y-235793D01*
X-14674Y-235543D01*
X-14091Y-235460D01*
X-13674Y-235543D01*
X-13174Y-235793D01*
G01X-4808Y-238793D02*
X-1474Y-237126D01*
X-4808Y-235460D01*
G01X2459Y-238793D02*
Y-233793D01*
X1459Y-234793D01*
G01Y-238793D02*
X3459D01*
G01X9059D02*
Y-233793D01*
X5976Y-237376D01*
X10142D01*
G01X16759Y-238793D02*
Y-235460D01*
G01Y-236376D02*
X17009Y-235960D01*
X17426Y-235626D01*
X18009Y-235460D01*
X18592Y-235626D01*
X19009Y-235960D01*
X19259Y-236376D01*
Y-238793D01*
G01Y-236376D02*
X19509Y-235960D01*
X19926Y-235626D01*
X20509Y-235460D01*
X21092Y-235626D01*
X21509Y-235960D01*
X21759Y-236460D01*
Y-238793D01*
G01X24859Y-235460D02*
Y-238793D01*
G01Y-234126D02*
X24692Y-234043D01*
Y-233876D01*
X24859Y-233793D01*
X25026Y-233876D01*
Y-234043D01*
X24859Y-234126D01*
G01X30459Y-238793D02*
Y-233793D01*
G01X-241241Y-288293D02*
X189259D01*
G01X-241241Y-243293D02*
X189259D01*
G01X-231661Y-216123D02*
Y-221123D01*
G01X-233578Y-216123D02*
X-229744D01*
G01X-227478Y-221123D02*
Y-216123D01*
G01Y-218540D02*
X-227061Y-218123D01*
X-226644Y-217873D01*
X-225978Y-217790D01*
X-225478Y-217873D01*
X-224894Y-218206D01*
X-224644Y-218706D01*
Y-221123D01*
G01X-221711Y-218873D02*
X-219044D01*
X-219294Y-218290D01*
X-219711Y-217956D01*
X-220294Y-217790D01*
X-220878Y-217873D01*
X-221378Y-218123D01*
X-221711Y-218706D01*
X-221878Y-219206D01*
Y-219706D01*
X-221711Y-220206D01*
X-221294Y-220706D01*
X-220794Y-221040D01*
X-220211Y-221123D01*
X-219628Y-220956D01*
X-219044Y-220456D01*
G01X-209261Y-221123D02*
Y-216123D01*
G01X-202161Y-221123D02*
Y-217790D01*
G01Y-218373D02*
X-202494Y-218040D01*
X-202994Y-217873D01*
X-203578Y-217790D01*
X-204161Y-217956D01*
X-204661Y-218290D01*
X-204994Y-218790D01*
X-205161Y-219456D01*
X-204994Y-220123D01*
X-204661Y-220623D01*
X-204161Y-220956D01*
X-203578Y-221123D01*
X-202994Y-221040D01*
X-202494Y-220790D01*
X-202161Y-220456D01*
G01X-199228Y-221123D02*
Y-217790D01*
G01Y-218456D02*
X-198811Y-218123D01*
X-198394Y-217873D01*
X-197811Y-217790D01*
X-197394Y-217873D01*
X-196894Y-218123D01*
G01X-193628Y-222373D02*
X-193044Y-222706D01*
X-192378Y-222790D01*
X-191794Y-222706D01*
X-191294Y-222290D01*
X-190961Y-221706D01*
Y-217790D01*
G01Y-218456D02*
X-191294Y-218123D01*
X-191794Y-217873D01*
X-192378Y-217790D01*
X-193044Y-217956D01*
X-193461Y-218290D01*
X-193794Y-218873D01*
X-193961Y-219456D01*
X-193878Y-219956D01*
X-193544Y-220540D01*
X-193044Y-220956D01*
X-192378Y-221123D01*
X-191878Y-221040D01*
X-191294Y-220706D01*
X-190961Y-220373D01*
G01X-188111Y-218873D02*
X-185444D01*
X-185694Y-218290D01*
X-186111Y-217956D01*
X-186694Y-217790D01*
X-187278Y-217873D01*
X-187778Y-218123D01*
X-188111Y-218706D01*
X-188278Y-219206D01*
Y-219706D01*
X-188111Y-220206D01*
X-187694Y-220706D01*
X-187194Y-221040D01*
X-186611Y-221123D01*
X-186028Y-220956D01*
X-185444Y-220456D01*
G01X-182511Y-220540D02*
X-182094Y-220873D01*
X-181511Y-221123D01*
X-181011D01*
X-180511Y-220956D01*
X-180178Y-220706D01*
X-180011Y-220373D01*
X-180094Y-219873D01*
X-180428Y-219623D01*
X-181928Y-219123D01*
X-182261Y-218540D01*
X-182094Y-218123D01*
X-181761Y-217873D01*
X-181261Y-217790D01*
X-180761Y-217873D01*
X-180261Y-218123D01*
G01X-175661Y-216123D02*
Y-221123D01*
G01X-176828Y-217790D02*
X-174494D01*
G01X-162961Y-216123D02*
Y-221123D01*
G01Y-220373D02*
X-163294Y-220790D01*
X-163794Y-221040D01*
X-164378Y-221123D01*
X-165044Y-220956D01*
X-165544Y-220540D01*
X-165878Y-220040D01*
X-165961Y-219456D01*
X-165878Y-218873D01*
X-165544Y-218373D01*
X-165044Y-217956D01*
X-164378Y-217790D01*
X-163794Y-217873D01*
X-163378Y-218040D01*
X-162961Y-218373D01*
G01X-158861Y-217790D02*
Y-221123D01*
G01Y-216456D02*
X-159028Y-216373D01*
Y-216206D01*
X-158861Y-216123D01*
X-158694Y-216206D01*
Y-216373D01*
X-158861Y-216456D01*
G01X-155761Y-221123D02*
Y-217790D01*
G01Y-218706D02*
X-155511Y-218290D01*
X-155094Y-217956D01*
X-154511Y-217790D01*
X-153928Y-217956D01*
X-153511Y-218290D01*
X-153261Y-218706D01*
Y-221123D01*
G01Y-218706D02*
X-153011Y-218290D01*
X-152594Y-217956D01*
X-152011Y-217790D01*
X-151428Y-217956D01*
X-151011Y-218290D01*
X-150761Y-218790D01*
Y-221123D01*
G01X-148911Y-218873D02*
X-146244D01*
X-146494Y-218290D01*
X-146911Y-217956D01*
X-147494Y-217790D01*
X-148078Y-217873D01*
X-148578Y-218123D01*
X-148911Y-218706D01*
X-149078Y-219206D01*
Y-219706D01*
X-148911Y-220206D01*
X-148494Y-220706D01*
X-147994Y-221040D01*
X-147411Y-221123D01*
X-146828Y-220956D01*
X-146244Y-220456D01*
G01X-143478Y-221123D02*
Y-217790D01*
G01Y-218623D02*
X-143144Y-218206D01*
X-142644Y-217873D01*
X-141978Y-217790D01*
X-141394Y-217873D01*
X-140894Y-218206D01*
X-140644Y-218790D01*
Y-221123D01*
G01X-137711Y-220540D02*
X-137294Y-220873D01*
X-136711Y-221123D01*
X-136211D01*
X-135711Y-220956D01*
X-135378Y-220706D01*
X-135211Y-220373D01*
X-135294Y-219873D01*
X-135628Y-219623D01*
X-137128Y-219123D01*
X-137461Y-218540D01*
X-137294Y-218123D01*
X-136961Y-217873D01*
X-136461Y-217790D01*
X-135961Y-217873D01*
X-135461Y-218123D01*
G01X-130861Y-217790D02*
Y-221123D01*
G01Y-216456D02*
X-131028Y-216373D01*
Y-216206D01*
X-130861Y-216123D01*
X-130694Y-216206D01*
Y-216373D01*
X-130861Y-216456D01*
G01X-125261Y-221123D02*
X-125761Y-221040D01*
X-126261Y-220706D01*
X-126594Y-220123D01*
X-126761Y-219456D01*
X-126594Y-218790D01*
X-126261Y-218206D01*
X-125761Y-217873D01*
X-125261Y-217790D01*
X-124761Y-217873D01*
X-124261Y-218206D01*
X-123928Y-218790D01*
X-123844Y-219456D01*
X-123928Y-220123D01*
X-124261Y-220706D01*
X-124761Y-221040D01*
X-125261Y-221123D01*
G01X-121078D02*
Y-217790D01*
G01Y-218623D02*
X-120744Y-218206D01*
X-120244Y-217873D01*
X-119578Y-217790D01*
X-118994Y-217873D01*
X-118494Y-218206D01*
X-118244Y-218790D01*
Y-221123D01*
G01X-108461D02*
X-108961Y-221040D01*
X-109461Y-220706D01*
X-109794Y-220123D01*
X-109961Y-219456D01*
X-109794Y-218790D01*
X-109461Y-218206D01*
X-108961Y-217873D01*
X-108461Y-217790D01*
X-107961Y-217873D01*
X-107461Y-218206D01*
X-107128Y-218790D01*
X-107044Y-219456D01*
X-107128Y-220123D01*
X-107461Y-220706D01*
X-107961Y-221040D01*
X-108461Y-221123D01*
G01X-103361D02*
Y-216873D01*
X-103194Y-216456D01*
X-102861Y-216206D01*
X-102361Y-216123D01*
X-101861Y-216290D01*
X-101611Y-216706D01*
G01X-102611Y-218123D02*
X-104278D01*
G01X-93161Y-222790D02*
Y-217790D01*
G01Y-218540D02*
X-92744Y-218123D01*
X-92328Y-217873D01*
X-91661Y-217790D01*
X-91078Y-217873D01*
X-90494Y-218290D01*
X-90244Y-218873D01*
X-90161Y-219456D01*
X-90244Y-220040D01*
X-90494Y-220623D01*
X-90994Y-220956D01*
X-91661Y-221123D01*
X-92244Y-221040D01*
X-92828Y-220790D01*
X-93161Y-220456D01*
G01X-84561Y-221123D02*
Y-217790D01*
G01Y-218373D02*
X-84894Y-218040D01*
X-85394Y-217873D01*
X-85978Y-217790D01*
X-86561Y-217956D01*
X-87061Y-218290D01*
X-87394Y-218790D01*
X-87561Y-219456D01*
X-87394Y-220123D01*
X-87061Y-220623D01*
X-86561Y-220956D01*
X-85978Y-221123D01*
X-85394Y-221040D01*
X-84894Y-220790D01*
X-84561Y-220456D01*
G01X-78961Y-216123D02*
Y-221123D01*
G01Y-220373D02*
X-79294Y-220790D01*
X-79794Y-221040D01*
X-80378Y-221123D01*
X-81044Y-220956D01*
X-81544Y-220540D01*
X-81878Y-220040D01*
X-81961Y-219456D01*
X-81878Y-218873D01*
X-81544Y-218373D01*
X-81044Y-217956D01*
X-80378Y-217790D01*
X-79794Y-217873D01*
X-79378Y-218040D01*
X-78961Y-218373D01*
G01X-69261Y-221123D02*
X-69761Y-221040D01*
X-70261Y-220706D01*
X-70594Y-220123D01*
X-70761Y-219456D01*
X-70594Y-218790D01*
X-70261Y-218206D01*
X-69761Y-217873D01*
X-69261Y-217790D01*
X-68761Y-217873D01*
X-68261Y-218206D01*
X-67928Y-218790D01*
X-67844Y-219456D01*
X-67928Y-220123D01*
X-68261Y-220706D01*
X-68761Y-221040D01*
X-69261Y-221123D01*
G01X-64828D02*
Y-217790D01*
G01Y-218456D02*
X-64411Y-218123D01*
X-63994Y-217873D01*
X-63411Y-217790D01*
X-62994Y-217873D01*
X-62494Y-218123D01*
G01X-50961Y-216123D02*
Y-221123D01*
G01Y-220373D02*
X-51294Y-220790D01*
X-51794Y-221040D01*
X-52378Y-221123D01*
X-53044Y-220956D01*
X-53544Y-220540D01*
X-53878Y-220040D01*
X-53961Y-219456D01*
X-53878Y-218873D01*
X-53544Y-218373D01*
X-53044Y-217956D01*
X-52378Y-217790D01*
X-51794Y-217873D01*
X-51378Y-218040D01*
X-50961Y-218373D01*
G01X-46861Y-217790D02*
Y-221123D01*
G01Y-216456D02*
X-47028Y-216373D01*
Y-216206D01*
X-46861Y-216123D01*
X-46694Y-216206D01*
Y-216373D01*
X-46861Y-216456D01*
G01X-39761Y-221123D02*
Y-217790D01*
G01Y-218373D02*
X-40094Y-218040D01*
X-40594Y-217873D01*
X-41178Y-217790D01*
X-41761Y-217956D01*
X-42261Y-218290D01*
X-42594Y-218790D01*
X-42761Y-219456D01*
X-42594Y-220123D01*
X-42261Y-220623D01*
X-41761Y-220956D01*
X-41178Y-221123D01*
X-40594Y-221040D01*
X-40094Y-220790D01*
X-39761Y-220456D01*
G01X-38161Y-221123D02*
Y-217790D01*
G01Y-218706D02*
X-37911Y-218290D01*
X-37494Y-217956D01*
X-36911Y-217790D01*
X-36328Y-217956D01*
X-35911Y-218290D01*
X-35661Y-218706D01*
Y-221123D01*
G01Y-218706D02*
X-35411Y-218290D01*
X-34994Y-217956D01*
X-34411Y-217790D01*
X-33828Y-217956D01*
X-33411Y-218290D01*
X-33161Y-218790D01*
Y-221123D01*
G01X-31311Y-218873D02*
X-28644D01*
X-28894Y-218290D01*
X-29311Y-217956D01*
X-29894Y-217790D01*
X-30478Y-217873D01*
X-30978Y-218123D01*
X-31311Y-218706D01*
X-31478Y-219206D01*
Y-219706D01*
X-31311Y-220206D01*
X-30894Y-220706D01*
X-30394Y-221040D01*
X-29811Y-221123D01*
X-29228Y-220956D01*
X-28644Y-220456D01*
G01X-24461Y-216123D02*
Y-221123D01*
G01X-25628Y-217790D02*
X-23294D01*
G01X-20111Y-218873D02*
X-17444D01*
X-17694Y-218290D01*
X-18111Y-217956D01*
X-18694Y-217790D01*
X-19278Y-217873D01*
X-19778Y-218123D01*
X-20111Y-218706D01*
X-20278Y-219206D01*
Y-219706D01*
X-20111Y-220206D01*
X-19694Y-220706D01*
X-19194Y-221040D01*
X-18611Y-221123D01*
X-18028Y-220956D01*
X-17444Y-220456D01*
G01X-14428Y-221123D02*
Y-217790D01*
G01Y-218456D02*
X-14011Y-218123D01*
X-13594Y-217873D01*
X-13011Y-217790D01*
X-12594Y-217873D01*
X-12094Y-218123D01*
G01X-394Y-221123D02*
X-3728Y-219456D01*
X-394Y-217790D01*
G01X2456Y-220206D02*
X4622D01*
G01Y-218706D02*
X2456D01*
G01X14739Y-221123D02*
Y-216123D01*
X13739Y-217123D01*
G01Y-221123D02*
X15739D01*
G01X21339D02*
Y-216123D01*
X18256Y-219706D01*
X22422D01*
G01X29039Y-221123D02*
Y-217790D01*
G01Y-218706D02*
X29289Y-218290D01*
X29706Y-217956D01*
X30289Y-217790D01*
X30872Y-217956D01*
X31289Y-218290D01*
X31539Y-218706D01*
Y-221123D01*
G01Y-218706D02*
X31789Y-218290D01*
X32206Y-217956D01*
X32789Y-217790D01*
X33372Y-217956D01*
X33789Y-218290D01*
X34039Y-218790D01*
Y-221123D01*
G01X37139Y-217790D02*
Y-221123D01*
G01Y-216456D02*
X36972Y-216373D01*
Y-216206D01*
X37139Y-216123D01*
X37306Y-216206D01*
Y-216373D01*
X37139Y-216456D01*
G01X42739Y-221123D02*
Y-216123D01*
G01X-234574Y-166543D02*
X-234074Y-166960D01*
X-233491Y-167210D01*
X-232741Y-167293D01*
X-231991Y-167126D01*
X-231408Y-166793D01*
X-230991Y-166210D01*
X-230908Y-165543D01*
X-231074Y-164876D01*
X-231491Y-164460D01*
X-232074Y-164126D01*
X-232658Y-164043D01*
X-233241Y-164126D01*
X-233991Y-164460D01*
X-233741Y-162293D01*
X-231491D01*
G01X-224041Y-167293D02*
Y-163960D01*
G01Y-164876D02*
X-223791Y-164460D01*
X-223374Y-164126D01*
X-222791Y-163960D01*
X-222208Y-164126D01*
X-221791Y-164460D01*
X-221541Y-164876D01*
Y-167293D01*
G01Y-164876D02*
X-221291Y-164460D01*
X-220874Y-164126D01*
X-220291Y-163960D01*
X-219708Y-164126D01*
X-219291Y-164460D01*
X-219041Y-164960D01*
Y-167293D01*
G01X-215941Y-163960D02*
Y-167293D01*
G01Y-162626D02*
X-216108Y-162543D01*
Y-162376D01*
X-215941Y-162293D01*
X-215774Y-162376D01*
Y-162543D01*
X-215941Y-162626D01*
G01X-210341Y-167293D02*
Y-162293D01*
G01X-197474Y-167293D02*
X-200808Y-165626D01*
X-197474Y-163960D01*
G01X-187941Y-162293D02*
Y-167293D01*
G01X-189108Y-163960D02*
X-186774D01*
G01X-183508Y-167293D02*
Y-163960D01*
G01Y-164626D02*
X-183091Y-164293D01*
X-182674Y-164043D01*
X-182091Y-163960D01*
X-181674Y-164043D01*
X-181174Y-164293D01*
G01X-175241Y-167293D02*
Y-163960D01*
G01Y-164543D02*
X-175574Y-164210D01*
X-176074Y-164043D01*
X-176658Y-163960D01*
X-177241Y-164126D01*
X-177741Y-164460D01*
X-178074Y-164960D01*
X-178241Y-165626D01*
X-178074Y-166293D01*
X-177741Y-166793D01*
X-177241Y-167126D01*
X-176658Y-167293D01*
X-176074Y-167210D01*
X-175574Y-166960D01*
X-175241Y-166626D01*
G01X-169808Y-164376D02*
X-170391Y-164043D01*
X-170891Y-163960D01*
X-171558Y-164126D01*
X-172058Y-164460D01*
X-172391Y-165043D01*
X-172474Y-165626D01*
X-172391Y-166210D01*
X-172058Y-166710D01*
X-171558Y-167126D01*
X-170891Y-167293D01*
X-170308Y-167126D01*
X-169808Y-166793D01*
G01X-166791Y-165043D02*
X-164124D01*
X-164374Y-164460D01*
X-164791Y-164126D01*
X-165374Y-163960D01*
X-165958Y-164043D01*
X-166458Y-164293D01*
X-166791Y-164876D01*
X-166958Y-165376D01*
Y-165876D01*
X-166791Y-166376D01*
X-166374Y-166876D01*
X-165874Y-167210D01*
X-165291Y-167293D01*
X-164708Y-167126D01*
X-164124Y-166626D01*
G01X-156424Y-163960D02*
X-155424Y-167293D01*
X-154341Y-163960D01*
X-153258Y-167293D01*
X-152258Y-163960D01*
G01X-148741D02*
Y-167293D01*
G01Y-162626D02*
X-148908Y-162543D01*
Y-162376D01*
X-148741Y-162293D01*
X-148574Y-162376D01*
Y-162543D01*
X-148741Y-162626D01*
G01X-141641Y-162293D02*
Y-167293D01*
G01Y-166543D02*
X-141974Y-166960D01*
X-142474Y-167210D01*
X-143058Y-167293D01*
X-143724Y-167126D01*
X-144224Y-166710D01*
X-144558Y-166210D01*
X-144641Y-165626D01*
X-144558Y-165043D01*
X-144224Y-164543D01*
X-143724Y-164126D01*
X-143058Y-163960D01*
X-142474Y-164043D01*
X-142058Y-164210D01*
X-141641Y-164543D01*
G01X-137541Y-162293D02*
Y-167293D01*
G01X-138708Y-163960D02*
X-136374D01*
G01X-133358Y-167293D02*
Y-162293D01*
G01Y-164710D02*
X-132941Y-164293D01*
X-132524Y-164043D01*
X-131858Y-163960D01*
X-131358Y-164043D01*
X-130774Y-164376D01*
X-130524Y-164876D01*
Y-167293D01*
G01X-119074D02*
X-122408Y-165626D01*
X-119074Y-163960D01*
G01X-116224Y-166376D02*
X-114058D01*
G01Y-164876D02*
X-116224D01*
G01X-104108Y-167293D02*
X-103941Y-166210D01*
X-103691Y-165293D01*
X-103358Y-164460D01*
X-102941Y-163543D01*
X-102274Y-162293D01*
X-105608D01*
G01X-95241Y-167293D02*
Y-163960D01*
G01Y-164876D02*
X-94991Y-164460D01*
X-94574Y-164126D01*
X-93991Y-163960D01*
X-93408Y-164126D01*
X-92991Y-164460D01*
X-92741Y-164876D01*
Y-167293D01*
G01Y-164876D02*
X-92491Y-164460D01*
X-92074Y-164126D01*
X-91491Y-163960D01*
X-90908Y-164126D01*
X-90491Y-164460D01*
X-90241Y-164960D01*
Y-167293D01*
G01X-87141Y-163960D02*
Y-167293D01*
G01Y-162626D02*
X-87308Y-162543D01*
Y-162376D01*
X-87141Y-162293D01*
X-86974Y-162376D01*
Y-162543D01*
X-87141Y-162626D01*
G01X-81541Y-167293D02*
Y-162293D01*
G01X-232741Y-177293D02*
Y-182293D01*
G01X-233908Y-178960D02*
X-231574D01*
G01X-228308Y-182293D02*
Y-178960D01*
G01Y-179626D02*
X-227891Y-179293D01*
X-227474Y-179043D01*
X-226891Y-178960D01*
X-226474Y-179043D01*
X-225974Y-179293D01*
G01X-220041Y-182293D02*
Y-178960D01*
G01Y-179543D02*
X-220374Y-179210D01*
X-220874Y-179043D01*
X-221458Y-178960D01*
X-222041Y-179126D01*
X-222541Y-179460D01*
X-222874Y-179960D01*
X-223041Y-180626D01*
X-222874Y-181293D01*
X-222541Y-181793D01*
X-222041Y-182126D01*
X-221458Y-182293D01*
X-220874Y-182210D01*
X-220374Y-181960D01*
X-220041Y-181626D01*
G01X-214608Y-179376D02*
X-215191Y-179043D01*
X-215691Y-178960D01*
X-216358Y-179126D01*
X-216858Y-179460D01*
X-217191Y-180043D01*
X-217274Y-180626D01*
X-217191Y-181210D01*
X-216858Y-181710D01*
X-216358Y-182126D01*
X-215691Y-182293D01*
X-215108Y-182126D01*
X-214608Y-181793D01*
G01X-211591Y-180043D02*
X-208924D01*
X-209174Y-179460D01*
X-209591Y-179126D01*
X-210174Y-178960D01*
X-210758Y-179043D01*
X-211258Y-179293D01*
X-211591Y-179876D01*
X-211758Y-180376D01*
Y-180876D01*
X-211591Y-181376D01*
X-211174Y-181876D01*
X-210674Y-182210D01*
X-210091Y-182293D01*
X-209508Y-182126D01*
X-208924Y-181626D01*
G01X-201224Y-178960D02*
X-200224Y-182293D01*
X-199141Y-178960D01*
X-198058Y-182293D01*
X-197058Y-178960D01*
G01X-193541D02*
Y-182293D01*
G01Y-177626D02*
X-193708Y-177543D01*
Y-177376D01*
X-193541Y-177293D01*
X-193374Y-177376D01*
Y-177543D01*
X-193541Y-177626D01*
G01X-186441Y-177293D02*
Y-182293D01*
G01Y-181543D02*
X-186774Y-181960D01*
X-187274Y-182210D01*
X-187858Y-182293D01*
X-188524Y-182126D01*
X-189024Y-181710D01*
X-189358Y-181210D01*
X-189441Y-180626D01*
X-189358Y-180043D01*
X-189024Y-179543D01*
X-188524Y-179126D01*
X-187858Y-178960D01*
X-187274Y-179043D01*
X-186858Y-179210D01*
X-186441Y-179543D01*
G01X-182341Y-177293D02*
Y-182293D01*
G01X-183508Y-178960D02*
X-181174D01*
G01X-178158Y-182293D02*
Y-177293D01*
G01Y-179710D02*
X-177741Y-179293D01*
X-177324Y-179043D01*
X-176658Y-178960D01*
X-176158Y-179043D01*
X-175574Y-179376D01*
X-175324Y-179876D01*
Y-182293D01*
G01X-167208D02*
X-163874Y-180626D01*
X-167208Y-178960D01*
G01X-154508Y-182293D02*
X-154341Y-181210D01*
X-154091Y-180293D01*
X-153758Y-179460D01*
X-153341Y-178543D01*
X-152674Y-177293D01*
X-156008D01*
G01X-145641Y-182293D02*
Y-178960D01*
G01Y-179876D02*
X-145391Y-179460D01*
X-144974Y-179126D01*
X-144391Y-178960D01*
X-143808Y-179126D01*
X-143391Y-179460D01*
X-143141Y-179876D01*
Y-182293D01*
G01Y-179876D02*
X-142891Y-179460D01*
X-142474Y-179126D01*
X-141891Y-178960D01*
X-141308Y-179126D01*
X-140891Y-179460D01*
X-140641Y-179960D01*
Y-182293D01*
G01X-137541Y-178960D02*
Y-182293D01*
G01Y-177626D02*
X-137708Y-177543D01*
Y-177376D01*
X-137541Y-177293D01*
X-137374Y-177376D01*
Y-177543D01*
X-137541Y-177626D01*
G01X-131941Y-182293D02*
Y-177293D01*
G01X-232741Y-196793D02*
Y-201793D01*
G01X-234658Y-196793D02*
X-230824D01*
G01X-228558Y-201793D02*
Y-196793D01*
G01Y-199210D02*
X-228141Y-198793D01*
X-227724Y-198543D01*
X-227058Y-198460D01*
X-226558Y-198543D01*
X-225974Y-198876D01*
X-225724Y-199376D01*
Y-201793D01*
G01X-222791Y-199543D02*
X-220124D01*
X-220374Y-198960D01*
X-220791Y-198626D01*
X-221374Y-198460D01*
X-221958Y-198543D01*
X-222458Y-198793D01*
X-222791Y-199376D01*
X-222958Y-199876D01*
Y-200376D01*
X-222791Y-200876D01*
X-222374Y-201376D01*
X-221874Y-201710D01*
X-221291Y-201793D01*
X-220708Y-201626D01*
X-220124Y-201126D01*
G01X-210341Y-201793D02*
Y-196793D01*
G01X-203241Y-201793D02*
Y-198460D01*
G01Y-199043D02*
X-203574Y-198710D01*
X-204074Y-198543D01*
X-204658Y-198460D01*
X-205241Y-198626D01*
X-205741Y-198960D01*
X-206074Y-199460D01*
X-206241Y-200126D01*
X-206074Y-200793D01*
X-205741Y-201293D01*
X-205241Y-201626D01*
X-204658Y-201793D01*
X-204074Y-201710D01*
X-203574Y-201460D01*
X-203241Y-201126D01*
G01X-200308Y-201793D02*
Y-198460D01*
G01Y-199126D02*
X-199891Y-198793D01*
X-199474Y-198543D01*
X-198891Y-198460D01*
X-198474Y-198543D01*
X-197974Y-198793D01*
G01X-194708Y-203043D02*
X-194124Y-203376D01*
X-193458Y-203460D01*
X-192874Y-203376D01*
X-192374Y-202960D01*
X-192041Y-202376D01*
Y-198460D01*
G01Y-199126D02*
X-192374Y-198793D01*
X-192874Y-198543D01*
X-193458Y-198460D01*
X-194124Y-198626D01*
X-194541Y-198960D01*
X-194874Y-199543D01*
X-195041Y-200126D01*
X-194958Y-200626D01*
X-194624Y-201210D01*
X-194124Y-201626D01*
X-193458Y-201793D01*
X-192958Y-201710D01*
X-192374Y-201376D01*
X-192041Y-201043D01*
G01X-189191Y-199543D02*
X-186524D01*
X-186774Y-198960D01*
X-187191Y-198626D01*
X-187774Y-198460D01*
X-188358Y-198543D01*
X-188858Y-198793D01*
X-189191Y-199376D01*
X-189358Y-199876D01*
Y-200376D01*
X-189191Y-200876D01*
X-188774Y-201376D01*
X-188274Y-201710D01*
X-187691Y-201793D01*
X-187108Y-201626D01*
X-186524Y-201126D01*
G01X-183591Y-201210D02*
X-183174Y-201543D01*
X-182591Y-201793D01*
X-182091D01*
X-181591Y-201626D01*
X-181258Y-201376D01*
X-181091Y-201043D01*
X-181174Y-200543D01*
X-181508Y-200293D01*
X-183008Y-199793D01*
X-183341Y-199210D01*
X-183174Y-198793D01*
X-182841Y-198543D01*
X-182341Y-198460D01*
X-181841Y-198543D01*
X-181341Y-198793D01*
G01X-176741Y-196793D02*
Y-201793D01*
G01X-177908Y-198460D02*
X-175574D01*
G01X-164041Y-196793D02*
Y-201793D01*
G01Y-201043D02*
X-164374Y-201460D01*
X-164874Y-201710D01*
X-165458Y-201793D01*
X-166124Y-201626D01*
X-166624Y-201210D01*
X-166958Y-200710D01*
X-167041Y-200126D01*
X-166958Y-199543D01*
X-166624Y-199043D01*
X-166124Y-198626D01*
X-165458Y-198460D01*
X-164874Y-198543D01*
X-164458Y-198710D01*
X-164041Y-199043D01*
G01X-159941Y-198460D02*
Y-201793D01*
G01Y-197126D02*
X-160108Y-197043D01*
Y-196876D01*
X-159941Y-196793D01*
X-159774Y-196876D01*
Y-197043D01*
X-159941Y-197126D01*
G01X-156841Y-201793D02*
Y-198460D01*
G01Y-199376D02*
X-156591Y-198960D01*
X-156174Y-198626D01*
X-155591Y-198460D01*
X-155008Y-198626D01*
X-154591Y-198960D01*
X-154341Y-199376D01*
Y-201793D01*
G01Y-199376D02*
X-154091Y-198960D01*
X-153674Y-198626D01*
X-153091Y-198460D01*
X-152508Y-198626D01*
X-152091Y-198960D01*
X-151841Y-199460D01*
Y-201793D01*
G01X-149991Y-199543D02*
X-147324D01*
X-147574Y-198960D01*
X-147991Y-198626D01*
X-148574Y-198460D01*
X-149158Y-198543D01*
X-149658Y-198793D01*
X-149991Y-199376D01*
X-150158Y-199876D01*
Y-200376D01*
X-149991Y-200876D01*
X-149574Y-201376D01*
X-149074Y-201710D01*
X-148491Y-201793D01*
X-147908Y-201626D01*
X-147324Y-201126D01*
G01X-144558Y-201793D02*
Y-198460D01*
G01Y-199293D02*
X-144224Y-198876D01*
X-143724Y-198543D01*
X-143058Y-198460D01*
X-142474Y-198543D01*
X-141974Y-198876D01*
X-141724Y-199460D01*
Y-201793D01*
G01X-138791Y-201210D02*
X-138374Y-201543D01*
X-137791Y-201793D01*
X-137291D01*
X-136791Y-201626D01*
X-136458Y-201376D01*
X-136291Y-201043D01*
X-136374Y-200543D01*
X-136708Y-200293D01*
X-138208Y-199793D01*
X-138541Y-199210D01*
X-138374Y-198793D01*
X-138041Y-198543D01*
X-137541Y-198460D01*
X-137041Y-198543D01*
X-136541Y-198793D01*
G01X-131941Y-198460D02*
Y-201793D01*
G01Y-197126D02*
X-132108Y-197043D01*
Y-196876D01*
X-131941Y-196793D01*
X-131774Y-196876D01*
Y-197043D01*
X-131941Y-197126D01*
G01X-126341Y-201793D02*
X-126841Y-201710D01*
X-127341Y-201376D01*
X-127674Y-200793D01*
X-127841Y-200126D01*
X-127674Y-199460D01*
X-127341Y-198876D01*
X-126841Y-198543D01*
X-126341Y-198460D01*
X-125841Y-198543D01*
X-125341Y-198876D01*
X-125008Y-199460D01*
X-124924Y-200126D01*
X-125008Y-200793D01*
X-125341Y-201376D01*
X-125841Y-201710D01*
X-126341Y-201793D01*
G01X-122158D02*
Y-198460D01*
G01Y-199293D02*
X-121824Y-198876D01*
X-121324Y-198543D01*
X-120658Y-198460D01*
X-120074Y-198543D01*
X-119574Y-198876D01*
X-119324Y-199460D01*
Y-201793D01*
G01X-109541D02*
X-110041Y-201710D01*
X-110541Y-201376D01*
X-110874Y-200793D01*
X-111041Y-200126D01*
X-110874Y-199460D01*
X-110541Y-198876D01*
X-110041Y-198543D01*
X-109541Y-198460D01*
X-109041Y-198543D01*
X-108541Y-198876D01*
X-108208Y-199460D01*
X-108124Y-200126D01*
X-108208Y-200793D01*
X-108541Y-201376D01*
X-109041Y-201710D01*
X-109541Y-201793D01*
G01X-104441D02*
Y-197543D01*
X-104274Y-197126D01*
X-103941Y-196876D01*
X-103441Y-196793D01*
X-102941Y-196960D01*
X-102691Y-197376D01*
G01X-103691Y-198793D02*
X-105358D01*
G01X-94241Y-203460D02*
Y-198460D01*
G01Y-199210D02*
X-93824Y-198793D01*
X-93408Y-198543D01*
X-92741Y-198460D01*
X-92158Y-198543D01*
X-91574Y-198960D01*
X-91324Y-199543D01*
X-91241Y-200126D01*
X-91324Y-200710D01*
X-91574Y-201293D01*
X-92074Y-201626D01*
X-92741Y-201793D01*
X-93324Y-201710D01*
X-93908Y-201460D01*
X-94241Y-201126D01*
G01X-85641Y-201793D02*
Y-198460D01*
G01Y-199043D02*
X-85974Y-198710D01*
X-86474Y-198543D01*
X-87058Y-198460D01*
X-87641Y-198626D01*
X-88141Y-198960D01*
X-88474Y-199460D01*
X-88641Y-200126D01*
X-88474Y-200793D01*
X-88141Y-201293D01*
X-87641Y-201626D01*
X-87058Y-201793D01*
X-86474Y-201710D01*
X-85974Y-201460D01*
X-85641Y-201126D01*
G01X-80041Y-196793D02*
Y-201793D01*
G01Y-201043D02*
X-80374Y-201460D01*
X-80874Y-201710D01*
X-81458Y-201793D01*
X-82124Y-201626D01*
X-82624Y-201210D01*
X-82958Y-200710D01*
X-83041Y-200126D01*
X-82958Y-199543D01*
X-82624Y-199043D01*
X-82124Y-198626D01*
X-81458Y-198460D01*
X-80874Y-198543D01*
X-80458Y-198710D01*
X-80041Y-199043D01*
G01X-70341Y-201793D02*
X-70841Y-201710D01*
X-71341Y-201376D01*
X-71674Y-200793D01*
X-71841Y-200126D01*
X-71674Y-199460D01*
X-71341Y-198876D01*
X-70841Y-198543D01*
X-70341Y-198460D01*
X-69841Y-198543D01*
X-69341Y-198876D01*
X-69008Y-199460D01*
X-68924Y-200126D01*
X-69008Y-200793D01*
X-69341Y-201376D01*
X-69841Y-201710D01*
X-70341Y-201793D01*
G01X-65908D02*
Y-198460D01*
G01Y-199126D02*
X-65491Y-198793D01*
X-65074Y-198543D01*
X-64491Y-198460D01*
X-64074Y-198543D01*
X-63574Y-198793D01*
G01X-52041Y-196793D02*
Y-201793D01*
G01Y-201043D02*
X-52374Y-201460D01*
X-52874Y-201710D01*
X-53458Y-201793D01*
X-54124Y-201626D01*
X-54624Y-201210D01*
X-54958Y-200710D01*
X-55041Y-200126D01*
X-54958Y-199543D01*
X-54624Y-199043D01*
X-54124Y-198626D01*
X-53458Y-198460D01*
X-52874Y-198543D01*
X-52458Y-198710D01*
X-52041Y-199043D01*
G01X-47941Y-198460D02*
Y-201793D01*
G01Y-197126D02*
X-48108Y-197043D01*
Y-196876D01*
X-47941Y-196793D01*
X-47774Y-196876D01*
Y-197043D01*
X-47941Y-197126D01*
G01X-40841Y-201793D02*
Y-198460D01*
G01Y-199043D02*
X-41174Y-198710D01*
X-41674Y-198543D01*
X-42258Y-198460D01*
X-42841Y-198626D01*
X-43341Y-198960D01*
X-43674Y-199460D01*
X-43841Y-200126D01*
X-43674Y-200793D01*
X-43341Y-201293D01*
X-42841Y-201626D01*
X-42258Y-201793D01*
X-41674Y-201710D01*
X-41174Y-201460D01*
X-40841Y-201126D01*
G01X-39241Y-201793D02*
Y-198460D01*
G01Y-199376D02*
X-38991Y-198960D01*
X-38574Y-198626D01*
X-37991Y-198460D01*
X-37408Y-198626D01*
X-36991Y-198960D01*
X-36741Y-199376D01*
Y-201793D01*
G01Y-199376D02*
X-36491Y-198960D01*
X-36074Y-198626D01*
X-35491Y-198460D01*
X-34908Y-198626D01*
X-34491Y-198960D01*
X-34241Y-199460D01*
Y-201793D01*
G01X-32391Y-199543D02*
X-29724D01*
X-29974Y-198960D01*
X-30391Y-198626D01*
X-30974Y-198460D01*
X-31558Y-198543D01*
X-32058Y-198793D01*
X-32391Y-199376D01*
X-32558Y-199876D01*
Y-200376D01*
X-32391Y-200876D01*
X-31974Y-201376D01*
X-31474Y-201710D01*
X-30891Y-201793D01*
X-30308Y-201626D01*
X-29724Y-201126D01*
G01X-25541Y-196793D02*
Y-201793D01*
G01X-26708Y-198460D02*
X-24374D01*
G01X-21191Y-199543D02*
X-18524D01*
X-18774Y-198960D01*
X-19191Y-198626D01*
X-19774Y-198460D01*
X-20358Y-198543D01*
X-20858Y-198793D01*
X-21191Y-199376D01*
X-21358Y-199876D01*
Y-200376D01*
X-21191Y-200876D01*
X-20774Y-201376D01*
X-20274Y-201710D01*
X-19691Y-201793D01*
X-19108Y-201626D01*
X-18524Y-201126D01*
G01X-15508Y-201793D02*
Y-198460D01*
G01Y-199126D02*
X-15091Y-198793D01*
X-14674Y-198543D01*
X-14091Y-198460D01*
X-13674Y-198543D01*
X-13174Y-198793D01*
G01X-4808Y-201793D02*
X-1474Y-200126D01*
X-4808Y-198460D01*
G01X8059Y-201793D02*
Y-196793D01*
X7059Y-197793D01*
G01Y-201793D02*
X9059D01*
G01X14659D02*
Y-196793D01*
X11576Y-200376D01*
X15742D01*
G01X22359Y-201793D02*
Y-198460D01*
G01Y-199376D02*
X22609Y-198960D01*
X23026Y-198626D01*
X23609Y-198460D01*
X24192Y-198626D01*
X24609Y-198960D01*
X24859Y-199376D01*
Y-201793D01*
G01Y-199376D02*
X25109Y-198960D01*
X25526Y-198626D01*
X26109Y-198460D01*
X26692Y-198626D01*
X27109Y-198960D01*
X27359Y-199460D01*
Y-201793D01*
G01X30459Y-198460D02*
Y-201793D01*
G01Y-197126D02*
X30292Y-197043D01*
Y-196876D01*
X30459Y-196793D01*
X30626Y-196876D01*
Y-197043D01*
X30459Y-197126D01*
G01X36059Y-201793D02*
Y-196793D01*
G01X-241241Y-208293D02*
X189259D01*
G01X-241241Y-173293D02*
X189259D01*
G01X-241241Y-158293D02*
X189259D01*
G01X-233991Y-107210D02*
X-233574Y-107543D01*
X-232991Y-107793D01*
X-232491D01*
X-231991Y-107626D01*
X-231658Y-107376D01*
X-231491Y-107043D01*
X-231574Y-106543D01*
X-231908Y-106293D01*
X-233408Y-105793D01*
X-233741Y-105210D01*
X-233574Y-104793D01*
X-233241Y-104543D01*
X-232741Y-104460D01*
X-232241Y-104543D01*
X-231741Y-104793D01*
G01X-228641Y-109460D02*
Y-104460D01*
G01Y-105210D02*
X-228224Y-104793D01*
X-227808Y-104543D01*
X-227141Y-104460D01*
X-226558Y-104543D01*
X-225974Y-104960D01*
X-225724Y-105543D01*
X-225641Y-106126D01*
X-225724Y-106710D01*
X-225974Y-107293D01*
X-226474Y-107626D01*
X-227141Y-107793D01*
X-227724Y-107710D01*
X-228308Y-107460D01*
X-228641Y-107126D01*
G01X-222791Y-105543D02*
X-220124D01*
X-220374Y-104960D01*
X-220791Y-104626D01*
X-221374Y-104460D01*
X-221958Y-104543D01*
X-222458Y-104793D01*
X-222791Y-105376D01*
X-222958Y-105876D01*
Y-106376D01*
X-222791Y-106876D01*
X-222374Y-107376D01*
X-221874Y-107710D01*
X-221291Y-107793D01*
X-220708Y-107626D01*
X-220124Y-107126D01*
G01X-214608Y-104876D02*
X-215191Y-104543D01*
X-215691Y-104460D01*
X-216358Y-104626D01*
X-216858Y-104960D01*
X-217191Y-105543D01*
X-217274Y-106126D01*
X-217191Y-106710D01*
X-216858Y-107210D01*
X-216358Y-107626D01*
X-215691Y-107793D01*
X-215108Y-107626D01*
X-214608Y-107293D01*
G01X-210341Y-104460D02*
Y-107793D01*
G01Y-103126D02*
X-210508Y-103043D01*
Y-102876D01*
X-210341Y-102793D01*
X-210174Y-102876D01*
Y-103043D01*
X-210341Y-103126D01*
G01X-205241Y-107793D02*
Y-103543D01*
X-205074Y-103126D01*
X-204741Y-102876D01*
X-204241Y-102793D01*
X-203741Y-102960D01*
X-203491Y-103376D01*
G01X-204491Y-104793D02*
X-206158D01*
G01X-199141Y-104460D02*
Y-107793D01*
G01Y-103126D02*
X-199308Y-103043D01*
Y-102876D01*
X-199141Y-102793D01*
X-198974Y-102876D01*
Y-103043D01*
X-199141Y-103126D01*
G01X-192208Y-104876D02*
X-192791Y-104543D01*
X-193291Y-104460D01*
X-193958Y-104626D01*
X-194458Y-104960D01*
X-194791Y-105543D01*
X-194874Y-106126D01*
X-194791Y-106710D01*
X-194458Y-107210D01*
X-193958Y-107626D01*
X-193291Y-107793D01*
X-192708Y-107626D01*
X-192208Y-107293D01*
G01X-186441Y-107793D02*
Y-104460D01*
G01Y-105043D02*
X-186774Y-104710D01*
X-187274Y-104543D01*
X-187858Y-104460D01*
X-188441Y-104626D01*
X-188941Y-104960D01*
X-189274Y-105460D01*
X-189441Y-106126D01*
X-189274Y-106793D01*
X-188941Y-107293D01*
X-188441Y-107626D01*
X-187858Y-107793D01*
X-187274Y-107710D01*
X-186774Y-107460D01*
X-186441Y-107126D01*
G01X-182341Y-102793D02*
Y-107793D01*
G01X-183508Y-104460D02*
X-181174D01*
G01X-176741D02*
Y-107793D01*
G01Y-103126D02*
X-176908Y-103043D01*
Y-102876D01*
X-176741Y-102793D01*
X-176574Y-102876D01*
Y-103043D01*
X-176741Y-103126D01*
G01X-171141Y-107793D02*
X-171641Y-107710D01*
X-172141Y-107376D01*
X-172474Y-106793D01*
X-172641Y-106126D01*
X-172474Y-105460D01*
X-172141Y-104876D01*
X-171641Y-104543D01*
X-171141Y-104460D01*
X-170641Y-104543D01*
X-170141Y-104876D01*
X-169808Y-105460D01*
X-169724Y-106126D01*
X-169808Y-106793D01*
X-170141Y-107376D01*
X-170641Y-107710D01*
X-171141Y-107793D01*
G01X-166958D02*
Y-104460D01*
G01Y-105293D02*
X-166624Y-104876D01*
X-166124Y-104543D01*
X-165458Y-104460D01*
X-164874Y-104543D01*
X-164374Y-104876D01*
X-164124Y-105460D01*
Y-107793D01*
G01X-159941Y-107960D02*
X-160108Y-107876D01*
Y-107710D01*
X-159941Y-107626D01*
X-159774Y-107710D01*
Y-107876D01*
X-159941Y-107960D01*
G01X-232741Y-147293D02*
Y-152293D01*
G01X-233908Y-148960D02*
X-231574D01*
G01X-228308Y-152293D02*
Y-148960D01*
G01Y-149626D02*
X-227891Y-149293D01*
X-227474Y-149043D01*
X-226891Y-148960D01*
X-226474Y-149043D01*
X-225974Y-149293D01*
G01X-220041Y-152293D02*
Y-148960D01*
G01Y-149543D02*
X-220374Y-149210D01*
X-220874Y-149043D01*
X-221458Y-148960D01*
X-222041Y-149126D01*
X-222541Y-149460D01*
X-222874Y-149960D01*
X-223041Y-150626D01*
X-222874Y-151293D01*
X-222541Y-151793D01*
X-222041Y-152126D01*
X-221458Y-152293D01*
X-220874Y-152210D01*
X-220374Y-151960D01*
X-220041Y-151626D01*
G01X-214608Y-149376D02*
X-215191Y-149043D01*
X-215691Y-148960D01*
X-216358Y-149126D01*
X-216858Y-149460D01*
X-217191Y-150043D01*
X-217274Y-150626D01*
X-217191Y-151210D01*
X-216858Y-151710D01*
X-216358Y-152126D01*
X-215691Y-152293D01*
X-215108Y-152126D01*
X-214608Y-151793D01*
G01X-211591Y-150043D02*
X-208924D01*
X-209174Y-149460D01*
X-209591Y-149126D01*
X-210174Y-148960D01*
X-210758Y-149043D01*
X-211258Y-149293D01*
X-211591Y-149876D01*
X-211758Y-150376D01*
Y-150876D01*
X-211591Y-151376D01*
X-211174Y-151876D01*
X-210674Y-152210D01*
X-210091Y-152293D01*
X-209508Y-152126D01*
X-208924Y-151626D01*
G01X-201224Y-148960D02*
X-200224Y-152293D01*
X-199141Y-148960D01*
X-198058Y-152293D01*
X-197058Y-148960D01*
G01X-193541D02*
Y-152293D01*
G01Y-147626D02*
X-193708Y-147543D01*
Y-147376D01*
X-193541Y-147293D01*
X-193374Y-147376D01*
Y-147543D01*
X-193541Y-147626D01*
G01X-186441Y-147293D02*
Y-152293D01*
G01Y-151543D02*
X-186774Y-151960D01*
X-187274Y-152210D01*
X-187858Y-152293D01*
X-188524Y-152126D01*
X-189024Y-151710D01*
X-189358Y-151210D01*
X-189441Y-150626D01*
X-189358Y-150043D01*
X-189024Y-149543D01*
X-188524Y-149126D01*
X-187858Y-148960D01*
X-187274Y-149043D01*
X-186858Y-149210D01*
X-186441Y-149543D01*
G01X-182341Y-147293D02*
Y-152293D01*
G01X-183508Y-148960D02*
X-181174D01*
G01X-178158Y-152293D02*
Y-147293D01*
G01Y-149710D02*
X-177741Y-149293D01*
X-177324Y-149043D01*
X-176658Y-148960D01*
X-176158Y-149043D01*
X-175574Y-149376D01*
X-175324Y-149876D01*
Y-152293D01*
G01X-163874D02*
X-167208Y-150626D01*
X-163874Y-148960D01*
G01X-161024Y-151376D02*
X-158858D01*
G01Y-149876D02*
X-161024D01*
G01X-150574Y-151543D02*
X-150074Y-151960D01*
X-149491Y-152210D01*
X-148741Y-152293D01*
X-147991Y-152126D01*
X-147408Y-151793D01*
X-146991Y-151210D01*
X-146908Y-150543D01*
X-147074Y-149876D01*
X-147491Y-149460D01*
X-148074Y-149126D01*
X-148658Y-149043D01*
X-149241Y-149126D01*
X-149991Y-149460D01*
X-149741Y-147293D01*
X-147491D01*
G01X-140041Y-152293D02*
Y-148960D01*
G01Y-149876D02*
X-139791Y-149460D01*
X-139374Y-149126D01*
X-138791Y-148960D01*
X-138208Y-149126D01*
X-137791Y-149460D01*
X-137541Y-149876D01*
Y-152293D01*
G01Y-149876D02*
X-137291Y-149460D01*
X-136874Y-149126D01*
X-136291Y-148960D01*
X-135708Y-149126D01*
X-135291Y-149460D01*
X-135041Y-149960D01*
Y-152293D01*
G01X-131941Y-148960D02*
Y-152293D01*
G01Y-147626D02*
X-132108Y-147543D01*
Y-147376D01*
X-131941Y-147293D01*
X-131774Y-147376D01*
Y-147543D01*
X-131941Y-147626D01*
G01X-126341Y-152293D02*
Y-147293D01*
G01X-234408Y-138793D02*
Y-133793D01*
X-232324D01*
X-231658Y-134043D01*
X-231241Y-134376D01*
X-231074Y-135043D01*
X-231241Y-135710D01*
X-231741Y-136126D01*
X-232324Y-136376D01*
X-234408D01*
G01X-232324D02*
X-231074Y-138793D01*
G01X-228391Y-136543D02*
X-225724D01*
X-225974Y-135960D01*
X-226391Y-135626D01*
X-226974Y-135460D01*
X-227558Y-135543D01*
X-228058Y-135793D01*
X-228391Y-136376D01*
X-228558Y-136876D01*
Y-137376D01*
X-228391Y-137876D01*
X-227974Y-138376D01*
X-227474Y-138710D01*
X-226891Y-138793D01*
X-226308Y-138626D01*
X-225724Y-138126D01*
G01X-221541Y-138793D02*
Y-133793D01*
G01X-214441Y-138793D02*
Y-135460D01*
G01Y-136043D02*
X-214774Y-135710D01*
X-215274Y-135543D01*
X-215858Y-135460D01*
X-216441Y-135626D01*
X-216941Y-135960D01*
X-217274Y-136460D01*
X-217441Y-137126D01*
X-217274Y-137793D01*
X-216941Y-138293D01*
X-216441Y-138626D01*
X-215858Y-138793D01*
X-215274Y-138710D01*
X-214774Y-138460D01*
X-214441Y-138126D01*
G01X-210341Y-133793D02*
Y-138793D01*
G01X-211508Y-135460D02*
X-209174D01*
G01X-204741D02*
Y-138793D01*
G01Y-134126D02*
X-204908Y-134043D01*
Y-133876D01*
X-204741Y-133793D01*
X-204574Y-133876D01*
Y-134043D01*
X-204741Y-134126D01*
G01X-200641Y-135460D02*
X-199141Y-138793D01*
X-197641Y-135460D01*
G01X-194791Y-136543D02*
X-192124D01*
X-192374Y-135960D01*
X-192791Y-135626D01*
X-193374Y-135460D01*
X-193958Y-135543D01*
X-194458Y-135793D01*
X-194791Y-136376D01*
X-194958Y-136876D01*
Y-137376D01*
X-194791Y-137876D01*
X-194374Y-138376D01*
X-193874Y-138710D01*
X-193291Y-138793D01*
X-192708Y-138626D01*
X-192124Y-138126D01*
G01X-183841Y-140460D02*
Y-135460D01*
G01Y-136210D02*
X-183424Y-135793D01*
X-183008Y-135543D01*
X-182341Y-135460D01*
X-181758Y-135543D01*
X-181174Y-135960D01*
X-180924Y-136543D01*
X-180841Y-137126D01*
X-180924Y-137710D01*
X-181174Y-138293D01*
X-181674Y-138626D01*
X-182341Y-138793D01*
X-182924Y-138710D01*
X-183508Y-138460D01*
X-183841Y-138126D01*
G01X-176741Y-138793D02*
X-177241Y-138710D01*
X-177741Y-138376D01*
X-178074Y-137793D01*
X-178241Y-137126D01*
X-178074Y-136460D01*
X-177741Y-135876D01*
X-177241Y-135543D01*
X-176741Y-135460D01*
X-176241Y-135543D01*
X-175741Y-135876D01*
X-175408Y-136460D01*
X-175324Y-137126D01*
X-175408Y-137793D01*
X-175741Y-138376D01*
X-176241Y-138710D01*
X-176741Y-138793D01*
G01X-172391Y-138210D02*
X-171974Y-138543D01*
X-171391Y-138793D01*
X-170891D01*
X-170391Y-138626D01*
X-170058Y-138376D01*
X-169891Y-138043D01*
X-169974Y-137543D01*
X-170308Y-137293D01*
X-171808Y-136793D01*
X-172141Y-136210D01*
X-171974Y-135793D01*
X-171641Y-135543D01*
X-171141Y-135460D01*
X-170641Y-135543D01*
X-170141Y-135793D01*
G01X-165541Y-135460D02*
Y-138793D01*
G01Y-134126D02*
X-165708Y-134043D01*
Y-133876D01*
X-165541Y-133793D01*
X-165374Y-133876D01*
Y-134043D01*
X-165541Y-134126D01*
G01X-159941Y-133793D02*
Y-138793D01*
G01X-161108Y-135460D02*
X-158774D01*
G01X-154341D02*
Y-138793D01*
G01Y-134126D02*
X-154508Y-134043D01*
Y-133876D01*
X-154341Y-133793D01*
X-154174Y-133876D01*
Y-134043D01*
X-154341Y-134126D01*
G01X-148741Y-138793D02*
X-149241Y-138710D01*
X-149741Y-138376D01*
X-150074Y-137793D01*
X-150241Y-137126D01*
X-150074Y-136460D01*
X-149741Y-135876D01*
X-149241Y-135543D01*
X-148741Y-135460D01*
X-148241Y-135543D01*
X-147741Y-135876D01*
X-147408Y-136460D01*
X-147324Y-137126D01*
X-147408Y-137793D01*
X-147741Y-138376D01*
X-148241Y-138710D01*
X-148741Y-138793D01*
G01X-144558D02*
Y-135460D01*
G01Y-136293D02*
X-144224Y-135876D01*
X-143724Y-135543D01*
X-143058Y-135460D01*
X-142474Y-135543D01*
X-141974Y-135876D01*
X-141724Y-136460D01*
Y-138793D01*
G01X-133441D02*
Y-133793D01*
G01Y-136293D02*
X-133024Y-135793D01*
X-132524Y-135543D01*
X-132024Y-135460D01*
X-131274Y-135626D01*
X-130774Y-135960D01*
X-130441Y-136543D01*
Y-137210D01*
X-130608Y-137876D01*
X-130941Y-138376D01*
X-131524Y-138710D01*
X-132024Y-138793D01*
X-132524Y-138710D01*
X-133024Y-138460D01*
X-133441Y-138043D01*
G01X-127591Y-136543D02*
X-124924D01*
X-125174Y-135960D01*
X-125591Y-135626D01*
X-126174Y-135460D01*
X-126758Y-135543D01*
X-127258Y-135793D01*
X-127591Y-136376D01*
X-127758Y-136876D01*
Y-137376D01*
X-127591Y-137876D01*
X-127174Y-138376D01*
X-126674Y-138710D01*
X-126091Y-138793D01*
X-125508Y-138626D01*
X-124924Y-138126D01*
G01X-120741Y-133793D02*
Y-138793D01*
G01X-121908Y-135460D02*
X-119574D01*
G01X-117224D02*
X-116224Y-138793D01*
X-115141Y-135460D01*
X-114058Y-138793D01*
X-113058Y-135460D01*
G01X-110791Y-136543D02*
X-108124D01*
X-108374Y-135960D01*
X-108791Y-135626D01*
X-109374Y-135460D01*
X-109958Y-135543D01*
X-110458Y-135793D01*
X-110791Y-136376D01*
X-110958Y-136876D01*
Y-137376D01*
X-110791Y-137876D01*
X-110374Y-138376D01*
X-109874Y-138710D01*
X-109291Y-138793D01*
X-108708Y-138626D01*
X-108124Y-138126D01*
G01X-105191Y-136543D02*
X-102524D01*
X-102774Y-135960D01*
X-103191Y-135626D01*
X-103774Y-135460D01*
X-104358Y-135543D01*
X-104858Y-135793D01*
X-105191Y-136376D01*
X-105358Y-136876D01*
Y-137376D01*
X-105191Y-137876D01*
X-104774Y-138376D01*
X-104274Y-138710D01*
X-103691Y-138793D01*
X-103108Y-138626D01*
X-102524Y-138126D01*
G01X-99758Y-138793D02*
Y-135460D01*
G01Y-136293D02*
X-99424Y-135876D01*
X-98924Y-135543D01*
X-98258Y-135460D01*
X-97674Y-135543D01*
X-97174Y-135876D01*
X-96924Y-136460D01*
Y-138793D01*
G01X-85641D02*
Y-135460D01*
G01Y-136043D02*
X-85974Y-135710D01*
X-86474Y-135543D01*
X-87058Y-135460D01*
X-87641Y-135626D01*
X-88141Y-135960D01*
X-88474Y-136460D01*
X-88641Y-137126D01*
X-88474Y-137793D01*
X-88141Y-138293D01*
X-87641Y-138626D01*
X-87058Y-138793D01*
X-86474Y-138710D01*
X-85974Y-138460D01*
X-85641Y-138126D01*
G01X-82958Y-138793D02*
Y-135460D01*
G01Y-136293D02*
X-82624Y-135876D01*
X-82124Y-135543D01*
X-81458Y-135460D01*
X-80874Y-135543D01*
X-80374Y-135876D01*
X-80124Y-136460D01*
Y-138793D01*
G01X-77691Y-140293D02*
X-77191Y-140460D01*
X-76524Y-140293D01*
X-76108Y-139960D01*
X-75774Y-139543D01*
X-75274Y-138210D01*
X-74191Y-135460D01*
G01X-76858D02*
X-75274Y-138210D01*
G01X-66241Y-140460D02*
Y-135460D01*
G01Y-136210D02*
X-65824Y-135793D01*
X-65408Y-135543D01*
X-64741Y-135460D01*
X-64158Y-135543D01*
X-63574Y-135960D01*
X-63324Y-136543D01*
X-63241Y-137126D01*
X-63324Y-137710D01*
X-63574Y-138293D01*
X-64074Y-138626D01*
X-64741Y-138793D01*
X-65324Y-138710D01*
X-65908Y-138460D01*
X-66241Y-138126D01*
G01X-57641Y-138793D02*
Y-135460D01*
G01Y-136043D02*
X-57974Y-135710D01*
X-58474Y-135543D01*
X-59058Y-135460D01*
X-59641Y-135626D01*
X-60141Y-135960D01*
X-60474Y-136460D01*
X-60641Y-137126D01*
X-60474Y-137793D01*
X-60141Y-138293D01*
X-59641Y-138626D01*
X-59058Y-138793D01*
X-58474Y-138710D01*
X-57974Y-138460D01*
X-57641Y-138126D01*
G01X-52041Y-133793D02*
Y-138793D01*
G01Y-138043D02*
X-52374Y-138460D01*
X-52874Y-138710D01*
X-53458Y-138793D01*
X-54124Y-138626D01*
X-54624Y-138210D01*
X-54958Y-137710D01*
X-55041Y-137126D01*
X-54958Y-136543D01*
X-54624Y-136043D01*
X-54124Y-135626D01*
X-53458Y-135460D01*
X-52874Y-135543D01*
X-52458Y-135710D01*
X-52041Y-136043D01*
G01X-42341Y-133793D02*
Y-138793D01*
G01X-43508Y-135460D02*
X-41174D01*
G01X-36741Y-138793D02*
X-37241Y-138710D01*
X-37741Y-138376D01*
X-38074Y-137793D01*
X-38241Y-137126D01*
X-38074Y-136460D01*
X-37741Y-135876D01*
X-37241Y-135543D01*
X-36741Y-135460D01*
X-36241Y-135543D01*
X-35741Y-135876D01*
X-35408Y-136460D01*
X-35324Y-137126D01*
X-35408Y-137793D01*
X-35741Y-138376D01*
X-36241Y-138710D01*
X-36741Y-138793D01*
G01X-27041Y-140460D02*
Y-135460D01*
G01Y-136210D02*
X-26624Y-135793D01*
X-26208Y-135543D01*
X-25541Y-135460D01*
X-24958Y-135543D01*
X-24374Y-135960D01*
X-24124Y-136543D01*
X-24041Y-137126D01*
X-24124Y-137710D01*
X-24374Y-138293D01*
X-24874Y-138626D01*
X-25541Y-138793D01*
X-26124Y-138710D01*
X-26708Y-138460D01*
X-27041Y-138126D01*
G01X-18441Y-138793D02*
Y-135460D01*
G01Y-136043D02*
X-18774Y-135710D01*
X-19274Y-135543D01*
X-19858Y-135460D01*
X-20441Y-135626D01*
X-20941Y-135960D01*
X-21274Y-136460D01*
X-21441Y-137126D01*
X-21274Y-137793D01*
X-20941Y-138293D01*
X-20441Y-138626D01*
X-19858Y-138793D01*
X-19274Y-138710D01*
X-18774Y-138460D01*
X-18441Y-138126D01*
G01X-12841Y-133793D02*
Y-138793D01*
G01Y-138043D02*
X-13174Y-138460D01*
X-13674Y-138710D01*
X-14258Y-138793D01*
X-14924Y-138626D01*
X-15424Y-138210D01*
X-15758Y-137710D01*
X-15841Y-137126D01*
X-15758Y-136543D01*
X-15424Y-136043D01*
X-14924Y-135626D01*
X-14258Y-135460D01*
X-13674Y-135543D01*
X-13258Y-135710D01*
X-12841Y-136043D01*
G01X-234491Y-123793D02*
Y-118793D01*
G01X-230991D02*
Y-123793D01*
G01Y-121293D02*
X-234491D01*
G01X-228974Y-123793D02*
Y-118793D01*
X-227308D01*
X-226641Y-119043D01*
X-226141Y-119376D01*
X-225724Y-119876D01*
X-225391Y-120460D01*
X-225308Y-121293D01*
X-225391Y-122126D01*
X-225724Y-122710D01*
X-226141Y-123210D01*
X-226641Y-123543D01*
X-227308Y-123793D01*
X-228974D01*
G01X-222541Y-118793D02*
X-220541D01*
G01X-221541D02*
Y-123793D01*
G01X-222541D02*
X-220541D01*
G01X-212008D02*
Y-118793D01*
X-210008D01*
X-209341Y-119043D01*
X-208841Y-119626D01*
X-208674Y-120293D01*
X-208841Y-120960D01*
X-209258Y-121460D01*
X-210008Y-121710D01*
X-212008D01*
G01X-202908Y-119210D02*
X-203408Y-118960D01*
X-203991Y-118793D01*
X-204658D01*
X-205408Y-119043D01*
X-205991Y-119460D01*
X-206408Y-119960D01*
X-206741Y-120793D01*
X-206824Y-121543D01*
X-206658Y-122293D01*
X-206408Y-122793D01*
X-205908Y-123293D01*
X-205324Y-123626D01*
X-204741Y-123793D01*
X-204158D01*
X-203574Y-123626D01*
X-203074Y-123376D01*
X-202658Y-123043D01*
G01X-198474Y-121126D02*
X-198141Y-120876D01*
X-197891Y-120460D01*
X-197724Y-119876D01*
X-197891Y-119376D01*
X-198224Y-119043D01*
X-198808Y-118793D01*
X-201058D01*
Y-123793D01*
X-198308D01*
X-197724Y-123460D01*
X-197391Y-122960D01*
X-197224Y-122376D01*
X-197391Y-121793D01*
X-197891Y-121293D01*
X-198474Y-121126D01*
X-201058D01*
G01X-193541Y-123960D02*
X-193708Y-123876D01*
Y-123710D01*
X-193541Y-123626D01*
X-193374Y-123710D01*
Y-123876D01*
X-193541Y-123960D01*
G01X-234491Y-98126D02*
X-233824Y-98543D01*
X-233074Y-98793D01*
X-232408D01*
X-231741Y-98543D01*
X-231241Y-98126D01*
X-230991Y-97543D01*
X-231158Y-96960D01*
X-231574Y-96460D01*
X-232324Y-96126D01*
X-233324Y-95960D01*
X-233908Y-95626D01*
X-234158Y-95043D01*
X-233991Y-94460D01*
X-233574Y-94043D01*
X-232991Y-93793D01*
X-232408D01*
X-231824Y-93960D01*
X-231324Y-94376D01*
G01X-228391Y-96543D02*
X-225724D01*
X-225974Y-95960D01*
X-226391Y-95626D01*
X-226974Y-95460D01*
X-227558Y-95543D01*
X-228058Y-95793D01*
X-228391Y-96376D01*
X-228558Y-96876D01*
Y-97376D01*
X-228391Y-97876D01*
X-227974Y-98376D01*
X-227474Y-98710D01*
X-226891Y-98793D01*
X-226308Y-98626D01*
X-225724Y-98126D01*
G01X-222708Y-98793D02*
Y-95460D01*
G01Y-96126D02*
X-222291Y-95793D01*
X-221874Y-95543D01*
X-221291Y-95460D01*
X-220874Y-95543D01*
X-220374Y-95793D01*
G01X-217441Y-95460D02*
X-215941Y-98793D01*
X-214441Y-95460D01*
G01X-211591Y-96543D02*
X-208924D01*
X-209174Y-95960D01*
X-209591Y-95626D01*
X-210174Y-95460D01*
X-210758Y-95543D01*
X-211258Y-95793D01*
X-211591Y-96376D01*
X-211758Y-96876D01*
Y-97376D01*
X-211591Y-97876D01*
X-211174Y-98376D01*
X-210674Y-98710D01*
X-210091Y-98793D01*
X-209508Y-98626D01*
X-208924Y-98126D01*
G01X-205908Y-98793D02*
Y-95460D01*
G01Y-96126D02*
X-205491Y-95793D01*
X-205074Y-95543D01*
X-204491Y-95460D01*
X-204074Y-95543D01*
X-203574Y-95793D01*
G01X-195208Y-98793D02*
Y-93793D01*
X-193208D01*
X-192541Y-94043D01*
X-192041Y-94626D01*
X-191874Y-95293D01*
X-192041Y-95960D01*
X-192458Y-96460D01*
X-193208Y-96710D01*
X-195208D01*
G01X-186108Y-94210D02*
X-186608Y-93960D01*
X-187191Y-93793D01*
X-187858D01*
X-188608Y-94043D01*
X-189191Y-94460D01*
X-189608Y-94960D01*
X-189941Y-95793D01*
X-190024Y-96543D01*
X-189858Y-97293D01*
X-189608Y-97793D01*
X-189108Y-98293D01*
X-188524Y-98626D01*
X-187941Y-98793D01*
X-187358D01*
X-186774Y-98626D01*
X-186274Y-98376D01*
X-185858Y-98043D01*
G01X-181674Y-96126D02*
X-181341Y-95876D01*
X-181091Y-95460D01*
X-180924Y-94876D01*
X-181091Y-94376D01*
X-181424Y-94043D01*
X-182008Y-93793D01*
X-184258D01*
Y-98793D01*
X-181508D01*
X-180924Y-98460D01*
X-180591Y-97960D01*
X-180424Y-97376D01*
X-180591Y-96793D01*
X-181091Y-96293D01*
X-181674Y-96126D01*
X-184258D01*
G01X-176741Y-98960D02*
X-176908Y-98876D01*
Y-98710D01*
X-176741Y-98626D01*
X-176574Y-98710D01*
Y-98876D01*
X-176741Y-98960D01*
G01Y-96710D02*
X-176908Y-96626D01*
Y-96460D01*
X-176741Y-96376D01*
X-176574Y-96460D01*
Y-96626D01*
X-176741Y-96710D01*
G01X-172724Y-98793D02*
Y-93793D01*
X-169558D01*
G01X-170724Y-96210D02*
X-172724D01*
G01X-165541Y-98793D02*
X-166041Y-98710D01*
X-166541Y-98376D01*
X-166874Y-97793D01*
X-167041Y-97126D01*
X-166874Y-96460D01*
X-166541Y-95876D01*
X-166041Y-95543D01*
X-165541Y-95460D01*
X-165041Y-95543D01*
X-164541Y-95876D01*
X-164208Y-96460D01*
X-164124Y-97126D01*
X-164208Y-97793D01*
X-164541Y-98376D01*
X-165041Y-98710D01*
X-165541Y-98793D01*
G01X-159941D02*
Y-93793D01*
G01X-154341Y-98793D02*
Y-93793D01*
G01X-148741Y-98793D02*
X-149241Y-98710D01*
X-149741Y-98376D01*
X-150074Y-97793D01*
X-150241Y-97126D01*
X-150074Y-96460D01*
X-149741Y-95876D01*
X-149241Y-95543D01*
X-148741Y-95460D01*
X-148241Y-95543D01*
X-147741Y-95876D01*
X-147408Y-96460D01*
X-147324Y-97126D01*
X-147408Y-97793D01*
X-147741Y-98376D01*
X-148241Y-98710D01*
X-148741Y-98793D01*
G01X-145224Y-95460D02*
X-144224Y-98793D01*
X-143141Y-95460D01*
X-142058Y-98793D01*
X-141058Y-95460D01*
G01X-133108Y-98793D02*
Y-95460D01*
G01Y-96126D02*
X-132691Y-95793D01*
X-132274Y-95543D01*
X-131691Y-95460D01*
X-131274Y-95543D01*
X-130774Y-95793D01*
G01X-126341Y-95460D02*
Y-98793D01*
G01Y-94126D02*
X-126508Y-94043D01*
Y-93876D01*
X-126341Y-93793D01*
X-126174Y-93876D01*
Y-94043D01*
X-126341Y-94126D01*
G01X-121908Y-100043D02*
X-121324Y-100376D01*
X-120658Y-100460D01*
X-120074Y-100376D01*
X-119574Y-99960D01*
X-119241Y-99376D01*
Y-95460D01*
G01Y-96126D02*
X-119574Y-95793D01*
X-120074Y-95543D01*
X-120658Y-95460D01*
X-121324Y-95626D01*
X-121741Y-95960D01*
X-122074Y-96543D01*
X-122241Y-97126D01*
X-122158Y-97626D01*
X-121824Y-98210D01*
X-121324Y-98626D01*
X-120658Y-98793D01*
X-120158Y-98710D01*
X-119574Y-98376D01*
X-119241Y-98043D01*
G01X-116558Y-98793D02*
Y-93793D01*
G01Y-96210D02*
X-116141Y-95793D01*
X-115724Y-95543D01*
X-115058Y-95460D01*
X-114558Y-95543D01*
X-113974Y-95876D01*
X-113724Y-96376D01*
Y-98793D01*
G01X-109541Y-93793D02*
Y-98793D01*
G01X-110708Y-95460D02*
X-108374D01*
G01X-99591Y-98210D02*
X-99174Y-98543D01*
X-98591Y-98793D01*
X-98091D01*
X-97591Y-98626D01*
X-97258Y-98376D01*
X-97091Y-98043D01*
X-97174Y-97543D01*
X-97508Y-97293D01*
X-99008Y-96793D01*
X-99341Y-96210D01*
X-99174Y-95793D01*
X-98841Y-95543D01*
X-98341Y-95460D01*
X-97841Y-95543D01*
X-97341Y-95793D01*
G01X-92741Y-95460D02*
Y-98793D01*
G01Y-94126D02*
X-92908Y-94043D01*
Y-93876D01*
X-92741Y-93793D01*
X-92574Y-93876D01*
Y-94043D01*
X-92741Y-94126D01*
G01X-85641Y-93793D02*
Y-98793D01*
G01Y-98043D02*
X-85974Y-98460D01*
X-86474Y-98710D01*
X-87058Y-98793D01*
X-87724Y-98626D01*
X-88224Y-98210D01*
X-88558Y-97710D01*
X-88641Y-97126D01*
X-88558Y-96543D01*
X-88224Y-96043D01*
X-87724Y-95626D01*
X-87058Y-95460D01*
X-86474Y-95543D01*
X-86058Y-95710D01*
X-85641Y-96043D01*
G01X-82791Y-96543D02*
X-80124D01*
X-80374Y-95960D01*
X-80791Y-95626D01*
X-81374Y-95460D01*
X-81958Y-95543D01*
X-82458Y-95793D01*
X-82791Y-96376D01*
X-82958Y-96876D01*
Y-97376D01*
X-82791Y-97876D01*
X-82374Y-98376D01*
X-81874Y-98710D01*
X-81291Y-98793D01*
X-80708Y-98626D01*
X-80124Y-98126D01*
G01X-71591Y-98210D02*
X-71174Y-98543D01*
X-70591Y-98793D01*
X-70091D01*
X-69591Y-98626D01*
X-69258Y-98376D01*
X-69091Y-98043D01*
X-69174Y-97543D01*
X-69508Y-97293D01*
X-71008Y-96793D01*
X-71341Y-96210D01*
X-71174Y-95793D01*
X-70841Y-95543D01*
X-70341Y-95460D01*
X-69841Y-95543D01*
X-69341Y-95793D01*
G01X-66241Y-100460D02*
Y-95460D01*
G01Y-96210D02*
X-65824Y-95793D01*
X-65408Y-95543D01*
X-64741Y-95460D01*
X-64158Y-95543D01*
X-63574Y-95960D01*
X-63324Y-96543D01*
X-63241Y-97126D01*
X-63324Y-97710D01*
X-63574Y-98293D01*
X-64074Y-98626D01*
X-64741Y-98793D01*
X-65324Y-98710D01*
X-65908Y-98460D01*
X-66241Y-98126D01*
G01X-60391Y-96543D02*
X-57724D01*
X-57974Y-95960D01*
X-58391Y-95626D01*
X-58974Y-95460D01*
X-59558Y-95543D01*
X-60058Y-95793D01*
X-60391Y-96376D01*
X-60558Y-96876D01*
Y-97376D01*
X-60391Y-97876D01*
X-59974Y-98376D01*
X-59474Y-98710D01*
X-58891Y-98793D01*
X-58308Y-98626D01*
X-57724Y-98126D01*
G01X-52208Y-95876D02*
X-52791Y-95543D01*
X-53291Y-95460D01*
X-53958Y-95626D01*
X-54458Y-95960D01*
X-54791Y-96543D01*
X-54874Y-97126D01*
X-54791Y-97710D01*
X-54458Y-98210D01*
X-53958Y-98626D01*
X-53291Y-98793D01*
X-52708Y-98626D01*
X-52208Y-98293D01*
G01X-42508Y-99710D02*
X-42174Y-98626D01*
G01X-36741Y-95460D02*
Y-98793D01*
G01Y-94126D02*
X-36908Y-94043D01*
Y-93876D01*
X-36741Y-93793D01*
X-36574Y-93876D01*
Y-94043D01*
X-36741Y-94126D01*
G01X-31641Y-98793D02*
Y-94543D01*
X-31474Y-94126D01*
X-31141Y-93876D01*
X-30641Y-93793D01*
X-30141Y-93960D01*
X-29891Y-94376D01*
G01X-30891Y-95793D02*
X-32558D01*
G01X-21191Y-98210D02*
X-20774Y-98543D01*
X-20191Y-98793D01*
X-19691D01*
X-19191Y-98626D01*
X-18858Y-98376D01*
X-18691Y-98043D01*
X-18774Y-97543D01*
X-19108Y-97293D01*
X-20608Y-96793D01*
X-20941Y-96210D01*
X-20774Y-95793D01*
X-20441Y-95543D01*
X-19941Y-95460D01*
X-19441Y-95543D01*
X-18941Y-95793D01*
G01X-14341Y-93793D02*
Y-98793D01*
G01X-15508Y-95460D02*
X-13174D01*
G01X-7241Y-98793D02*
Y-95460D01*
G01Y-96043D02*
X-7574Y-95710D01*
X-8074Y-95543D01*
X-8658Y-95460D01*
X-9241Y-95626D01*
X-9741Y-95960D01*
X-10074Y-96460D01*
X-10241Y-97126D01*
X-10074Y-97793D01*
X-9741Y-98293D01*
X-9241Y-98626D01*
X-8658Y-98793D01*
X-8074Y-98710D01*
X-7574Y-98460D01*
X-7241Y-98126D01*
G01X-1808Y-95876D02*
X-2391Y-95543D01*
X-2891Y-95460D01*
X-3558Y-95626D01*
X-4058Y-95960D01*
X-4391Y-96543D01*
X-4474Y-97126D01*
X-4391Y-97710D01*
X-4058Y-98210D01*
X-3558Y-98626D01*
X-2891Y-98793D01*
X-2308Y-98626D01*
X-1808Y-98293D01*
G01X1042Y-98793D02*
Y-93793D01*
G01X3709Y-95460D02*
X1042Y-97376D01*
G01X2126Y-96626D02*
X3876Y-98793D01*
G01X12242Y-95460D02*
Y-97793D01*
X12576Y-98376D01*
X13076Y-98710D01*
X13659Y-98793D01*
X14242Y-98710D01*
X14742Y-98376D01*
X15076Y-97793D01*
G01Y-98793D02*
Y-95460D01*
G01X17759Y-100460D02*
Y-95460D01*
G01Y-96210D02*
X18176Y-95793D01*
X18592Y-95543D01*
X19259Y-95460D01*
X19842Y-95543D01*
X20426Y-95960D01*
X20676Y-96543D01*
X20759Y-97126D01*
X20676Y-97710D01*
X20426Y-98293D01*
X19926Y-98626D01*
X19259Y-98793D01*
X18676Y-98710D01*
X18092Y-98460D01*
X17759Y-98126D01*
G01X28376Y-95460D02*
X29376Y-98793D01*
X30459Y-95460D01*
X31542Y-98793D01*
X32542Y-95460D01*
G01X36059D02*
Y-98793D01*
G01Y-94126D02*
X35892Y-94043D01*
Y-93876D01*
X36059Y-93793D01*
X36226Y-93876D01*
Y-94043D01*
X36059Y-94126D01*
G01X41659Y-93793D02*
Y-98793D01*
G01X40492Y-95460D02*
X42826D01*
G01X45842Y-98793D02*
Y-93793D01*
G01Y-96210D02*
X46259Y-95793D01*
X46676Y-95543D01*
X47342Y-95460D01*
X47842Y-95543D01*
X48426Y-95876D01*
X48676Y-96376D01*
Y-98793D01*
G01X52859D02*
X52359Y-98710D01*
X51859Y-98376D01*
X51526Y-97793D01*
X51359Y-97126D01*
X51526Y-96460D01*
X51859Y-95876D01*
X52359Y-95543D01*
X52859Y-95460D01*
X53359Y-95543D01*
X53859Y-95876D01*
X54192Y-96460D01*
X54276Y-97126D01*
X54192Y-97793D01*
X53859Y-98376D01*
X53359Y-98710D01*
X52859Y-98793D01*
G01X57042Y-95460D02*
Y-97793D01*
X57376Y-98376D01*
X57876Y-98710D01*
X58459Y-98793D01*
X59042Y-98710D01*
X59542Y-98376D01*
X59876Y-97793D01*
G01Y-98793D02*
Y-95460D01*
G01X64059Y-93793D02*
Y-98793D01*
G01X62892Y-95460D02*
X65226D01*
G01X-232741Y-78793D02*
Y-83793D01*
G01X-234658Y-78793D02*
X-230824D01*
G01X-228308Y-83793D02*
Y-80460D01*
G01Y-81126D02*
X-227891Y-80793D01*
X-227474Y-80543D01*
X-226891Y-80460D01*
X-226474Y-80543D01*
X-225974Y-80793D01*
G01X-220041Y-83793D02*
Y-80460D01*
G01Y-81043D02*
X-220374Y-80710D01*
X-220874Y-80543D01*
X-221458Y-80460D01*
X-222041Y-80626D01*
X-222541Y-80960D01*
X-222874Y-81460D01*
X-223041Y-82126D01*
X-222874Y-82793D01*
X-222541Y-83293D01*
X-222041Y-83626D01*
X-221458Y-83793D01*
X-220874Y-83710D01*
X-220374Y-83460D01*
X-220041Y-83126D01*
G01X-214441Y-78793D02*
Y-83793D01*
G01Y-83043D02*
X-214774Y-83460D01*
X-215274Y-83710D01*
X-215858Y-83793D01*
X-216524Y-83626D01*
X-217024Y-83210D01*
X-217358Y-82710D01*
X-217441Y-82126D01*
X-217358Y-81543D01*
X-217024Y-81043D01*
X-216524Y-80626D01*
X-215858Y-80460D01*
X-215274Y-80543D01*
X-214858Y-80710D01*
X-214441Y-81043D01*
G01X-210341Y-80460D02*
Y-83793D01*
G01Y-79126D02*
X-210508Y-79043D01*
Y-78876D01*
X-210341Y-78793D01*
X-210174Y-78876D01*
Y-79043D01*
X-210341Y-79126D01*
G01X-204741Y-78793D02*
Y-83793D01*
G01X-205908Y-80460D02*
X-203574D01*
G01X-199141D02*
Y-83793D01*
G01Y-79126D02*
X-199308Y-79043D01*
Y-78876D01*
X-199141Y-78793D01*
X-198974Y-78876D01*
Y-79043D01*
X-199141Y-79126D01*
G01X-193541Y-83793D02*
X-194041Y-83710D01*
X-194541Y-83376D01*
X-194874Y-82793D01*
X-195041Y-82126D01*
X-194874Y-81460D01*
X-194541Y-80876D01*
X-194041Y-80543D01*
X-193541Y-80460D01*
X-193041Y-80543D01*
X-192541Y-80876D01*
X-192208Y-81460D01*
X-192124Y-82126D01*
X-192208Y-82793D01*
X-192541Y-83376D01*
X-193041Y-83710D01*
X-193541Y-83793D01*
G01X-189358D02*
Y-80460D01*
G01Y-81293D02*
X-189024Y-80876D01*
X-188524Y-80543D01*
X-187858Y-80460D01*
X-187274Y-80543D01*
X-186774Y-80876D01*
X-186524Y-81460D01*
Y-83793D01*
G01X-180841D02*
Y-80460D01*
G01Y-81043D02*
X-181174Y-80710D01*
X-181674Y-80543D01*
X-182258Y-80460D01*
X-182841Y-80626D01*
X-183341Y-80960D01*
X-183674Y-81460D01*
X-183841Y-82126D01*
X-183674Y-82793D01*
X-183341Y-83293D01*
X-182841Y-83626D01*
X-182258Y-83793D01*
X-181674Y-83710D01*
X-181174Y-83460D01*
X-180841Y-83126D01*
G01X-176741Y-83793D02*
Y-78793D01*
G01X-167208Y-83793D02*
Y-78793D01*
X-165208D01*
X-164541Y-79043D01*
X-164041Y-79626D01*
X-163874Y-80293D01*
X-164041Y-80960D01*
X-164458Y-81460D01*
X-165208Y-81710D01*
X-167208D01*
G01X-158108Y-79210D02*
X-158608Y-78960D01*
X-159191Y-78793D01*
X-159858D01*
X-160608Y-79043D01*
X-161191Y-79460D01*
X-161608Y-79960D01*
X-161941Y-80793D01*
X-162024Y-81543D01*
X-161858Y-82293D01*
X-161608Y-82793D01*
X-161108Y-83293D01*
X-160524Y-83626D01*
X-159941Y-83793D01*
X-159358D01*
X-158774Y-83626D01*
X-158274Y-83376D01*
X-157858Y-83043D01*
G01X-153674Y-81126D02*
X-153341Y-80876D01*
X-153091Y-80460D01*
X-152924Y-79876D01*
X-153091Y-79376D01*
X-153424Y-79043D01*
X-154008Y-78793D01*
X-156258D01*
Y-83793D01*
X-153508D01*
X-152924Y-83460D01*
X-152591Y-82960D01*
X-152424Y-82376D01*
X-152591Y-81793D01*
X-153091Y-81293D01*
X-153674Y-81126D01*
X-156258D01*
G01X-148741Y-83960D02*
X-148908Y-83876D01*
Y-83710D01*
X-148741Y-83626D01*
X-148574Y-83710D01*
Y-83876D01*
X-148741Y-83960D01*
G01X-241241Y-113293D02*
X189259D01*
G01X-241241Y-88293D02*
X189259D01*
G01X-242741Y-11293D02*
X189259D01*
G01X-242741Y41707D02*
X189259D01*
G01X-235241Y125207D02*
Y120207D01*
G01X-236408Y123540D02*
X-234074D01*
G01X-229641Y120207D02*
X-230141Y120290D01*
X-230641Y120624D01*
X-230974Y121207D01*
X-231141Y121874D01*
X-230974Y122540D01*
X-230641Y123124D01*
X-230141Y123457D01*
X-229641Y123540D01*
X-229141Y123457D01*
X-228641Y123124D01*
X-228308Y122540D01*
X-228224Y121874D01*
X-228308Y121207D01*
X-228641Y120624D01*
X-229141Y120290D01*
X-229641Y120207D01*
G01X-224041D02*
Y125207D01*
G01X-219691Y122457D02*
X-217024D01*
X-217274Y123040D01*
X-217691Y123374D01*
X-218274Y123540D01*
X-218858Y123457D01*
X-219358Y123207D01*
X-219691Y122624D01*
X-219858Y122124D01*
Y121624D01*
X-219691Y121124D01*
X-219274Y120624D01*
X-218774Y120290D01*
X-218191Y120207D01*
X-217608Y120374D01*
X-217024Y120874D01*
G01X-214008Y120207D02*
Y123540D01*
G01Y122874D02*
X-213591Y123207D01*
X-213174Y123457D01*
X-212591Y123540D01*
X-212174Y123457D01*
X-211674Y123207D01*
G01X-205741Y120207D02*
Y123540D01*
G01Y122957D02*
X-206074Y123290D01*
X-206574Y123457D01*
X-207158Y123540D01*
X-207741Y123374D01*
X-208241Y123040D01*
X-208574Y122540D01*
X-208741Y121874D01*
X-208574Y121207D01*
X-208241Y120707D01*
X-207741Y120374D01*
X-207158Y120207D01*
X-206574Y120290D01*
X-206074Y120540D01*
X-205741Y120874D01*
G01X-203058Y120207D02*
Y123540D01*
G01Y122707D02*
X-202724Y123124D01*
X-202224Y123457D01*
X-201558Y123540D01*
X-200974Y123457D01*
X-200474Y123124D01*
X-200224Y122540D01*
Y120207D01*
G01X-194708Y123124D02*
X-195291Y123457D01*
X-195791Y123540D01*
X-196458Y123374D01*
X-196958Y123040D01*
X-197291Y122457D01*
X-197374Y121874D01*
X-197291Y121290D01*
X-196958Y120790D01*
X-196458Y120374D01*
X-195791Y120207D01*
X-195208Y120374D01*
X-194708Y120707D01*
G01X-191691Y122457D02*
X-189024D01*
X-189274Y123040D01*
X-189691Y123374D01*
X-190274Y123540D01*
X-190858Y123457D01*
X-191358Y123207D01*
X-191691Y122624D01*
X-191858Y122124D01*
Y121624D01*
X-191691Y121124D01*
X-191274Y120624D01*
X-190774Y120290D01*
X-190191Y120207D01*
X-189608Y120374D01*
X-189024Y120874D01*
G01X-179241Y125207D02*
Y120207D01*
G01X-180408Y123540D02*
X-178074D01*
G01X-172141Y120207D02*
Y123540D01*
G01Y122957D02*
X-172474Y123290D01*
X-172974Y123457D01*
X-173558Y123540D01*
X-174141Y123374D01*
X-174641Y123040D01*
X-174974Y122540D01*
X-175141Y121874D01*
X-174974Y121207D01*
X-174641Y120707D01*
X-174141Y120374D01*
X-173558Y120207D01*
X-172974Y120290D01*
X-172474Y120540D01*
X-172141Y120874D01*
G01X-169541Y120207D02*
Y125207D01*
G01Y122707D02*
X-169124Y123207D01*
X-168624Y123457D01*
X-168124Y123540D01*
X-167374Y123374D01*
X-166874Y123040D01*
X-166541Y122457D01*
Y121790D01*
X-166708Y121124D01*
X-167041Y120624D01*
X-167624Y120290D01*
X-168124Y120207D01*
X-168624Y120290D01*
X-169124Y120540D01*
X-169541Y120957D01*
G01X-162441Y120207D02*
Y125207D01*
G01X-158091Y122457D02*
X-155424D01*
X-155674Y123040D01*
X-156091Y123374D01*
X-156674Y123540D01*
X-157258Y123457D01*
X-157758Y123207D01*
X-158091Y122624D01*
X-158258Y122124D01*
Y121624D01*
X-158091Y121124D01*
X-157674Y120624D01*
X-157174Y120290D01*
X-156591Y120207D01*
X-156008Y120374D01*
X-155424Y120874D01*
G01X-151241Y120040D02*
X-151408Y120124D01*
Y120290D01*
X-151241Y120374D01*
X-151074Y120290D01*
Y120124D01*
X-151241Y120040D01*
G01X-236574Y130957D02*
X-235991Y130624D01*
X-235491Y130540D01*
X-234824Y130707D01*
X-234324Y131124D01*
X-234074Y131874D01*
Y135540D01*
G01Y136874D02*
X-234241Y136957D01*
Y137124D01*
X-234074Y137207D01*
X-233908Y137124D01*
Y136957D01*
X-234074Y136874D01*
G01X-231058Y135540D02*
Y133207D01*
X-230724Y132624D01*
X-230224Y132290D01*
X-229641Y132207D01*
X-229058Y132290D01*
X-228558Y132624D01*
X-228224Y133207D01*
G01Y132207D02*
Y135540D01*
G01X-225458Y132207D02*
Y135540D01*
G01Y134707D02*
X-225124Y135124D01*
X-224624Y135457D01*
X-223958Y135540D01*
X-223374Y135457D01*
X-222874Y135124D01*
X-222624Y134540D01*
Y132207D01*
G01X-217108Y135124D02*
X-217691Y135457D01*
X-218191Y135540D01*
X-218858Y135374D01*
X-219358Y135040D01*
X-219691Y134457D01*
X-219774Y133874D01*
X-219691Y133290D01*
X-219358Y132790D01*
X-218858Y132374D01*
X-218191Y132207D01*
X-217608Y132374D01*
X-217108Y132707D01*
G01X-212841Y137207D02*
Y132207D01*
G01X-214008Y135540D02*
X-211674D01*
G01X-207241D02*
Y132207D01*
G01Y136874D02*
X-207408Y136957D01*
Y137124D01*
X-207241Y137207D01*
X-207074Y137124D01*
Y136957D01*
X-207241Y136874D01*
G01X-201641Y132207D02*
X-202141Y132290D01*
X-202641Y132624D01*
X-202974Y133207D01*
X-203141Y133874D01*
X-202974Y134540D01*
X-202641Y135124D01*
X-202141Y135457D01*
X-201641Y135540D01*
X-201141Y135457D01*
X-200641Y135124D01*
X-200308Y134540D01*
X-200224Y133874D01*
X-200308Y133207D01*
X-200641Y132624D01*
X-201141Y132290D01*
X-201641Y132207D01*
G01X-197458D02*
Y135540D01*
G01Y134707D02*
X-197124Y135124D01*
X-196624Y135457D01*
X-195958Y135540D01*
X-195374Y135457D01*
X-194874Y135124D01*
X-194624Y134540D01*
Y132207D01*
G01X-186341D02*
Y137207D01*
G01Y134707D02*
X-185924Y135207D01*
X-185424Y135457D01*
X-184924Y135540D01*
X-184174Y135374D01*
X-183674Y135040D01*
X-183341Y134457D01*
Y133790D01*
X-183508Y133124D01*
X-183841Y132624D01*
X-184424Y132290D01*
X-184924Y132207D01*
X-185424Y132290D01*
X-185924Y132540D01*
X-186341Y132957D01*
G01X-180491Y134457D02*
X-177824D01*
X-178074Y135040D01*
X-178491Y135374D01*
X-179074Y135540D01*
X-179658Y135457D01*
X-180158Y135207D01*
X-180491Y134624D01*
X-180658Y134124D01*
Y133624D01*
X-180491Y133124D01*
X-180074Y132624D01*
X-179574Y132290D01*
X-178991Y132207D01*
X-178408Y132374D01*
X-177824Y132874D01*
G01X-173641Y132207D02*
Y137207D01*
G01X-168041Y132207D02*
X-168541Y132290D01*
X-169041Y132624D01*
X-169374Y133207D01*
X-169541Y133874D01*
X-169374Y134540D01*
X-169041Y135124D01*
X-168541Y135457D01*
X-168041Y135540D01*
X-167541Y135457D01*
X-167041Y135124D01*
X-166708Y134540D01*
X-166624Y133874D01*
X-166708Y133207D01*
X-167041Y132624D01*
X-167541Y132290D01*
X-168041Y132207D01*
G01X-164524Y135540D02*
X-163524Y132207D01*
X-162441Y135540D01*
X-161358Y132207D01*
X-160358Y135540D01*
G01X-151241Y137207D02*
Y132207D01*
G01X-152408Y135540D02*
X-150074D01*
G01X-147058Y132207D02*
Y137207D01*
G01Y134790D02*
X-146641Y135207D01*
X-146224Y135457D01*
X-145558Y135540D01*
X-145058Y135457D01*
X-144474Y135124D01*
X-144224Y134624D01*
Y132207D01*
G01X-141291Y134457D02*
X-138624D01*
X-138874Y135040D01*
X-139291Y135374D01*
X-139874Y135540D01*
X-140458Y135457D01*
X-140958Y135207D01*
X-141291Y134624D01*
X-141458Y134124D01*
Y133624D01*
X-141291Y133124D01*
X-140874Y132624D01*
X-140374Y132290D01*
X-139791Y132207D01*
X-139208Y132374D01*
X-138624Y132874D01*
G01X-131341Y132207D02*
Y135540D01*
G01Y134624D02*
X-131091Y135040D01*
X-130674Y135374D01*
X-130091Y135540D01*
X-129508Y135374D01*
X-129091Y135040D01*
X-128841Y134624D01*
Y132207D01*
G01Y134624D02*
X-128591Y135040D01*
X-128174Y135374D01*
X-127591Y135540D01*
X-127008Y135374D01*
X-126591Y135040D01*
X-126341Y134540D01*
Y132207D01*
G01X-123241Y135540D02*
Y132207D01*
G01Y136874D02*
X-123408Y136957D01*
Y137124D01*
X-123241Y137207D01*
X-123074Y137124D01*
Y136957D01*
X-123241Y136874D01*
G01X-119058Y132207D02*
Y135540D01*
G01Y134707D02*
X-118724Y135124D01*
X-118224Y135457D01*
X-117558Y135540D01*
X-116974Y135457D01*
X-116474Y135124D01*
X-116224Y134540D01*
Y132207D01*
G01X-105108Y135124D02*
X-105691Y135457D01*
X-106191Y135540D01*
X-106858Y135374D01*
X-107358Y135040D01*
X-107691Y134457D01*
X-107774Y133874D01*
X-107691Y133290D01*
X-107358Y132790D01*
X-106858Y132374D01*
X-106191Y132207D01*
X-105608Y132374D01*
X-105108Y132707D01*
G01X-100841Y132207D02*
X-101341Y132290D01*
X-101841Y132624D01*
X-102174Y133207D01*
X-102341Y133874D01*
X-102174Y134540D01*
X-101841Y135124D01*
X-101341Y135457D01*
X-100841Y135540D01*
X-100341Y135457D01*
X-99841Y135124D01*
X-99508Y134540D01*
X-99424Y133874D01*
X-99508Y133207D01*
X-99841Y132624D01*
X-100341Y132290D01*
X-100841Y132207D01*
G01X-96658D02*
Y135540D01*
G01Y134707D02*
X-96324Y135124D01*
X-95824Y135457D01*
X-95158Y135540D01*
X-94574Y135457D01*
X-94074Y135124D01*
X-93824Y134540D01*
Y132207D01*
G01X-88141Y137207D02*
Y132207D01*
G01Y132957D02*
X-88474Y132540D01*
X-88974Y132290D01*
X-89558Y132207D01*
X-90224Y132374D01*
X-90724Y132790D01*
X-91058Y133290D01*
X-91141Y133874D01*
X-91058Y134457D01*
X-90724Y134957D01*
X-90224Y135374D01*
X-89558Y135540D01*
X-88974Y135457D01*
X-88558Y135290D01*
X-88141Y134957D01*
G01X-85458Y135540D02*
Y133207D01*
X-85124Y132624D01*
X-84624Y132290D01*
X-84041Y132207D01*
X-83458Y132290D01*
X-82958Y132624D01*
X-82624Y133207D01*
G01Y132207D02*
Y135540D01*
G01X-77108Y135124D02*
X-77691Y135457D01*
X-78191Y135540D01*
X-78858Y135374D01*
X-79358Y135040D01*
X-79691Y134457D01*
X-79774Y133874D01*
X-79691Y133290D01*
X-79358Y132790D01*
X-78858Y132374D01*
X-78191Y132207D01*
X-77608Y132374D01*
X-77108Y132707D01*
G01X-72841Y137207D02*
Y132207D01*
G01X-74008Y135540D02*
X-71674D01*
G01X-67241Y132207D02*
X-67741Y132290D01*
X-68241Y132624D01*
X-68574Y133207D01*
X-68741Y133874D01*
X-68574Y134540D01*
X-68241Y135124D01*
X-67741Y135457D01*
X-67241Y135540D01*
X-66741Y135457D01*
X-66241Y135124D01*
X-65908Y134540D01*
X-65824Y133874D01*
X-65908Y133207D01*
X-66241Y132624D01*
X-66741Y132290D01*
X-67241Y132207D01*
G01X-62808D02*
Y135540D01*
G01Y134874D02*
X-62391Y135207D01*
X-61974Y135457D01*
X-61391Y135540D01*
X-60974Y135457D01*
X-60474Y135207D01*
G01X-52524Y135540D02*
X-51524Y132207D01*
X-50441Y135540D01*
X-49358Y132207D01*
X-48358Y135540D01*
G01X-44841D02*
Y132207D01*
G01Y136874D02*
X-45008Y136957D01*
Y137124D01*
X-44841Y137207D01*
X-44674Y137124D01*
Y136957D01*
X-44841Y136874D01*
G01X-37741Y137207D02*
Y132207D01*
G01Y132957D02*
X-38074Y132540D01*
X-38574Y132290D01*
X-39158Y132207D01*
X-39824Y132374D01*
X-40324Y132790D01*
X-40658Y133290D01*
X-40741Y133874D01*
X-40658Y134457D01*
X-40324Y134957D01*
X-39824Y135374D01*
X-39158Y135540D01*
X-38574Y135457D01*
X-38158Y135290D01*
X-37741Y134957D01*
G01X-33641Y137207D02*
Y132207D01*
G01X-34808Y135540D02*
X-32474D01*
G01X-29458Y132207D02*
Y137207D01*
G01Y134790D02*
X-29041Y135207D01*
X-28624Y135457D01*
X-27958Y135540D01*
X-27458Y135457D01*
X-26874Y135124D01*
X-26624Y134624D01*
Y132207D01*
G01X-18091Y132790D02*
X-17674Y132457D01*
X-17091Y132207D01*
X-16591D01*
X-16091Y132374D01*
X-15758Y132624D01*
X-15591Y132957D01*
X-15674Y133457D01*
X-16008Y133707D01*
X-17508Y134207D01*
X-17841Y134790D01*
X-17674Y135207D01*
X-17341Y135457D01*
X-16841Y135540D01*
X-16341Y135457D01*
X-15841Y135207D01*
G01X-12741Y130540D02*
Y135540D01*
G01Y134790D02*
X-12324Y135207D01*
X-11908Y135457D01*
X-11241Y135540D01*
X-10658Y135457D01*
X-10074Y135040D01*
X-9824Y134457D01*
X-9741Y133874D01*
X-9824Y133290D01*
X-10074Y132707D01*
X-10574Y132374D01*
X-11241Y132207D01*
X-11824Y132290D01*
X-12408Y132540D01*
X-12741Y132874D01*
G01X-6891Y134457D02*
X-4224D01*
X-4474Y135040D01*
X-4891Y135374D01*
X-5474Y135540D01*
X-6058Y135457D01*
X-6558Y135207D01*
X-6891Y134624D01*
X-7058Y134124D01*
Y133624D01*
X-6891Y133124D01*
X-6474Y132624D01*
X-5974Y132290D01*
X-5391Y132207D01*
X-4808Y132374D01*
X-4224Y132874D01*
G01X1292Y135124D02*
X709Y135457D01*
X209Y135540D01*
X-458Y135374D01*
X-958Y135040D01*
X-1291Y134457D01*
X-1374Y133874D01*
X-1291Y133290D01*
X-958Y132790D01*
X-458Y132374D01*
X209Y132207D01*
X792Y132374D01*
X1292Y132707D01*
G01X5559Y135540D02*
Y132207D01*
G01Y136874D02*
X5392Y136957D01*
Y137124D01*
X5559Y137207D01*
X5726Y137124D01*
Y136957D01*
X5559Y136874D01*
G01X10659Y132207D02*
Y136457D01*
X10826Y136874D01*
X11159Y137124D01*
X11659Y137207D01*
X12159Y137040D01*
X12409Y136624D01*
G01X11409Y135207D02*
X9742D01*
G01X16759Y135540D02*
Y132207D01*
G01Y136874D02*
X16592Y136957D01*
Y137124D01*
X16759Y137207D01*
X16926Y137124D01*
Y136957D01*
X16759Y136874D01*
G01X21109Y134457D02*
X23776D01*
X23526Y135040D01*
X23109Y135374D01*
X22526Y135540D01*
X21942Y135457D01*
X21442Y135207D01*
X21109Y134624D01*
X20942Y134124D01*
Y133624D01*
X21109Y133124D01*
X21526Y132624D01*
X22026Y132290D01*
X22609Y132207D01*
X23192Y132374D01*
X23776Y132874D01*
G01X29459Y137207D02*
Y132207D01*
G01Y132957D02*
X29126Y132540D01*
X28626Y132290D01*
X28042Y132207D01*
X27376Y132374D01*
X26876Y132790D01*
X26542Y133290D01*
X26459Y133874D01*
X26542Y134457D01*
X26876Y134957D01*
X27376Y135374D01*
X28042Y135540D01*
X28626Y135457D01*
X29042Y135290D01*
X29459Y134957D01*
G01X39159Y132207D02*
X38659Y132290D01*
X38159Y132624D01*
X37826Y133207D01*
X37659Y133874D01*
X37826Y134540D01*
X38159Y135124D01*
X38659Y135457D01*
X39159Y135540D01*
X39659Y135457D01*
X40159Y135124D01*
X40492Y134540D01*
X40576Y133874D01*
X40492Y133207D01*
X40159Y132624D01*
X39659Y132290D01*
X39159Y132207D01*
G01X43342D02*
Y135540D01*
G01Y134707D02*
X43676Y135124D01*
X44176Y135457D01*
X44842Y135540D01*
X45426Y135457D01*
X45926Y135124D01*
X46176Y134540D01*
Y132207D01*
G01X55959Y137207D02*
Y132207D01*
G01X54792Y135540D02*
X57126D01*
G01X60142Y132207D02*
Y137207D01*
G01Y134790D02*
X60559Y135207D01*
X60976Y135457D01*
X61642Y135540D01*
X62142Y135457D01*
X62726Y135124D01*
X62976Y134624D01*
Y132207D01*
G01X65909Y134457D02*
X68576D01*
X68326Y135040D01*
X67909Y135374D01*
X67326Y135540D01*
X66742Y135457D01*
X66242Y135207D01*
X65909Y134624D01*
X65742Y134124D01*
Y133624D01*
X65909Y133124D01*
X66326Y132624D01*
X66826Y132290D01*
X67409Y132207D01*
X67992Y132374D01*
X68576Y132874D01*
G01X-236991Y142707D02*
Y147707D01*
G01X-233491D02*
Y142707D01*
G01Y145207D02*
X-236991D01*
G01X-229641Y142707D02*
X-230141Y142790D01*
X-230641Y143124D01*
X-230974Y143707D01*
X-231141Y144374D01*
X-230974Y145040D01*
X-230641Y145624D01*
X-230141Y145957D01*
X-229641Y146040D01*
X-229141Y145957D01*
X-228641Y145624D01*
X-228308Y145040D01*
X-228224Y144374D01*
X-228308Y143707D01*
X-228641Y143124D01*
X-229141Y142790D01*
X-229641Y142707D01*
G01X-226124Y146040D02*
X-225124Y142707D01*
X-224041Y146040D01*
X-222958Y142707D01*
X-221958Y146040D01*
G01X-219691Y144957D02*
X-217024D01*
X-217274Y145540D01*
X-217691Y145874D01*
X-218274Y146040D01*
X-218858Y145957D01*
X-219358Y145707D01*
X-219691Y145124D01*
X-219858Y144624D01*
Y144124D01*
X-219691Y143624D01*
X-219274Y143124D01*
X-218774Y142790D01*
X-218191Y142707D01*
X-217608Y142874D01*
X-217024Y143374D01*
G01X-214341Y146040D02*
X-212841Y142707D01*
X-211341Y146040D01*
G01X-208491Y144957D02*
X-205824D01*
X-206074Y145540D01*
X-206491Y145874D01*
X-207074Y146040D01*
X-207658Y145957D01*
X-208158Y145707D01*
X-208491Y145124D01*
X-208658Y144624D01*
Y144124D01*
X-208491Y143624D01*
X-208074Y143124D01*
X-207574Y142790D01*
X-206991Y142707D01*
X-206408Y142874D01*
X-205824Y143374D01*
G01X-202808Y142707D02*
Y146040D01*
G01Y145374D02*
X-202391Y145707D01*
X-201974Y145957D01*
X-201391Y146040D01*
X-200974Y145957D01*
X-200474Y145707D01*
G01X-196208Y141790D02*
X-195874Y142874D01*
G01X-190441Y147707D02*
Y142707D01*
G01X-191608Y146040D02*
X-189274D01*
G01X-186258Y142707D02*
Y147707D01*
G01Y145290D02*
X-185841Y145707D01*
X-185424Y145957D01*
X-184758Y146040D01*
X-184258Y145957D01*
X-183674Y145624D01*
X-183424Y145124D01*
Y142707D01*
G01X-180491Y144957D02*
X-177824D01*
X-178074Y145540D01*
X-178491Y145874D01*
X-179074Y146040D01*
X-179658Y145957D01*
X-180158Y145707D01*
X-180491Y145124D01*
X-180658Y144624D01*
Y144124D01*
X-180491Y143624D01*
X-180074Y143124D01*
X-179574Y142790D01*
X-178991Y142707D01*
X-178408Y142874D01*
X-177824Y143374D01*
G01X-168041Y147707D02*
Y142707D01*
G01X-169208Y146040D02*
X-166874D01*
G01X-160941Y142707D02*
Y146040D01*
G01Y145457D02*
X-161274Y145790D01*
X-161774Y145957D01*
X-162358Y146040D01*
X-162941Y145874D01*
X-163441Y145540D01*
X-163774Y145040D01*
X-163941Y144374D01*
X-163774Y143707D01*
X-163441Y143207D01*
X-162941Y142874D01*
X-162358Y142707D01*
X-161774Y142790D01*
X-161274Y143040D01*
X-160941Y143374D01*
G01X-158258Y142707D02*
Y146040D01*
G01Y145207D02*
X-157924Y145624D01*
X-157424Y145957D01*
X-156758Y146040D01*
X-156174Y145957D01*
X-155674Y145624D01*
X-155424Y145040D01*
Y142707D01*
G01X-152408Y141457D02*
X-151824Y141124D01*
X-151158Y141040D01*
X-150574Y141124D01*
X-150074Y141540D01*
X-149741Y142124D01*
Y146040D01*
G01Y145374D02*
X-150074Y145707D01*
X-150574Y145957D01*
X-151158Y146040D01*
X-151824Y145874D01*
X-152241Y145540D01*
X-152574Y144957D01*
X-152741Y144374D01*
X-152658Y143874D01*
X-152324Y143290D01*
X-151824Y142874D01*
X-151158Y142707D01*
X-150658Y142790D01*
X-150074Y143124D01*
X-149741Y143457D01*
G01X-146891Y144957D02*
X-144224D01*
X-144474Y145540D01*
X-144891Y145874D01*
X-145474Y146040D01*
X-146058Y145957D01*
X-146558Y145707D01*
X-146891Y145124D01*
X-147058Y144624D01*
Y144124D01*
X-146891Y143624D01*
X-146474Y143124D01*
X-145974Y142790D01*
X-145391Y142707D01*
X-144808Y142874D01*
X-144224Y143374D01*
G01X-141458Y142707D02*
Y146040D01*
G01Y145207D02*
X-141124Y145624D01*
X-140624Y145957D01*
X-139958Y146040D01*
X-139374Y145957D01*
X-138874Y145624D01*
X-138624Y145040D01*
Y142707D01*
G01X-133108Y145624D02*
X-133691Y145957D01*
X-134191Y146040D01*
X-134858Y145874D01*
X-135358Y145540D01*
X-135691Y144957D01*
X-135774Y144374D01*
X-135691Y143790D01*
X-135358Y143290D01*
X-134858Y142874D01*
X-134191Y142707D01*
X-133608Y142874D01*
X-133108Y143207D01*
G01X-130591Y141207D02*
X-130091Y141040D01*
X-129424Y141207D01*
X-129008Y141540D01*
X-128674Y141957D01*
X-128174Y143290D01*
X-127091Y146040D01*
G01X-129758D02*
X-128174Y143290D01*
G01X-118891D02*
X-118474Y142957D01*
X-117891Y142707D01*
X-117391D01*
X-116891Y142874D01*
X-116558Y143124D01*
X-116391Y143457D01*
X-116474Y143957D01*
X-116808Y144207D01*
X-118308Y144707D01*
X-118641Y145290D01*
X-118474Y145707D01*
X-118141Y145957D01*
X-117641Y146040D01*
X-117141Y145957D01*
X-116641Y145707D01*
G01X-113458Y142707D02*
Y147707D01*
G01Y145290D02*
X-113041Y145707D01*
X-112624Y145957D01*
X-111958Y146040D01*
X-111458Y145957D01*
X-110874Y145624D01*
X-110624Y145124D01*
Y142707D01*
G01X-106441D02*
X-106941Y142790D01*
X-107441Y143124D01*
X-107774Y143707D01*
X-107941Y144374D01*
X-107774Y145040D01*
X-107441Y145624D01*
X-106941Y145957D01*
X-106441Y146040D01*
X-105941Y145957D01*
X-105441Y145624D01*
X-105108Y145040D01*
X-105024Y144374D01*
X-105108Y143707D01*
X-105441Y143124D01*
X-105941Y142790D01*
X-106441Y142707D01*
G01X-102258Y146040D02*
Y143707D01*
X-101924Y143124D01*
X-101424Y142790D01*
X-100841Y142707D01*
X-100258Y142790D01*
X-99758Y143124D01*
X-99424Y143707D01*
G01Y142707D02*
Y146040D01*
G01X-95241Y142707D02*
Y147707D01*
G01X-88141D02*
Y142707D01*
G01Y143457D02*
X-88474Y143040D01*
X-88974Y142790D01*
X-89558Y142707D01*
X-90224Y142874D01*
X-90724Y143290D01*
X-91058Y143790D01*
X-91141Y144374D01*
X-91058Y144957D01*
X-90724Y145457D01*
X-90224Y145874D01*
X-89558Y146040D01*
X-88974Y145957D01*
X-88558Y145790D01*
X-88141Y145457D01*
G01X-79858Y142707D02*
Y146040D01*
G01Y145207D02*
X-79524Y145624D01*
X-79024Y145957D01*
X-78358Y146040D01*
X-77774Y145957D01*
X-77274Y145624D01*
X-77024Y145040D01*
Y142707D01*
G01X-72841D02*
X-73341Y142790D01*
X-73841Y143124D01*
X-74174Y143707D01*
X-74341Y144374D01*
X-74174Y145040D01*
X-73841Y145624D01*
X-73341Y145957D01*
X-72841Y146040D01*
X-72341Y145957D01*
X-71841Y145624D01*
X-71508Y145040D01*
X-71424Y144374D01*
X-71508Y143707D01*
X-71841Y143124D01*
X-72341Y142790D01*
X-72841Y142707D01*
G01X-67241Y147707D02*
Y142707D01*
G01X-68408Y146040D02*
X-66074D01*
G01X-57208Y142707D02*
Y146040D01*
G01Y145374D02*
X-56791Y145707D01*
X-56374Y145957D01*
X-55791Y146040D01*
X-55374Y145957D01*
X-54874Y145707D01*
G01X-51691Y144957D02*
X-49024D01*
X-49274Y145540D01*
X-49691Y145874D01*
X-50274Y146040D01*
X-50858Y145957D01*
X-51358Y145707D01*
X-51691Y145124D01*
X-51858Y144624D01*
Y144124D01*
X-51691Y143624D01*
X-51274Y143124D01*
X-50774Y142790D01*
X-50191Y142707D01*
X-49608Y142874D01*
X-49024Y143374D01*
G01X-43341Y147707D02*
Y142707D01*
G01Y143457D02*
X-43674Y143040D01*
X-44174Y142790D01*
X-44758Y142707D01*
X-45424Y142874D01*
X-45924Y143290D01*
X-46258Y143790D01*
X-46341Y144374D01*
X-46258Y144957D01*
X-45924Y145457D01*
X-45424Y145874D01*
X-44758Y146040D01*
X-44174Y145957D01*
X-43758Y145790D01*
X-43341Y145457D01*
G01X-40658Y146040D02*
Y143707D01*
X-40324Y143124D01*
X-39824Y142790D01*
X-39241Y142707D01*
X-38658Y142790D01*
X-38158Y143124D01*
X-37824Y143707D01*
G01Y142707D02*
Y146040D01*
G01X-32308Y145624D02*
X-32891Y145957D01*
X-33391Y146040D01*
X-34058Y145874D01*
X-34558Y145540D01*
X-34891Y144957D01*
X-34974Y144374D01*
X-34891Y143790D01*
X-34558Y143290D01*
X-34058Y142874D01*
X-33391Y142707D01*
X-32808Y142874D01*
X-32308Y143207D01*
G01X-29291Y144957D02*
X-26624D01*
X-26874Y145540D01*
X-27291Y145874D01*
X-27874Y146040D01*
X-28458Y145957D01*
X-28958Y145707D01*
X-29291Y145124D01*
X-29458Y144624D01*
Y144124D01*
X-29291Y143624D01*
X-28874Y143124D01*
X-28374Y142790D01*
X-27791Y142707D01*
X-27208Y142874D01*
X-26624Y143374D01*
G01X-16841Y147707D02*
Y142707D01*
G01X-18008Y146040D02*
X-15674D01*
G01X-12658Y142707D02*
Y147707D01*
G01Y145290D02*
X-12241Y145707D01*
X-11824Y145957D01*
X-11158Y146040D01*
X-10658Y145957D01*
X-10074Y145624D01*
X-9824Y145124D01*
Y142707D01*
G01X-6891Y144957D02*
X-4224D01*
X-4474Y145540D01*
X-4891Y145874D01*
X-5474Y146040D01*
X-6058Y145957D01*
X-6558Y145707D01*
X-6891Y145124D01*
X-7058Y144624D01*
Y144124D01*
X-6891Y143624D01*
X-6474Y143124D01*
X-5974Y142790D01*
X-5391Y142707D01*
X-4808Y142874D01*
X-4224Y143374D01*
G01X5559Y142707D02*
Y147707D01*
G01X12659Y142707D02*
Y146040D01*
G01Y145457D02*
X12326Y145790D01*
X11826Y145957D01*
X11242Y146040D01*
X10659Y145874D01*
X10159Y145540D01*
X9826Y145040D01*
X9659Y144374D01*
X9826Y143707D01*
X10159Y143207D01*
X10659Y142874D01*
X11242Y142707D01*
X11826Y142790D01*
X12326Y143040D01*
X12659Y143374D01*
G01X15342Y142707D02*
Y146040D01*
G01Y145207D02*
X15676Y145624D01*
X16176Y145957D01*
X16842Y146040D01*
X17426Y145957D01*
X17926Y145624D01*
X18176Y145040D01*
Y142707D01*
G01X23859Y147707D02*
Y142707D01*
G01Y143457D02*
X23526Y143040D01*
X23026Y142790D01*
X22442Y142707D01*
X21776Y142874D01*
X21276Y143290D01*
X20942Y143790D01*
X20859Y144374D01*
X20942Y144957D01*
X21276Y145457D01*
X21776Y145874D01*
X22442Y146040D01*
X23026Y145957D01*
X23442Y145790D01*
X23859Y145457D01*
G01X26459Y142540D02*
X29459Y147707D01*
G01X34892Y145624D02*
X34309Y145957D01*
X33809Y146040D01*
X33142Y145874D01*
X32642Y145540D01*
X32309Y144957D01*
X32226Y144374D01*
X32309Y143790D01*
X32642Y143290D01*
X33142Y142874D01*
X33809Y142707D01*
X34392Y142874D01*
X34892Y143207D01*
G01X39159Y142707D02*
X38659Y142790D01*
X38159Y143124D01*
X37826Y143707D01*
X37659Y144374D01*
X37826Y145040D01*
X38159Y145624D01*
X38659Y145957D01*
X39159Y146040D01*
X39659Y145957D01*
X40159Y145624D01*
X40492Y145040D01*
X40576Y144374D01*
X40492Y143707D01*
X40159Y143124D01*
X39659Y142790D01*
X39159Y142707D01*
G01X43342D02*
Y146040D01*
G01Y145207D02*
X43676Y145624D01*
X44176Y145957D01*
X44842Y146040D01*
X45426Y145957D01*
X45926Y145624D01*
X46176Y145040D01*
Y142707D01*
G01X51859Y147707D02*
Y142707D01*
G01Y143457D02*
X51526Y143040D01*
X51026Y142790D01*
X50442Y142707D01*
X49776Y142874D01*
X49276Y143290D01*
X48942Y143790D01*
X48859Y144374D01*
X48942Y144957D01*
X49276Y145457D01*
X49776Y145874D01*
X50442Y146040D01*
X51026Y145957D01*
X51442Y145790D01*
X51859Y145457D01*
G01X54542Y146040D02*
Y143707D01*
X54876Y143124D01*
X55376Y142790D01*
X55959Y142707D01*
X56542Y142790D01*
X57042Y143124D01*
X57376Y143707D01*
G01Y142707D02*
Y146040D01*
G01X62892Y145624D02*
X62309Y145957D01*
X61809Y146040D01*
X61142Y145874D01*
X60642Y145540D01*
X60309Y144957D01*
X60226Y144374D01*
X60309Y143790D01*
X60642Y143290D01*
X61142Y142874D01*
X61809Y142707D01*
X62392Y142874D01*
X62892Y143207D01*
G01X67159Y147707D02*
Y142707D01*
G01X65992Y146040D02*
X68326D01*
G01X72759Y142707D02*
X72259Y142790D01*
X71759Y143124D01*
X71426Y143707D01*
X71259Y144374D01*
X71426Y145040D01*
X71759Y145624D01*
X72259Y145957D01*
X72759Y146040D01*
X73259Y145957D01*
X73759Y145624D01*
X74092Y145040D01*
X74176Y144374D01*
X74092Y143707D01*
X73759Y143124D01*
X73259Y142790D01*
X72759Y142707D01*
G01X77192D02*
Y146040D01*
G01Y145374D02*
X77609Y145707D01*
X78026Y145957D01*
X78609Y146040D01*
X79026Y145957D01*
X79526Y145707D01*
G01X-233741Y153207D02*
Y156540D01*
G01Y155957D02*
X-234074Y156290D01*
X-234574Y156457D01*
X-235158Y156540D01*
X-235741Y156374D01*
X-236241Y156040D01*
X-236574Y155540D01*
X-236741Y154874D01*
X-236574Y154207D01*
X-236241Y153707D01*
X-235741Y153374D01*
X-235158Y153207D01*
X-234574Y153290D01*
X-234074Y153540D01*
X-233741Y153874D01*
G01X-228308Y156124D02*
X-228891Y156457D01*
X-229391Y156540D01*
X-230058Y156374D01*
X-230558Y156040D01*
X-230891Y155457D01*
X-230974Y154874D01*
X-230891Y154290D01*
X-230558Y153790D01*
X-230058Y153374D01*
X-229391Y153207D01*
X-228808Y153374D01*
X-228308Y153707D01*
G01X-222708Y156124D02*
X-223291Y156457D01*
X-223791Y156540D01*
X-224458Y156374D01*
X-224958Y156040D01*
X-225291Y155457D01*
X-225374Y154874D01*
X-225291Y154290D01*
X-224958Y153790D01*
X-224458Y153374D01*
X-223791Y153207D01*
X-223208Y153374D01*
X-222708Y153707D01*
G01X-219691Y155457D02*
X-217024D01*
X-217274Y156040D01*
X-217691Y156374D01*
X-218274Y156540D01*
X-218858Y156457D01*
X-219358Y156207D01*
X-219691Y155624D01*
X-219858Y155124D01*
Y154624D01*
X-219691Y154124D01*
X-219274Y153624D01*
X-218774Y153290D01*
X-218191Y153207D01*
X-217608Y153374D01*
X-217024Y153874D01*
G01X-214341Y151540D02*
Y156540D01*
G01Y155790D02*
X-213924Y156207D01*
X-213508Y156457D01*
X-212841Y156540D01*
X-212258Y156457D01*
X-211674Y156040D01*
X-211424Y155457D01*
X-211341Y154874D01*
X-211424Y154290D01*
X-211674Y153707D01*
X-212174Y153374D01*
X-212841Y153207D01*
X-213424Y153290D01*
X-214008Y153540D01*
X-214341Y153874D01*
G01X-207241Y158207D02*
Y153207D01*
G01X-208408Y156540D02*
X-206074D01*
G01X-200141Y153207D02*
Y156540D01*
G01Y155957D02*
X-200474Y156290D01*
X-200974Y156457D01*
X-201558Y156540D01*
X-202141Y156374D01*
X-202641Y156040D01*
X-202974Y155540D01*
X-203141Y154874D01*
X-202974Y154207D01*
X-202641Y153707D01*
X-202141Y153374D01*
X-201558Y153207D01*
X-200974Y153290D01*
X-200474Y153540D01*
X-200141Y153874D01*
G01X-197541Y153207D02*
Y158207D01*
G01Y155707D02*
X-197124Y156207D01*
X-196624Y156457D01*
X-196124Y156540D01*
X-195374Y156374D01*
X-194874Y156040D01*
X-194541Y155457D01*
Y154790D01*
X-194708Y154124D01*
X-195041Y153624D01*
X-195624Y153290D01*
X-196124Y153207D01*
X-196624Y153290D01*
X-197124Y153540D01*
X-197541Y153957D01*
G01X-190441Y153207D02*
Y158207D01*
G01X-186091Y155457D02*
X-183424D01*
X-183674Y156040D01*
X-184091Y156374D01*
X-184674Y156540D01*
X-185258Y156457D01*
X-185758Y156207D01*
X-186091Y155624D01*
X-186258Y155124D01*
Y154624D01*
X-186091Y154124D01*
X-185674Y153624D01*
X-185174Y153290D01*
X-184591Y153207D01*
X-184008Y153374D01*
X-183424Y153874D01*
G01X-179241Y153040D02*
X-179408Y153124D01*
Y153290D01*
X-179241Y153374D01*
X-179074Y153290D01*
Y153124D01*
X-179241Y153040D01*
G01X-235241Y168707D02*
Y163707D01*
G01X-237158Y168707D02*
X-233324D01*
G01X-231058Y163707D02*
Y168707D01*
G01Y166290D02*
X-230641Y166707D01*
X-230224Y166957D01*
X-229558Y167040D01*
X-229058Y166957D01*
X-228474Y166624D01*
X-228224Y166124D01*
Y163707D01*
G01X-225291Y165957D02*
X-222624D01*
X-222874Y166540D01*
X-223291Y166874D01*
X-223874Y167040D01*
X-224458Y166957D01*
X-224958Y166707D01*
X-225291Y166124D01*
X-225458Y165624D01*
Y165124D01*
X-225291Y164624D01*
X-224874Y164124D01*
X-224374Y163790D01*
X-223791Y163707D01*
X-223208Y163874D01*
X-222624Y164374D01*
G01X-214341Y163707D02*
Y168707D01*
G01Y166207D02*
X-213924Y166707D01*
X-213424Y166957D01*
X-212924Y167040D01*
X-212174Y166874D01*
X-211674Y166540D01*
X-211341Y165957D01*
Y165290D01*
X-211508Y164624D01*
X-211841Y164124D01*
X-212424Y163790D01*
X-212924Y163707D01*
X-213424Y163790D01*
X-213924Y164040D01*
X-214341Y164457D01*
G01X-208408Y163707D02*
Y167040D01*
G01Y166374D02*
X-207991Y166707D01*
X-207574Y166957D01*
X-206991Y167040D01*
X-206574Y166957D01*
X-206074Y166707D01*
G01X-202891Y165957D02*
X-200224D01*
X-200474Y166540D01*
X-200891Y166874D01*
X-201474Y167040D01*
X-202058Y166957D01*
X-202558Y166707D01*
X-202891Y166124D01*
X-203058Y165624D01*
Y165124D01*
X-202891Y164624D01*
X-202474Y164124D01*
X-201974Y163790D01*
X-201391Y163707D01*
X-200808Y163874D01*
X-200224Y164374D01*
G01X-194541Y163707D02*
Y167040D01*
G01Y166457D02*
X-194874Y166790D01*
X-195374Y166957D01*
X-195958Y167040D01*
X-196541Y166874D01*
X-197041Y166540D01*
X-197374Y166040D01*
X-197541Y165374D01*
X-197374Y164707D01*
X-197041Y164207D01*
X-196541Y163874D01*
X-195958Y163707D01*
X-195374Y163790D01*
X-194874Y164040D01*
X-194541Y164374D01*
G01X-191858Y163707D02*
Y168707D01*
G01X-189191Y167040D02*
X-191858Y165124D01*
G01X-190774Y165874D02*
X-189024Y163707D01*
G01X-184841D02*
X-185341Y163790D01*
X-185841Y164124D01*
X-186174Y164707D01*
X-186341Y165374D01*
X-186174Y166040D01*
X-185841Y166624D01*
X-185341Y166957D01*
X-184841Y167040D01*
X-184341Y166957D01*
X-183841Y166624D01*
X-183508Y166040D01*
X-183424Y165374D01*
X-183508Y164707D01*
X-183841Y164124D01*
X-184341Y163790D01*
X-184841Y163707D01*
G01X-180658Y167040D02*
Y164707D01*
X-180324Y164124D01*
X-179824Y163790D01*
X-179241Y163707D01*
X-178658Y163790D01*
X-178158Y164124D01*
X-177824Y164707D01*
G01Y163707D02*
Y167040D01*
G01X-173641Y168707D02*
Y163707D01*
G01X-174808Y167040D02*
X-172474D01*
G01X-162441D02*
Y163707D01*
G01Y168374D02*
X-162608Y168457D01*
Y168624D01*
X-162441Y168707D01*
X-162274Y168624D01*
Y168457D01*
X-162441Y168374D01*
G01X-158091Y164290D02*
X-157674Y163957D01*
X-157091Y163707D01*
X-156591D01*
X-156091Y163874D01*
X-155758Y164124D01*
X-155591Y164457D01*
X-155674Y164957D01*
X-156008Y165207D01*
X-157508Y165707D01*
X-157841Y166290D01*
X-157674Y166707D01*
X-157341Y166957D01*
X-156841Y167040D01*
X-156341Y166957D01*
X-155841Y166707D01*
G01X-147058Y163707D02*
Y167040D01*
G01Y166207D02*
X-146724Y166624D01*
X-146224Y166957D01*
X-145558Y167040D01*
X-144974Y166957D01*
X-144474Y166624D01*
X-144224Y166040D01*
Y163707D01*
G01X-140041D02*
X-140541Y163790D01*
X-141041Y164124D01*
X-141374Y164707D01*
X-141541Y165374D01*
X-141374Y166040D01*
X-141041Y166624D01*
X-140541Y166957D01*
X-140041Y167040D01*
X-139541Y166957D01*
X-139041Y166624D01*
X-138708Y166040D01*
X-138624Y165374D01*
X-138708Y164707D01*
X-139041Y164124D01*
X-139541Y163790D01*
X-140041Y163707D01*
G01X-134441Y168707D02*
Y163707D01*
G01X-135608Y167040D02*
X-133274D01*
G01X-121741Y163707D02*
Y167040D01*
G01Y166457D02*
X-122074Y166790D01*
X-122574Y166957D01*
X-123158Y167040D01*
X-123741Y166874D01*
X-124241Y166540D01*
X-124574Y166040D01*
X-124741Y165374D01*
X-124574Y164707D01*
X-124241Y164207D01*
X-123741Y163874D01*
X-123158Y163707D01*
X-122574Y163790D01*
X-122074Y164040D01*
X-121741Y164374D01*
G01X-117641Y163707D02*
Y168707D01*
G01X-112041Y163707D02*
Y168707D01*
G01X-106441Y163707D02*
X-106941Y163790D01*
X-107441Y164124D01*
X-107774Y164707D01*
X-107941Y165374D01*
X-107774Y166040D01*
X-107441Y166624D01*
X-106941Y166957D01*
X-106441Y167040D01*
X-105941Y166957D01*
X-105441Y166624D01*
X-105108Y166040D01*
X-105024Y165374D01*
X-105108Y164707D01*
X-105441Y164124D01*
X-105941Y163790D01*
X-106441Y163707D01*
G01X-102924Y167040D02*
X-101924Y163707D01*
X-100841Y167040D01*
X-99758Y163707D01*
X-98758Y167040D01*
G01X-96491Y165957D02*
X-93824D01*
X-94074Y166540D01*
X-94491Y166874D01*
X-95074Y167040D01*
X-95658Y166957D01*
X-96158Y166707D01*
X-96491Y166124D01*
X-96658Y165624D01*
Y165124D01*
X-96491Y164624D01*
X-96074Y164124D01*
X-95574Y163790D01*
X-94991Y163707D01*
X-94408Y163874D01*
X-93824Y164374D01*
G01X-88141Y168707D02*
Y163707D01*
G01Y164457D02*
X-88474Y164040D01*
X-88974Y163790D01*
X-89558Y163707D01*
X-90224Y163874D01*
X-90724Y164290D01*
X-91058Y164790D01*
X-91141Y165374D01*
X-91058Y165957D01*
X-90724Y166457D01*
X-90224Y166874D01*
X-89558Y167040D01*
X-88974Y166957D01*
X-88558Y166790D01*
X-88141Y166457D01*
G01X-84208Y162790D02*
X-83874Y163874D01*
G01X-68741Y163707D02*
Y168707D01*
G01Y166207D02*
X-68324Y166707D01*
X-67824Y166957D01*
X-67324Y167040D01*
X-66574Y166874D01*
X-66074Y166540D01*
X-65741Y165957D01*
Y165290D01*
X-65908Y164624D01*
X-66241Y164124D01*
X-66824Y163790D01*
X-67324Y163707D01*
X-67824Y163790D01*
X-68324Y164040D01*
X-68741Y164457D01*
G01X-63058Y167040D02*
Y164707D01*
X-62724Y164124D01*
X-62224Y163790D01*
X-61641Y163707D01*
X-61058Y163790D01*
X-60558Y164124D01*
X-60224Y164707D01*
G01Y163707D02*
Y167040D01*
G01X-56041Y168707D02*
Y163707D01*
G01X-57208Y167040D02*
X-54874D01*
G01X-43341Y163707D02*
Y167040D01*
G01Y166457D02*
X-43674Y166790D01*
X-44174Y166957D01*
X-44758Y167040D01*
X-45341Y166874D01*
X-45841Y166540D01*
X-46174Y166040D01*
X-46341Y165374D01*
X-46174Y164707D01*
X-45841Y164207D01*
X-45341Y163874D01*
X-44758Y163707D01*
X-44174Y163790D01*
X-43674Y164040D01*
X-43341Y164374D01*
G01X-40658Y163707D02*
Y167040D01*
G01Y166207D02*
X-40324Y166624D01*
X-39824Y166957D01*
X-39158Y167040D01*
X-38574Y166957D01*
X-38074Y166624D01*
X-37824Y166040D01*
Y163707D01*
G01X-35058D02*
Y167040D01*
G01Y166207D02*
X-34724Y166624D01*
X-34224Y166957D01*
X-33558Y167040D01*
X-32974Y166957D01*
X-32474Y166624D01*
X-32224Y166040D01*
Y163707D01*
G01X-29458Y167040D02*
Y164707D01*
X-29124Y164124D01*
X-28624Y163790D01*
X-28041Y163707D01*
X-27458Y163790D01*
X-26958Y164124D01*
X-26624Y164707D01*
G01Y163707D02*
Y167040D01*
G01X-20941Y163707D02*
Y167040D01*
G01Y166457D02*
X-21274Y166790D01*
X-21774Y166957D01*
X-22358Y167040D01*
X-22941Y166874D01*
X-23441Y166540D01*
X-23774Y166040D01*
X-23941Y165374D01*
X-23774Y164707D01*
X-23441Y164207D01*
X-22941Y163874D01*
X-22358Y163707D01*
X-21774Y163790D01*
X-21274Y164040D01*
X-20941Y164374D01*
G01X-16841Y163707D02*
Y168707D01*
G01X-6808Y163707D02*
Y167040D01*
G01Y166374D02*
X-6391Y166707D01*
X-5974Y166957D01*
X-5391Y167040D01*
X-4974Y166957D01*
X-4474Y166707D01*
G01X-41Y167040D02*
Y163707D01*
G01Y168374D02*
X-208Y168457D01*
Y168624D01*
X-41Y168707D01*
X126Y168624D01*
Y168457D01*
X-41Y168374D01*
G01X4142Y163707D02*
Y167040D01*
G01Y166207D02*
X4476Y166624D01*
X4976Y166957D01*
X5642Y167040D01*
X6226Y166957D01*
X6726Y166624D01*
X6976Y166040D01*
Y163707D01*
G01X9992Y162457D02*
X10576Y162124D01*
X11242Y162040D01*
X11826Y162124D01*
X12326Y162540D01*
X12659Y163124D01*
Y167040D01*
G01Y166374D02*
X12326Y166707D01*
X11826Y166957D01*
X11242Y167040D01*
X10576Y166874D01*
X10159Y166540D01*
X9826Y165957D01*
X9659Y165374D01*
X9742Y164874D01*
X10076Y164290D01*
X10576Y163874D01*
X11242Y163707D01*
X11742Y163790D01*
X12326Y164124D01*
X12659Y164457D01*
G01X22359Y168707D02*
Y163707D01*
G01X21192Y167040D02*
X23526D01*
G01X29459Y163707D02*
Y167040D01*
G01Y166457D02*
X29126Y166790D01*
X28626Y166957D01*
X28042Y167040D01*
X27459Y166874D01*
X26959Y166540D01*
X26626Y166040D01*
X26459Y165374D01*
X26626Y164707D01*
X26959Y164207D01*
X27459Y163874D01*
X28042Y163707D01*
X28626Y163790D01*
X29126Y164040D01*
X29459Y164374D01*
G01X32142Y163707D02*
Y167040D01*
G01Y166207D02*
X32476Y166624D01*
X32976Y166957D01*
X33642Y167040D01*
X34226Y166957D01*
X34726Y166624D01*
X34976Y166040D01*
Y163707D01*
G01X37992Y162457D02*
X38576Y162124D01*
X39242Y162040D01*
X39826Y162124D01*
X40326Y162540D01*
X40659Y163124D01*
Y167040D01*
G01Y166374D02*
X40326Y166707D01*
X39826Y166957D01*
X39242Y167040D01*
X38576Y166874D01*
X38159Y166540D01*
X37826Y165957D01*
X37659Y165374D01*
X37742Y164874D01*
X38076Y164290D01*
X38576Y163874D01*
X39242Y163707D01*
X39742Y163790D01*
X40326Y164124D01*
X40659Y164457D01*
G01X43509Y165957D02*
X46176D01*
X45926Y166540D01*
X45509Y166874D01*
X44926Y167040D01*
X44342Y166957D01*
X43842Y166707D01*
X43509Y166124D01*
X43342Y165624D01*
Y165124D01*
X43509Y164624D01*
X43926Y164124D01*
X44426Y163790D01*
X45009Y163707D01*
X45592Y163874D01*
X46176Y164374D01*
G01X48942Y163707D02*
Y167040D01*
G01Y166207D02*
X49276Y166624D01*
X49776Y166957D01*
X50442Y167040D01*
X51026Y166957D01*
X51526Y166624D01*
X51776Y166040D01*
Y163707D01*
G01X57292Y166624D02*
X56709Y166957D01*
X56209Y167040D01*
X55542Y166874D01*
X55042Y166540D01*
X54709Y165957D01*
X54626Y165374D01*
X54709Y164790D01*
X55042Y164290D01*
X55542Y163874D01*
X56209Y163707D01*
X56792Y163874D01*
X57292Y164207D01*
G01X59809Y162207D02*
X60309Y162040D01*
X60976Y162207D01*
X61392Y162540D01*
X61726Y162957D01*
X62226Y164290D01*
X63309Y167040D01*
G01X60642D02*
X62226Y164290D01*
G01X72759Y167040D02*
Y163707D01*
G01Y168374D02*
X72592Y168457D01*
Y168624D01*
X72759Y168707D01*
X72926Y168624D01*
Y168457D01*
X72759Y168374D01*
G01X77109Y164290D02*
X77526Y163957D01*
X78109Y163707D01*
X78609D01*
X79109Y163874D01*
X79442Y164124D01*
X79609Y164457D01*
X79526Y164957D01*
X79192Y165207D01*
X77692Y165707D01*
X77359Y166290D01*
X77526Y166707D01*
X77859Y166957D01*
X78359Y167040D01*
X78859Y166957D01*
X79359Y166707D01*
G01X-232241Y188707D02*
Y183707D01*
G01Y184457D02*
X-232574Y184040D01*
X-233074Y183790D01*
X-233658Y183707D01*
X-234324Y183874D01*
X-234824Y184290D01*
X-235158Y184790D01*
X-235241Y185374D01*
X-235158Y185957D01*
X-234824Y186457D01*
X-234324Y186874D01*
X-233658Y187040D01*
X-233074Y186957D01*
X-232658Y186790D01*
X-232241Y186457D01*
G01X-229391Y185957D02*
X-226724D01*
X-226974Y186540D01*
X-227391Y186874D01*
X-227974Y187040D01*
X-228558Y186957D01*
X-229058Y186707D01*
X-229391Y186124D01*
X-229558Y185624D01*
Y185124D01*
X-229391Y184624D01*
X-228974Y184124D01*
X-228474Y183790D01*
X-227891Y183707D01*
X-227308Y183874D01*
X-226724Y184374D01*
G01X-224041Y182040D02*
Y187040D01*
G01Y186290D02*
X-223624Y186707D01*
X-223208Y186957D01*
X-222541Y187040D01*
X-221958Y186957D01*
X-221374Y186540D01*
X-221124Y185957D01*
X-221041Y185374D01*
X-221124Y184790D01*
X-221374Y184207D01*
X-221874Y183874D01*
X-222541Y183707D01*
X-223124Y183790D01*
X-223708Y184040D01*
X-224041Y184374D01*
G01X-216941Y188707D02*
Y183707D01*
G01X-218108Y187040D02*
X-215774D01*
G01X-212758Y183707D02*
Y188707D01*
G01Y186290D02*
X-212341Y186707D01*
X-211924Y186957D01*
X-211258Y187040D01*
X-210758Y186957D01*
X-210174Y186624D01*
X-209924Y186124D01*
Y183707D01*
G01X-200141Y188707D02*
Y183707D01*
G01X-201308Y187040D02*
X-198974D01*
G01X-194541Y183707D02*
X-195041Y183790D01*
X-195541Y184124D01*
X-195874Y184707D01*
X-196041Y185374D01*
X-195874Y186040D01*
X-195541Y186624D01*
X-195041Y186957D01*
X-194541Y187040D01*
X-194041Y186957D01*
X-193541Y186624D01*
X-193208Y186040D01*
X-193124Y185374D01*
X-193208Y184707D01*
X-193541Y184124D01*
X-194041Y183790D01*
X-194541Y183707D01*
G01X-188941D02*
Y188707D01*
G01X-184591Y185957D02*
X-181924D01*
X-182174Y186540D01*
X-182591Y186874D01*
X-183174Y187040D01*
X-183758Y186957D01*
X-184258Y186707D01*
X-184591Y186124D01*
X-184758Y185624D01*
Y185124D01*
X-184591Y184624D01*
X-184174Y184124D01*
X-183674Y183790D01*
X-183091Y183707D01*
X-182508Y183874D01*
X-181924Y184374D01*
G01X-178908Y183707D02*
Y187040D01*
G01Y186374D02*
X-178491Y186707D01*
X-178074Y186957D01*
X-177491Y187040D01*
X-177074Y186957D01*
X-176574Y186707D01*
G01X-170641Y183707D02*
Y187040D01*
G01Y186457D02*
X-170974Y186790D01*
X-171474Y186957D01*
X-172058Y187040D01*
X-172641Y186874D01*
X-173141Y186540D01*
X-173474Y186040D01*
X-173641Y185374D01*
X-173474Y184707D01*
X-173141Y184207D01*
X-172641Y183874D01*
X-172058Y183707D01*
X-171474Y183790D01*
X-170974Y184040D01*
X-170641Y184374D01*
G01X-167958Y183707D02*
Y187040D01*
G01Y186207D02*
X-167624Y186624D01*
X-167124Y186957D01*
X-166458Y187040D01*
X-165874Y186957D01*
X-165374Y186624D01*
X-165124Y186040D01*
Y183707D01*
G01X-159608Y186624D02*
X-160191Y186957D01*
X-160691Y187040D01*
X-161358Y186874D01*
X-161858Y186540D01*
X-162191Y185957D01*
X-162274Y185374D01*
X-162191Y184790D01*
X-161858Y184290D01*
X-161358Y183874D01*
X-160691Y183707D01*
X-160108Y183874D01*
X-159608Y184207D01*
G01X-156591Y185957D02*
X-153924D01*
X-154174Y186540D01*
X-154591Y186874D01*
X-155174Y187040D01*
X-155758Y186957D01*
X-156258Y186707D01*
X-156591Y186124D01*
X-156758Y185624D01*
Y185124D01*
X-156591Y184624D01*
X-156174Y184124D01*
X-155674Y183790D01*
X-155091Y183707D01*
X-154508Y183874D01*
X-153924Y184374D01*
G01X-234491Y204707D02*
Y209707D01*
G01X-230991D02*
Y204707D01*
G01Y207207D02*
X-234491D01*
G01X-227141Y204707D02*
X-227641Y204790D01*
X-228141Y205124D01*
X-228474Y205707D01*
X-228641Y206374D01*
X-228474Y207040D01*
X-228141Y207624D01*
X-227641Y207957D01*
X-227141Y208040D01*
X-226641Y207957D01*
X-226141Y207624D01*
X-225808Y207040D01*
X-225724Y206374D01*
X-225808Y205707D01*
X-226141Y205124D01*
X-226641Y204790D01*
X-227141Y204707D01*
G01X-221541D02*
Y209707D01*
G01X-217191Y206957D02*
X-214524D01*
X-214774Y207540D01*
X-215191Y207874D01*
X-215774Y208040D01*
X-216358Y207957D01*
X-216858Y207707D01*
X-217191Y207124D01*
X-217358Y206624D01*
Y206124D01*
X-217191Y205624D01*
X-216774Y205124D01*
X-216274Y204790D01*
X-215691Y204707D01*
X-215108Y204874D01*
X-214524Y205374D01*
G01X-207241Y209707D02*
X-206074Y204707D01*
X-204741Y209707D01*
X-203408Y204707D01*
X-202241Y209707D01*
G01X-197641Y204707D02*
Y208040D01*
G01Y207457D02*
X-197974Y207790D01*
X-198474Y207957D01*
X-199058Y208040D01*
X-199641Y207874D01*
X-200141Y207540D01*
X-200474Y207040D01*
X-200641Y206374D01*
X-200474Y205707D01*
X-200141Y205207D01*
X-199641Y204874D01*
X-199058Y204707D01*
X-198474Y204790D01*
X-197974Y205040D01*
X-197641Y205374D01*
G01X-193541Y204707D02*
Y209707D01*
G01X-187941Y204707D02*
Y209707D01*
G01X-178408Y204707D02*
Y209707D01*
X-176324D01*
X-175658Y209457D01*
X-175241Y209124D01*
X-175074Y208457D01*
X-175241Y207790D01*
X-175741Y207374D01*
X-176324Y207124D01*
X-178408D01*
G01X-176324D02*
X-175074Y204707D01*
G01X-171141D02*
X-171641Y204790D01*
X-172141Y205124D01*
X-172474Y205707D01*
X-172641Y206374D01*
X-172474Y207040D01*
X-172141Y207624D01*
X-171641Y207957D01*
X-171141Y208040D01*
X-170641Y207957D01*
X-170141Y207624D01*
X-169808Y207040D01*
X-169724Y206374D01*
X-169808Y205707D01*
X-170141Y205124D01*
X-170641Y204790D01*
X-171141Y204707D01*
G01X-166958Y208040D02*
Y205707D01*
X-166624Y205124D01*
X-166124Y204790D01*
X-165541Y204707D01*
X-164958Y204790D01*
X-164458Y205124D01*
X-164124Y205707D01*
G01Y204707D02*
Y208040D01*
G01X-161108Y203457D02*
X-160524Y203124D01*
X-159858Y203040D01*
X-159274Y203124D01*
X-158774Y203540D01*
X-158441Y204124D01*
Y208040D01*
G01Y207374D02*
X-158774Y207707D01*
X-159274Y207957D01*
X-159858Y208040D01*
X-160524Y207874D01*
X-160941Y207540D01*
X-161274Y206957D01*
X-161441Y206374D01*
X-161358Y205874D01*
X-161024Y205290D01*
X-160524Y204874D01*
X-159858Y204707D01*
X-159358Y204790D01*
X-158774Y205124D01*
X-158441Y205457D01*
G01X-155758Y204707D02*
Y209707D01*
G01Y207290D02*
X-155341Y207707D01*
X-154924Y207957D01*
X-154258Y208040D01*
X-153758Y207957D01*
X-153174Y207624D01*
X-152924Y207124D01*
Y204707D01*
G01X-150158D02*
Y208040D01*
G01Y207207D02*
X-149824Y207624D01*
X-149324Y207957D01*
X-148658Y208040D01*
X-148074Y207957D01*
X-147574Y207624D01*
X-147324Y207040D01*
Y204707D01*
G01X-144391Y206957D02*
X-141724D01*
X-141974Y207540D01*
X-142391Y207874D01*
X-142974Y208040D01*
X-143558Y207957D01*
X-144058Y207707D01*
X-144391Y207124D01*
X-144558Y206624D01*
Y206124D01*
X-144391Y205624D01*
X-143974Y205124D01*
X-143474Y204790D01*
X-142891Y204707D01*
X-142308Y204874D01*
X-141724Y205374D01*
G01X-138791Y205290D02*
X-138374Y204957D01*
X-137791Y204707D01*
X-137291D01*
X-136791Y204874D01*
X-136458Y205124D01*
X-136291Y205457D01*
X-136374Y205957D01*
X-136708Y206207D01*
X-138208Y206707D01*
X-138541Y207290D01*
X-138374Y207707D01*
X-138041Y207957D01*
X-137541Y208040D01*
X-137041Y207957D01*
X-136541Y207707D01*
G01X-133191Y205290D02*
X-132774Y204957D01*
X-132191Y204707D01*
X-131691D01*
X-131191Y204874D01*
X-130858Y205124D01*
X-130691Y205457D01*
X-130774Y205957D01*
X-131108Y206207D01*
X-132608Y206707D01*
X-132941Y207290D01*
X-132774Y207707D01*
X-132441Y207957D01*
X-131941Y208040D01*
X-131441Y207957D01*
X-130941Y207707D01*
G01X-232741Y221207D02*
X-233408Y221290D01*
X-233991Y221624D01*
X-234491Y222124D01*
X-234824Y222707D01*
X-234991Y223374D01*
Y224040D01*
X-234824Y224707D01*
X-234491Y225290D01*
X-233991Y225790D01*
X-233408Y226124D01*
X-232741Y226207D01*
X-232074Y226124D01*
X-231491Y225790D01*
X-230991Y225290D01*
X-230658Y224707D01*
X-230491Y224040D01*
Y223374D01*
X-230658Y222707D01*
X-230991Y222124D01*
X-231491Y221624D01*
X-232074Y221290D01*
X-232741Y221207D01*
G01X-227141Y226207D02*
Y221207D01*
G01X-228308Y224540D02*
X-225974D01*
G01X-222958Y221207D02*
Y226207D01*
G01Y223790D02*
X-222541Y224207D01*
X-222124Y224457D01*
X-221458Y224540D01*
X-220958Y224457D01*
X-220374Y224124D01*
X-220124Y223624D01*
Y221207D01*
G01X-217191Y223457D02*
X-214524D01*
X-214774Y224040D01*
X-215191Y224374D01*
X-215774Y224540D01*
X-216358Y224457D01*
X-216858Y224207D01*
X-217191Y223624D01*
X-217358Y223124D01*
Y222624D01*
X-217191Y222124D01*
X-216774Y221624D01*
X-216274Y221290D01*
X-215691Y221207D01*
X-215108Y221374D01*
X-214524Y221874D01*
G01X-211508Y221207D02*
Y224540D01*
G01Y223874D02*
X-211091Y224207D01*
X-210674Y224457D01*
X-210091Y224540D01*
X-209674Y224457D01*
X-209174Y224207D01*
G01X-205991Y221790D02*
X-205574Y221457D01*
X-204991Y221207D01*
X-204491D01*
X-203991Y221374D01*
X-203658Y221624D01*
X-203491Y221957D01*
X-203574Y222457D01*
X-203908Y222707D01*
X-205408Y223207D01*
X-205741Y223790D01*
X-205574Y224207D01*
X-205241Y224457D01*
X-204741Y224540D01*
X-204241Y224457D01*
X-203741Y224207D01*
G01X-193958Y219540D02*
X-194791Y220374D01*
X-195208Y221207D01*
Y224540D01*
X-194791Y225374D01*
X-193958Y226207D01*
G01X-187941Y221207D02*
Y226207D01*
G01X-182341Y224540D02*
Y221207D01*
G01Y225874D02*
X-182508Y225957D01*
Y226124D01*
X-182341Y226207D01*
X-182174Y226124D01*
Y225957D01*
X-182341Y225874D01*
G01X-178158Y221207D02*
Y226207D01*
G01X-175491Y224540D02*
X-178158Y222624D01*
G01X-177074Y223374D02*
X-175324Y221207D01*
G01X-172391Y223457D02*
X-169724D01*
X-169974Y224040D01*
X-170391Y224374D01*
X-170974Y224540D01*
X-171558Y224457D01*
X-172058Y224207D01*
X-172391Y223624D01*
X-172558Y223124D01*
Y222624D01*
X-172391Y222124D01*
X-171974Y221624D01*
X-171474Y221290D01*
X-170891Y221207D01*
X-170308Y221374D01*
X-169724Y221874D01*
G01X-161191Y223457D02*
X-158524D01*
X-158774Y224040D01*
X-159191Y224374D01*
X-159774Y224540D01*
X-160358Y224457D01*
X-160858Y224207D01*
X-161191Y223624D01*
X-161358Y223124D01*
Y222624D01*
X-161191Y222124D01*
X-160774Y221624D01*
X-160274Y221290D01*
X-159691Y221207D01*
X-159108Y221374D01*
X-158524Y221874D01*
G01X-154341Y221207D02*
Y226207D01*
G01X-148741Y221207D02*
Y226207D01*
G01X-143141Y224540D02*
Y221207D01*
G01Y225874D02*
X-143308Y225957D01*
Y226124D01*
X-143141Y226207D01*
X-142974Y226124D01*
Y225957D01*
X-143141Y225874D01*
G01X-139041Y219540D02*
Y224540D01*
G01Y223790D02*
X-138624Y224207D01*
X-138208Y224457D01*
X-137541Y224540D01*
X-136958Y224457D01*
X-136374Y224040D01*
X-136124Y223457D01*
X-136041Y222874D01*
X-136124Y222290D01*
X-136374Y221707D01*
X-136874Y221374D01*
X-137541Y221207D01*
X-138124Y221290D01*
X-138708Y221540D01*
X-139041Y221874D01*
G01X-133191Y221790D02*
X-132774Y221457D01*
X-132191Y221207D01*
X-131691D01*
X-131191Y221374D01*
X-130858Y221624D01*
X-130691Y221957D01*
X-130774Y222457D01*
X-131108Y222707D01*
X-132608Y223207D01*
X-132941Y223790D01*
X-132774Y224207D01*
X-132441Y224457D01*
X-131941Y224540D01*
X-131441Y224457D01*
X-130941Y224207D01*
G01X-127591Y223457D02*
X-124924D01*
X-125174Y224040D01*
X-125591Y224374D01*
X-126174Y224540D01*
X-126758Y224457D01*
X-127258Y224207D01*
X-127591Y223624D01*
X-127758Y223124D01*
Y222624D01*
X-127591Y222124D01*
X-127174Y221624D01*
X-126674Y221290D01*
X-126091Y221207D01*
X-125508Y221374D01*
X-124924Y221874D01*
G01X-113641Y221207D02*
Y224540D01*
G01Y223957D02*
X-113974Y224290D01*
X-114474Y224457D01*
X-115058Y224540D01*
X-115641Y224374D01*
X-116141Y224040D01*
X-116474Y223540D01*
X-116641Y222874D01*
X-116474Y222207D01*
X-116141Y221707D01*
X-115641Y221374D01*
X-115058Y221207D01*
X-114474Y221290D01*
X-113974Y221540D01*
X-113641Y221874D01*
G01X-110958Y221207D02*
Y224540D01*
G01Y223707D02*
X-110624Y224124D01*
X-110124Y224457D01*
X-109458Y224540D01*
X-108874Y224457D01*
X-108374Y224124D01*
X-108124Y223540D01*
Y221207D01*
G01X-102441Y226207D02*
Y221207D01*
G01Y221957D02*
X-102774Y221540D01*
X-103274Y221290D01*
X-103858Y221207D01*
X-104524Y221374D01*
X-105024Y221790D01*
X-105358Y222290D01*
X-105441Y222874D01*
X-105358Y223457D01*
X-105024Y223957D01*
X-104524Y224374D01*
X-103858Y224540D01*
X-103274Y224457D01*
X-102858Y224290D01*
X-102441Y223957D01*
G01X-92741Y221207D02*
X-93241Y221290D01*
X-93741Y221624D01*
X-94074Y222207D01*
X-94241Y222874D01*
X-94074Y223540D01*
X-93741Y224124D01*
X-93241Y224457D01*
X-92741Y224540D01*
X-92241Y224457D01*
X-91741Y224124D01*
X-91408Y223540D01*
X-91324Y222874D01*
X-91408Y222207D01*
X-91741Y221624D01*
X-92241Y221290D01*
X-92741Y221207D01*
G01X-87141Y226207D02*
Y221207D01*
G01X-88308Y224540D02*
X-85974D01*
G01X-82958Y221207D02*
Y226207D01*
G01Y223790D02*
X-82541Y224207D01*
X-82124Y224457D01*
X-81458Y224540D01*
X-80958Y224457D01*
X-80374Y224124D01*
X-80124Y223624D01*
Y221207D01*
G01X-77191Y223457D02*
X-74524D01*
X-74774Y224040D01*
X-75191Y224374D01*
X-75774Y224540D01*
X-76358Y224457D01*
X-76858Y224207D01*
X-77191Y223624D01*
X-77358Y223124D01*
Y222624D01*
X-77191Y222124D01*
X-76774Y221624D01*
X-76274Y221290D01*
X-75691Y221207D01*
X-75108Y221374D01*
X-74524Y221874D01*
G01X-71508Y221207D02*
Y224540D01*
G01Y223874D02*
X-71091Y224207D01*
X-70674Y224457D01*
X-70091Y224540D01*
X-69674Y224457D01*
X-69174Y224207D01*
G01X-65991Y221790D02*
X-65574Y221457D01*
X-64991Y221207D01*
X-64491D01*
X-63991Y221374D01*
X-63658Y221624D01*
X-63491Y221957D01*
X-63574Y222457D01*
X-63908Y222707D01*
X-65408Y223207D01*
X-65741Y223790D01*
X-65574Y224207D01*
X-65241Y224457D01*
X-64741Y224540D01*
X-64241Y224457D01*
X-63741Y224207D01*
G01X-58724Y219540D02*
X-57891Y220374D01*
X-57474Y221207D01*
Y224540D01*
X-57891Y225374D01*
X-58724Y226207D01*
G01X-242741Y148207D02*
Y430207D01*
G01X-234408Y236207D02*
Y241207D01*
X-232408D01*
X-231741Y240957D01*
X-231241Y240374D01*
X-231074Y239707D01*
X-231241Y239040D01*
X-231658Y238540D01*
X-232408Y238290D01*
X-234408D01*
G01X-227141Y241207D02*
Y236207D01*
G01X-229058Y241207D02*
X-225224D01*
G01X-223291Y236207D02*
Y241207D01*
G01X-219791D02*
Y236207D01*
G01Y238707D02*
X-223291D01*
G01X-217441Y236040D02*
X-214441Y241207D01*
G01X-212258Y236207D02*
Y241207D01*
X-208424Y236207D01*
Y241207D01*
G01X-206408Y236207D02*
Y241207D01*
X-204408D01*
X-203741Y240957D01*
X-203241Y240374D01*
X-203074Y239707D01*
X-203241Y239040D01*
X-203658Y238540D01*
X-204408Y238290D01*
X-206408D01*
G01X-199141Y241207D02*
Y236207D01*
G01X-201058Y241207D02*
X-197224D01*
G01X-195291Y236207D02*
Y241207D01*
G01X-191791D02*
Y236207D01*
G01Y238707D02*
X-195291D01*
G01X-184008Y236207D02*
X-180674Y237874D01*
X-184008Y239540D01*
G01X-177824Y237124D02*
X-175658D01*
G01Y238624D02*
X-177824D01*
G01X-172974Y236957D02*
X-172474Y236540D01*
X-171891Y236290D01*
X-171141Y236207D01*
X-170391Y236374D01*
X-169808Y236707D01*
X-169391Y237290D01*
X-169308Y237957D01*
X-169474Y238624D01*
X-169891Y239040D01*
X-170474Y239374D01*
X-171058Y239457D01*
X-171641Y239374D01*
X-172391Y239040D01*
X-172141Y241207D01*
X-169891D01*
G01X-162441Y236207D02*
Y239540D01*
G01Y238624D02*
X-162191Y239040D01*
X-161774Y239374D01*
X-161191Y239540D01*
X-160608Y239374D01*
X-160191Y239040D01*
X-159941Y238624D01*
Y236207D01*
G01Y238624D02*
X-159691Y239040D01*
X-159274Y239374D01*
X-158691Y239540D01*
X-158108Y239374D01*
X-157691Y239040D01*
X-157441Y238540D01*
Y236207D01*
G01X-156841D02*
Y239540D01*
G01Y238624D02*
X-156591Y239040D01*
X-156174Y239374D01*
X-155591Y239540D01*
X-155008Y239374D01*
X-154591Y239040D01*
X-154341Y238624D01*
Y236207D01*
G01Y238624D02*
X-154091Y239040D01*
X-153674Y239374D01*
X-153091Y239540D01*
X-152508Y239374D01*
X-152091Y239040D01*
X-151841Y238540D01*
Y236207D01*
G01X-234658Y249707D02*
Y254707D01*
X-230824Y249707D01*
Y254707D01*
G01X-228808Y249707D02*
Y254707D01*
X-226808D01*
X-226141Y254457D01*
X-225641Y253874D01*
X-225474Y253207D01*
X-225641Y252540D01*
X-226058Y252040D01*
X-226808Y251790D01*
X-228808D01*
G01X-221541Y254707D02*
Y249707D01*
G01X-223458Y254707D02*
X-219624D01*
G01X-217691Y249707D02*
Y254707D01*
G01X-214191D02*
Y249707D01*
G01Y252207D02*
X-217691D01*
G01X-206491Y250374D02*
X-205824Y249957D01*
X-205074Y249707D01*
X-204408D01*
X-203741Y249957D01*
X-203241Y250374D01*
X-202991Y250957D01*
X-203158Y251540D01*
X-203574Y252040D01*
X-204324Y252374D01*
X-205324Y252540D01*
X-205908Y252874D01*
X-206158Y253457D01*
X-205991Y254040D01*
X-205574Y254457D01*
X-204991Y254707D01*
X-204408D01*
X-203824Y254540D01*
X-203324Y254124D01*
G01X-199141Y253040D02*
Y249707D01*
G01Y254374D02*
X-199308Y254457D01*
Y254624D01*
X-199141Y254707D01*
X-198974Y254624D01*
Y254457D01*
X-199141Y254374D01*
G01X-194791Y253040D02*
X-192291D01*
X-194791Y249707D01*
X-192291D01*
G01X-189191Y251957D02*
X-186524D01*
X-186774Y252540D01*
X-187191Y252874D01*
X-187774Y253040D01*
X-188358Y252957D01*
X-188858Y252707D01*
X-189191Y252124D01*
X-189358Y251624D01*
Y251124D01*
X-189191Y250624D01*
X-188774Y250124D01*
X-188274Y249790D01*
X-187691Y249707D01*
X-187108Y249874D01*
X-186524Y250374D01*
G01X-178574Y250707D02*
X-178074Y250124D01*
X-177408Y249790D01*
X-176658Y249707D01*
X-175991Y249790D01*
X-175324Y250207D01*
X-174908Y250707D01*
X-174824Y251207D01*
X-174991Y251790D01*
X-175574Y252207D01*
X-176158Y252374D01*
X-176908D01*
G01X-176158D02*
X-175658Y252624D01*
X-175241Y253040D01*
X-175074Y253540D01*
X-175241Y254040D01*
X-175658Y254457D01*
X-176408Y254707D01*
X-177158Y254624D01*
X-177908Y254290D01*
G01X-171141Y249540D02*
X-171308Y249624D01*
Y249790D01*
X-171141Y249874D01*
X-170974Y249790D01*
Y249624D01*
X-171141Y249540D01*
G01X-167374Y250457D02*
X-166874Y250040D01*
X-166291Y249790D01*
X-165541Y249707D01*
X-164791Y249874D01*
X-164208Y250207D01*
X-163791Y250790D01*
X-163708Y251457D01*
X-163874Y252124D01*
X-164291Y252540D01*
X-164874Y252874D01*
X-165458Y252957D01*
X-166041Y252874D01*
X-166791Y252540D01*
X-166541Y254707D01*
X-164291D01*
G01X-161774Y250457D02*
X-161274Y250040D01*
X-160691Y249790D01*
X-159941Y249707D01*
X-159191Y249874D01*
X-158608Y250207D01*
X-158191Y250790D01*
X-158108Y251457D01*
X-158274Y252124D01*
X-158691Y252540D01*
X-159274Y252874D01*
X-159858Y252957D01*
X-160441Y252874D01*
X-161191Y252540D01*
X-160941Y254707D01*
X-158691D01*
G01X-156841Y249707D02*
Y253040D01*
G01Y252124D02*
X-156591Y252540D01*
X-156174Y252874D01*
X-155591Y253040D01*
X-155008Y252874D01*
X-154591Y252540D01*
X-154341Y252124D01*
Y249707D01*
G01Y252124D02*
X-154091Y252540D01*
X-153674Y252874D01*
X-153091Y253040D01*
X-152508Y252874D01*
X-152091Y252540D01*
X-151841Y252040D01*
Y249707D01*
G01X-151241D02*
Y253040D01*
G01Y252124D02*
X-150991Y252540D01*
X-150574Y252874D01*
X-149991Y253040D01*
X-149408Y252874D01*
X-148991Y252540D01*
X-148741Y252124D01*
Y249707D01*
G01Y252124D02*
X-148491Y252540D01*
X-148074Y252874D01*
X-147491Y253040D01*
X-146908Y252874D01*
X-146491Y252540D01*
X-146241Y252040D01*
Y249707D01*
G01X-234658Y264707D02*
Y269707D01*
X-230824Y264707D01*
Y269707D01*
G01X-228808Y264707D02*
Y269707D01*
X-226808D01*
X-226141Y269457D01*
X-225641Y268874D01*
X-225474Y268207D01*
X-225641Y267540D01*
X-226058Y267040D01*
X-226808Y266790D01*
X-228808D01*
G01X-221541Y269707D02*
Y264707D01*
G01X-223458Y269707D02*
X-219624D01*
G01X-217691Y264707D02*
Y269707D01*
G01X-214191D02*
Y264707D01*
G01Y267207D02*
X-217691D01*
G01X-206491Y265374D02*
X-205824Y264957D01*
X-205074Y264707D01*
X-204408D01*
X-203741Y264957D01*
X-203241Y265374D01*
X-202991Y265957D01*
X-203158Y266540D01*
X-203574Y267040D01*
X-204324Y267374D01*
X-205324Y267540D01*
X-205908Y267874D01*
X-206158Y268457D01*
X-205991Y269040D01*
X-205574Y269457D01*
X-204991Y269707D01*
X-204408D01*
X-203824Y269540D01*
X-203324Y269124D01*
G01X-199141Y268040D02*
Y264707D01*
G01Y269374D02*
X-199308Y269457D01*
Y269624D01*
X-199141Y269707D01*
X-198974Y269624D01*
Y269457D01*
X-199141Y269374D01*
G01X-194791Y268040D02*
X-192291D01*
X-194791Y264707D01*
X-192291D01*
G01X-189191Y266957D02*
X-186524D01*
X-186774Y267540D01*
X-187191Y267874D01*
X-187774Y268040D01*
X-188358Y267957D01*
X-188858Y267707D01*
X-189191Y267124D01*
X-189358Y266624D01*
Y266124D01*
X-189191Y265624D01*
X-188774Y265124D01*
X-188274Y264790D01*
X-187691Y264707D01*
X-187108Y264874D01*
X-186524Y265374D01*
G01X-180674Y264707D02*
X-184008Y266374D01*
X-180674Y268040D01*
G01X-172974Y265457D02*
X-172474Y265040D01*
X-171891Y264790D01*
X-171141Y264707D01*
X-170391Y264874D01*
X-169808Y265207D01*
X-169391Y265790D01*
X-169308Y266457D01*
X-169474Y267124D01*
X-169891Y267540D01*
X-170474Y267874D01*
X-171058Y267957D01*
X-171641Y267874D01*
X-172391Y267540D01*
X-172141Y269707D01*
X-169891D01*
G01X-168041Y264707D02*
Y268040D01*
G01Y267124D02*
X-167791Y267540D01*
X-167374Y267874D01*
X-166791Y268040D01*
X-166208Y267874D01*
X-165791Y267540D01*
X-165541Y267124D01*
Y264707D01*
G01Y267124D02*
X-165291Y267540D01*
X-164874Y267874D01*
X-164291Y268040D01*
X-163708Y267874D01*
X-163291Y267540D01*
X-163041Y267040D01*
Y264707D01*
G01X-162441D02*
Y268040D01*
G01Y267124D02*
X-162191Y267540D01*
X-161774Y267874D01*
X-161191Y268040D01*
X-160608Y267874D01*
X-160191Y267540D01*
X-159941Y267124D01*
Y264707D01*
G01Y267124D02*
X-159691Y267540D01*
X-159274Y267874D01*
X-158691Y268040D01*
X-158108Y267874D01*
X-157691Y267540D01*
X-157441Y267040D01*
Y264707D01*
G01X-234574Y286207D02*
Y282624D01*
X-234241Y281874D01*
X-233574Y281374D01*
X-232741Y281207D01*
X-231908Y281374D01*
X-231241Y281874D01*
X-230908Y282624D01*
Y286207D01*
G01X-228558Y281207D02*
Y284540D01*
G01Y283707D02*
X-228224Y284124D01*
X-227724Y284457D01*
X-227058Y284540D01*
X-226474Y284457D01*
X-225974Y284124D01*
X-225724Y283540D01*
Y281207D01*
G01X-222624Y282874D02*
X-220458D01*
G01X-217441Y279540D02*
Y284540D01*
G01Y283790D02*
X-217024Y284207D01*
X-216608Y284457D01*
X-215941Y284540D01*
X-215358Y284457D01*
X-214774Y284040D01*
X-214524Y283457D01*
X-214441Y282874D01*
X-214524Y282290D01*
X-214774Y281707D01*
X-215274Y281374D01*
X-215941Y281207D01*
X-216524Y281290D01*
X-217108Y281540D01*
X-217441Y281874D01*
G01X-210341Y281207D02*
Y286207D01*
G01X-206158Y284540D02*
Y282207D01*
X-205824Y281624D01*
X-205324Y281290D01*
X-204741Y281207D01*
X-204158Y281290D01*
X-203658Y281624D01*
X-203324Y282207D01*
G01Y281207D02*
Y284540D01*
G01X-200308Y279957D02*
X-199724Y279624D01*
X-199058Y279540D01*
X-198474Y279624D01*
X-197974Y280040D01*
X-197641Y280624D01*
Y284540D01*
G01Y283874D02*
X-197974Y284207D01*
X-198474Y284457D01*
X-199058Y284540D01*
X-199724Y284374D01*
X-200141Y284040D01*
X-200474Y283457D01*
X-200641Y282874D01*
X-200558Y282374D01*
X-200224Y281790D01*
X-199724Y281374D01*
X-199058Y281207D01*
X-198558Y281290D01*
X-197974Y281624D01*
X-197641Y281957D01*
G01X-194708Y279957D02*
X-194124Y279624D01*
X-193458Y279540D01*
X-192874Y279624D01*
X-192374Y280040D01*
X-192041Y280624D01*
Y284540D01*
G01Y283874D02*
X-192374Y284207D01*
X-192874Y284457D01*
X-193458Y284540D01*
X-194124Y284374D01*
X-194541Y284040D01*
X-194874Y283457D01*
X-195041Y282874D01*
X-194958Y282374D01*
X-194624Y281790D01*
X-194124Y281374D01*
X-193458Y281207D01*
X-192958Y281290D01*
X-192374Y281624D01*
X-192041Y281957D01*
G01X-189191Y283457D02*
X-186524D01*
X-186774Y284040D01*
X-187191Y284374D01*
X-187774Y284540D01*
X-188358Y284457D01*
X-188858Y284207D01*
X-189191Y283624D01*
X-189358Y283124D01*
Y282624D01*
X-189191Y282124D01*
X-188774Y281624D01*
X-188274Y281290D01*
X-187691Y281207D01*
X-187108Y281374D01*
X-186524Y281874D01*
G01X-180841Y286207D02*
Y281207D01*
G01Y281957D02*
X-181174Y281540D01*
X-181674Y281290D01*
X-182258Y281207D01*
X-182924Y281374D01*
X-183424Y281790D01*
X-183758Y282290D01*
X-183841Y282874D01*
X-183758Y283457D01*
X-183424Y283957D01*
X-182924Y284374D01*
X-182258Y284540D01*
X-181674Y284457D01*
X-181258Y284290D01*
X-180841Y283957D01*
G01X-172808Y281207D02*
Y286207D01*
X-170808D01*
X-170141Y285957D01*
X-169641Y285374D01*
X-169474Y284707D01*
X-169641Y284040D01*
X-170058Y283540D01*
X-170808Y283290D01*
X-172808D01*
G01X-165541Y286207D02*
Y281207D01*
G01X-167458Y286207D02*
X-163624D01*
G01X-161691Y281207D02*
Y286207D01*
G01X-158191D02*
Y281207D01*
G01Y283707D02*
X-161691D01*
G01X-149158Y279540D02*
X-149991Y280374D01*
X-150408Y281207D01*
Y284540D01*
X-149991Y285374D01*
X-149158Y286207D01*
G01X-144891Y281207D02*
Y286207D01*
G01X-141391D02*
Y281207D01*
G01Y283707D02*
X-144891D01*
G01X-137541Y281207D02*
X-138041Y281290D01*
X-138541Y281624D01*
X-138874Y282207D01*
X-139041Y282874D01*
X-138874Y283540D01*
X-138541Y284124D01*
X-138041Y284457D01*
X-137541Y284540D01*
X-137041Y284457D01*
X-136541Y284124D01*
X-136208Y283540D01*
X-136124Y282874D01*
X-136208Y282207D01*
X-136541Y281624D01*
X-137041Y281290D01*
X-137541Y281207D01*
G01X-131941D02*
Y286207D01*
G01X-127591Y283457D02*
X-124924D01*
X-125174Y284040D01*
X-125591Y284374D01*
X-126174Y284540D01*
X-126758Y284457D01*
X-127258Y284207D01*
X-127591Y283624D01*
X-127758Y283124D01*
Y282624D01*
X-127591Y282124D01*
X-127174Y281624D01*
X-126674Y281290D01*
X-126091Y281207D01*
X-125508Y281374D01*
X-124924Y281874D01*
G01X-116891D02*
X-116224Y281457D01*
X-115474Y281207D01*
X-114808D01*
X-114141Y281457D01*
X-113641Y281874D01*
X-113391Y282457D01*
X-113558Y283040D01*
X-113974Y283540D01*
X-114724Y283874D01*
X-115724Y284040D01*
X-116308Y284374D01*
X-116558Y284957D01*
X-116391Y285540D01*
X-115974Y285957D01*
X-115391Y286207D01*
X-114808D01*
X-114224Y286040D01*
X-113724Y285624D01*
G01X-109541Y284540D02*
Y281207D01*
G01Y285874D02*
X-109708Y285957D01*
Y286124D01*
X-109541Y286207D01*
X-109374Y286124D01*
Y285957D01*
X-109541Y285874D01*
G01X-105191Y284540D02*
X-102691D01*
X-105191Y281207D01*
X-102691D01*
G01X-99591Y283457D02*
X-96924D01*
X-97174Y284040D01*
X-97591Y284374D01*
X-98174Y284540D01*
X-98758Y284457D01*
X-99258Y284207D01*
X-99591Y283624D01*
X-99758Y283124D01*
Y282624D01*
X-99591Y282124D01*
X-99174Y281624D01*
X-98674Y281290D01*
X-98091Y281207D01*
X-97508Y281374D01*
X-96924Y281874D01*
G01X-91074Y281207D02*
X-94408Y282874D01*
X-91074Y284540D01*
G01X-87141Y281207D02*
Y286207D01*
X-88141Y285207D01*
G01Y281207D02*
X-86141D01*
G01X-82958Y281790D02*
X-82374Y281374D01*
X-81708Y281207D01*
X-81041Y281374D01*
X-80458Y281874D01*
X-80041Y282624D01*
X-79874Y283374D01*
Y284290D01*
X-80041Y285040D01*
X-80458Y285707D01*
X-80958Y286040D01*
X-81541Y286207D01*
X-82208Y286040D01*
X-82708Y285707D01*
X-83041Y285207D01*
X-83208Y284540D01*
X-83041Y283957D01*
X-82624Y283374D01*
X-82124Y283040D01*
X-81541Y282957D01*
X-80874Y283124D01*
X-80374Y283540D01*
X-79874Y284290D01*
G01X-76108Y281207D02*
X-75941Y282290D01*
X-75691Y283207D01*
X-75358Y284040D01*
X-74941Y284957D01*
X-74274Y286207D01*
X-77608D01*
G01X-72841Y281207D02*
Y284540D01*
G01Y283624D02*
X-72591Y284040D01*
X-72174Y284374D01*
X-71591Y284540D01*
X-71008Y284374D01*
X-70591Y284040D01*
X-70341Y283624D01*
Y281207D01*
G01Y283624D02*
X-70091Y284040D01*
X-69674Y284374D01*
X-69091Y284540D01*
X-68508Y284374D01*
X-68091Y284040D01*
X-67841Y283540D01*
Y281207D01*
G01X-64741Y284540D02*
Y281207D01*
G01Y285874D02*
X-64908Y285957D01*
Y286124D01*
X-64741Y286207D01*
X-64574Y286124D01*
Y285957D01*
X-64741Y285874D01*
G01X-59141Y281207D02*
Y286207D01*
G01X-50024Y284540D02*
X-49024Y281207D01*
X-47941Y284540D01*
X-46858Y281207D01*
X-45858Y284540D01*
G01X-42341D02*
Y281207D01*
G01Y285874D02*
X-42508Y285957D01*
Y286124D01*
X-42341Y286207D01*
X-42174Y286124D01*
Y285957D01*
X-42341Y285874D01*
G01X-36741Y286207D02*
Y281207D01*
G01X-37908Y284540D02*
X-35574D01*
G01X-32558Y281207D02*
Y286207D01*
G01Y283790D02*
X-32141Y284207D01*
X-31724Y284457D01*
X-31058Y284540D01*
X-30558Y284457D01*
X-29974Y284124D01*
X-29724Y283624D01*
Y281207D01*
G01X-21691D02*
Y286207D01*
G01X-18191D02*
Y281207D01*
G01Y283707D02*
X-21691D01*
G01X-16424Y281207D02*
X-14341Y286207D01*
X-12258Y281207D01*
G01X-13008Y282957D02*
X-15674D01*
G01X-10491Y281874D02*
X-9824Y281457D01*
X-9074Y281207D01*
X-8408D01*
X-7741Y281457D01*
X-7241Y281874D01*
X-6991Y282457D01*
X-7158Y283040D01*
X-7574Y283540D01*
X-8324Y283874D01*
X-9324Y284040D01*
X-9908Y284374D01*
X-10158Y284957D01*
X-9991Y285540D01*
X-9574Y285957D01*
X-8991Y286207D01*
X-8408D01*
X-7824Y286040D01*
X-7324Y285624D01*
G01X-4808Y286207D02*
Y281207D01*
X-1474D01*
G01X6559Y279540D02*
Y284540D01*
G01Y283790D02*
X6976Y284207D01*
X7392Y284457D01*
X8059Y284540D01*
X8642Y284457D01*
X9226Y284040D01*
X9476Y283457D01*
X9559Y282874D01*
X9476Y282290D01*
X9226Y281707D01*
X8726Y281374D01*
X8059Y281207D01*
X7476Y281290D01*
X6892Y281540D01*
X6559Y281874D01*
G01X12492Y281207D02*
Y284540D01*
G01Y283874D02*
X12909Y284207D01*
X13326Y284457D01*
X13909Y284540D01*
X14326Y284457D01*
X14826Y284207D01*
G01X19259Y281207D02*
X18759Y281290D01*
X18259Y281624D01*
X17926Y282207D01*
X17759Y282874D01*
X17926Y283540D01*
X18259Y284124D01*
X18759Y284457D01*
X19259Y284540D01*
X19759Y284457D01*
X20259Y284124D01*
X20592Y283540D01*
X20676Y282874D01*
X20592Y282207D01*
X20259Y281624D01*
X19759Y281290D01*
X19259Y281207D01*
G01X26359Y286207D02*
Y281207D01*
G01Y281957D02*
X26026Y281540D01*
X25526Y281290D01*
X24942Y281207D01*
X24276Y281374D01*
X23776Y281790D01*
X23442Y282290D01*
X23359Y282874D01*
X23442Y283457D01*
X23776Y283957D01*
X24276Y284374D01*
X24942Y284540D01*
X25526Y284457D01*
X25942Y284290D01*
X26359Y283957D01*
G01X29042Y284540D02*
Y282207D01*
X29376Y281624D01*
X29876Y281290D01*
X30459Y281207D01*
X31042Y281290D01*
X31542Y281624D01*
X31876Y282207D01*
G01Y281207D02*
Y284540D01*
G01X37392Y284124D02*
X36809Y284457D01*
X36309Y284540D01*
X35642Y284374D01*
X35142Y284040D01*
X34809Y283457D01*
X34726Y282874D01*
X34809Y282290D01*
X35142Y281790D01*
X35642Y281374D01*
X36309Y281207D01*
X36892Y281374D01*
X37392Y281707D01*
G01X41659Y286207D02*
Y281207D01*
G01X40492Y284540D02*
X42826D01*
G01X46009Y281790D02*
X46426Y281457D01*
X47009Y281207D01*
X47509D01*
X48009Y281374D01*
X48342Y281624D01*
X48509Y281957D01*
X48426Y282457D01*
X48092Y282707D01*
X46592Y283207D01*
X46259Y283790D01*
X46426Y284207D01*
X46759Y284457D01*
X47259Y284540D01*
X47759Y284457D01*
X48259Y284207D01*
G01X53276Y279540D02*
X54109Y280374D01*
X54526Y281207D01*
Y284540D01*
X54109Y285374D01*
X53276Y286207D01*
G01X-234574Y301207D02*
Y297624D01*
X-234241Y296874D01*
X-233574Y296374D01*
X-232741Y296207D01*
X-231908Y296374D01*
X-231241Y296874D01*
X-230908Y297624D01*
Y301207D01*
G01X-228558Y296207D02*
Y299540D01*
G01Y298707D02*
X-228224Y299124D01*
X-227724Y299457D01*
X-227058Y299540D01*
X-226474Y299457D01*
X-225974Y299124D01*
X-225724Y298540D01*
Y296207D01*
G01X-222624Y297874D02*
X-220458D01*
G01X-217441Y294540D02*
Y299540D01*
G01Y298790D02*
X-217024Y299207D01*
X-216608Y299457D01*
X-215941Y299540D01*
X-215358Y299457D01*
X-214774Y299040D01*
X-214524Y298457D01*
X-214441Y297874D01*
X-214524Y297290D01*
X-214774Y296707D01*
X-215274Y296374D01*
X-215941Y296207D01*
X-216524Y296290D01*
X-217108Y296540D01*
X-217441Y296874D01*
G01X-210341Y296207D02*
Y301207D01*
G01X-206158Y299540D02*
Y297207D01*
X-205824Y296624D01*
X-205324Y296290D01*
X-204741Y296207D01*
X-204158Y296290D01*
X-203658Y296624D01*
X-203324Y297207D01*
G01Y296207D02*
Y299540D01*
G01X-200308Y294957D02*
X-199724Y294624D01*
X-199058Y294540D01*
X-198474Y294624D01*
X-197974Y295040D01*
X-197641Y295624D01*
Y299540D01*
G01Y298874D02*
X-197974Y299207D01*
X-198474Y299457D01*
X-199058Y299540D01*
X-199724Y299374D01*
X-200141Y299040D01*
X-200474Y298457D01*
X-200641Y297874D01*
X-200558Y297374D01*
X-200224Y296790D01*
X-199724Y296374D01*
X-199058Y296207D01*
X-198558Y296290D01*
X-197974Y296624D01*
X-197641Y296957D01*
G01X-194708Y294957D02*
X-194124Y294624D01*
X-193458Y294540D01*
X-192874Y294624D01*
X-192374Y295040D01*
X-192041Y295624D01*
Y299540D01*
G01Y298874D02*
X-192374Y299207D01*
X-192874Y299457D01*
X-193458Y299540D01*
X-194124Y299374D01*
X-194541Y299040D01*
X-194874Y298457D01*
X-195041Y297874D01*
X-194958Y297374D01*
X-194624Y296790D01*
X-194124Y296374D01*
X-193458Y296207D01*
X-192958Y296290D01*
X-192374Y296624D01*
X-192041Y296957D01*
G01X-189191Y298457D02*
X-186524D01*
X-186774Y299040D01*
X-187191Y299374D01*
X-187774Y299540D01*
X-188358Y299457D01*
X-188858Y299207D01*
X-189191Y298624D01*
X-189358Y298124D01*
Y297624D01*
X-189191Y297124D01*
X-188774Y296624D01*
X-188274Y296290D01*
X-187691Y296207D01*
X-187108Y296374D01*
X-186524Y296874D01*
G01X-180841Y301207D02*
Y296207D01*
G01Y296957D02*
X-181174Y296540D01*
X-181674Y296290D01*
X-182258Y296207D01*
X-182924Y296374D01*
X-183424Y296790D01*
X-183758Y297290D01*
X-183841Y297874D01*
X-183758Y298457D01*
X-183424Y298957D01*
X-182924Y299374D01*
X-182258Y299540D01*
X-181674Y299457D01*
X-181258Y299290D01*
X-180841Y298957D01*
G01X-172808Y296207D02*
Y301207D01*
X-170808D01*
X-170141Y300957D01*
X-169641Y300374D01*
X-169474Y299707D01*
X-169641Y299040D01*
X-170058Y298540D01*
X-170808Y298290D01*
X-172808D01*
G01X-165541Y301207D02*
Y296207D01*
G01X-167458Y301207D02*
X-163624D01*
G01X-161691Y296207D02*
Y301207D01*
G01X-158191D02*
Y296207D01*
G01Y298707D02*
X-161691D01*
G01X-149158Y294540D02*
X-149991Y295374D01*
X-150408Y296207D01*
Y299540D01*
X-149991Y300374D01*
X-149158Y301207D01*
G01X-144891Y296207D02*
Y301207D01*
G01X-141391D02*
Y296207D01*
G01Y298707D02*
X-144891D01*
G01X-137541Y296207D02*
X-138041Y296290D01*
X-138541Y296624D01*
X-138874Y297207D01*
X-139041Y297874D01*
X-138874Y298540D01*
X-138541Y299124D01*
X-138041Y299457D01*
X-137541Y299540D01*
X-137041Y299457D01*
X-136541Y299124D01*
X-136208Y298540D01*
X-136124Y297874D01*
X-136208Y297207D01*
X-136541Y296624D01*
X-137041Y296290D01*
X-137541Y296207D01*
G01X-131941D02*
Y301207D01*
G01X-127591Y298457D02*
X-124924D01*
X-125174Y299040D01*
X-125591Y299374D01*
X-126174Y299540D01*
X-126758Y299457D01*
X-127258Y299207D01*
X-127591Y298624D01*
X-127758Y298124D01*
Y297624D01*
X-127591Y297124D01*
X-127174Y296624D01*
X-126674Y296290D01*
X-126091Y296207D01*
X-125508Y296374D01*
X-124924Y296874D01*
G01X-116891D02*
X-116224Y296457D01*
X-115474Y296207D01*
X-114808D01*
X-114141Y296457D01*
X-113641Y296874D01*
X-113391Y297457D01*
X-113558Y298040D01*
X-113974Y298540D01*
X-114724Y298874D01*
X-115724Y299040D01*
X-116308Y299374D01*
X-116558Y299957D01*
X-116391Y300540D01*
X-115974Y300957D01*
X-115391Y301207D01*
X-114808D01*
X-114224Y301040D01*
X-113724Y300624D01*
G01X-109541Y299540D02*
Y296207D01*
G01Y300874D02*
X-109708Y300957D01*
Y301124D01*
X-109541Y301207D01*
X-109374Y301124D01*
Y300957D01*
X-109541Y300874D01*
G01X-105191Y299540D02*
X-102691D01*
X-105191Y296207D01*
X-102691D01*
G01X-99591Y298457D02*
X-96924D01*
X-97174Y299040D01*
X-97591Y299374D01*
X-98174Y299540D01*
X-98758Y299457D01*
X-99258Y299207D01*
X-99591Y298624D01*
X-99758Y298124D01*
Y297624D01*
X-99591Y297124D01*
X-99174Y296624D01*
X-98674Y296290D01*
X-98091Y296207D01*
X-97508Y296374D01*
X-96924Y296874D01*
G01X-91074Y296207D02*
X-94408Y297874D01*
X-91074Y299540D01*
G01X-87141Y296207D02*
Y301207D01*
X-88141Y300207D01*
G01Y296207D02*
X-86141D01*
G01X-82958Y296790D02*
X-82374Y296374D01*
X-81708Y296207D01*
X-81041Y296374D01*
X-80458Y296874D01*
X-80041Y297624D01*
X-79874Y298374D01*
Y299290D01*
X-80041Y300040D01*
X-80458Y300707D01*
X-80958Y301040D01*
X-81541Y301207D01*
X-82208Y301040D01*
X-82708Y300707D01*
X-83041Y300207D01*
X-83208Y299540D01*
X-83041Y298957D01*
X-82624Y298374D01*
X-82124Y298040D01*
X-81541Y297957D01*
X-80874Y298124D01*
X-80374Y298540D01*
X-79874Y299290D01*
G01X-76108Y296207D02*
X-75941Y297290D01*
X-75691Y298207D01*
X-75358Y299040D01*
X-74941Y299957D01*
X-74274Y301207D01*
X-77608D01*
G01X-72841Y296207D02*
Y299540D01*
G01Y298624D02*
X-72591Y299040D01*
X-72174Y299374D01*
X-71591Y299540D01*
X-71008Y299374D01*
X-70591Y299040D01*
X-70341Y298624D01*
Y296207D01*
G01Y298624D02*
X-70091Y299040D01*
X-69674Y299374D01*
X-69091Y299540D01*
X-68508Y299374D01*
X-68091Y299040D01*
X-67841Y298540D01*
Y296207D01*
G01X-64741Y299540D02*
Y296207D01*
G01Y300874D02*
X-64908Y300957D01*
Y301124D01*
X-64741Y301207D01*
X-64574Y301124D01*
Y300957D01*
X-64741Y300874D01*
G01X-59141Y296207D02*
Y301207D01*
G01X-50024Y299540D02*
X-49024Y296207D01*
X-47941Y299540D01*
X-46858Y296207D01*
X-45858Y299540D01*
G01X-42341D02*
Y296207D01*
G01Y300874D02*
X-42508Y300957D01*
Y301124D01*
X-42341Y301207D01*
X-42174Y301124D01*
Y300957D01*
X-42341Y300874D01*
G01X-36741Y301207D02*
Y296207D01*
G01X-37908Y299540D02*
X-35574D01*
G01X-32558Y296207D02*
Y301207D01*
G01Y298790D02*
X-32141Y299207D01*
X-31724Y299457D01*
X-31058Y299540D01*
X-30558Y299457D01*
X-29974Y299124D01*
X-29724Y298624D01*
Y296207D01*
G01X-21358D02*
Y299540D01*
G01Y298707D02*
X-21024Y299124D01*
X-20524Y299457D01*
X-19858Y299540D01*
X-19274Y299457D01*
X-18774Y299124D01*
X-18524Y298540D01*
Y296207D01*
G01X-14341D02*
X-14841Y296290D01*
X-15341Y296624D01*
X-15674Y297207D01*
X-15841Y297874D01*
X-15674Y298540D01*
X-15341Y299124D01*
X-14841Y299457D01*
X-14341Y299540D01*
X-13841Y299457D01*
X-13341Y299124D01*
X-13008Y298540D01*
X-12924Y297874D01*
X-13008Y297207D01*
X-13341Y296624D01*
X-13841Y296290D01*
X-14341Y296207D01*
G01X-10158D02*
Y299540D01*
G01Y298707D02*
X-9824Y299124D01*
X-9324Y299457D01*
X-8658Y299540D01*
X-8074Y299457D01*
X-7574Y299124D01*
X-7324Y298540D01*
Y296207D01*
G01X-4224Y297874D02*
X-2058D01*
G01X709Y296207D02*
Y301207D01*
G01X4209D02*
Y296207D01*
G01Y298707D02*
X709D01*
G01X5976Y296207D02*
X8059Y301207D01*
X10142Y296207D01*
G01X9392Y297957D02*
X6726D01*
G01X11909Y296874D02*
X12576Y296457D01*
X13326Y296207D01*
X13992D01*
X14659Y296457D01*
X15159Y296874D01*
X15409Y297457D01*
X15242Y298040D01*
X14826Y298540D01*
X14076Y298874D01*
X13076Y299040D01*
X12492Y299374D01*
X12242Y299957D01*
X12409Y300540D01*
X12826Y300957D01*
X13409Y301207D01*
X13992D01*
X14576Y301040D01*
X15076Y300624D01*
G01X17592Y301207D02*
Y296207D01*
X20926D01*
G01X28959Y294540D02*
Y299540D01*
G01Y298790D02*
X29376Y299207D01*
X29792Y299457D01*
X30459Y299540D01*
X31042Y299457D01*
X31626Y299040D01*
X31876Y298457D01*
X31959Y297874D01*
X31876Y297290D01*
X31626Y296707D01*
X31126Y296374D01*
X30459Y296207D01*
X29876Y296290D01*
X29292Y296540D01*
X28959Y296874D01*
G01X34892Y296207D02*
Y299540D01*
G01Y298874D02*
X35309Y299207D01*
X35726Y299457D01*
X36309Y299540D01*
X36726Y299457D01*
X37226Y299207D01*
G01X41659Y296207D02*
X41159Y296290D01*
X40659Y296624D01*
X40326Y297207D01*
X40159Y297874D01*
X40326Y298540D01*
X40659Y299124D01*
X41159Y299457D01*
X41659Y299540D01*
X42159Y299457D01*
X42659Y299124D01*
X42992Y298540D01*
X43076Y297874D01*
X42992Y297207D01*
X42659Y296624D01*
X42159Y296290D01*
X41659Y296207D01*
G01X48759Y301207D02*
Y296207D01*
G01Y296957D02*
X48426Y296540D01*
X47926Y296290D01*
X47342Y296207D01*
X46676Y296374D01*
X46176Y296790D01*
X45842Y297290D01*
X45759Y297874D01*
X45842Y298457D01*
X46176Y298957D01*
X46676Y299374D01*
X47342Y299540D01*
X47926Y299457D01*
X48342Y299290D01*
X48759Y298957D01*
G01X51442Y299540D02*
Y297207D01*
X51776Y296624D01*
X52276Y296290D01*
X52859Y296207D01*
X53442Y296290D01*
X53942Y296624D01*
X54276Y297207D01*
G01Y296207D02*
Y299540D01*
G01X59792Y299124D02*
X59209Y299457D01*
X58709Y299540D01*
X58042Y299374D01*
X57542Y299040D01*
X57209Y298457D01*
X57126Y297874D01*
X57209Y297290D01*
X57542Y296790D01*
X58042Y296374D01*
X58709Y296207D01*
X59292Y296374D01*
X59792Y296707D01*
G01X64059Y301207D02*
Y296207D01*
G01X62892Y299540D02*
X65226D01*
G01X68409Y296790D02*
X68826Y296457D01*
X69409Y296207D01*
X69909D01*
X70409Y296374D01*
X70742Y296624D01*
X70909Y296957D01*
X70826Y297457D01*
X70492Y297707D01*
X68992Y298207D01*
X68659Y298790D01*
X68826Y299207D01*
X69159Y299457D01*
X69659Y299540D01*
X70159Y299457D01*
X70659Y299207D01*
G01X75676Y294540D02*
X76509Y295374D01*
X76926Y296207D01*
Y299540D01*
X76509Y300374D01*
X75676Y301207D01*
G01X-242741Y230207D02*
X189259D01*
G01X-242741Y245207D02*
X189259D01*
G01X-242741Y260207D02*
X189259D01*
G01X-242741Y275207D02*
X189259D01*
G01X-242741Y290207D02*
X189259D01*
G01X-232241Y360207D02*
Y355207D01*
G01X-234158Y360207D02*
X-230324D01*
G01X-228058Y355207D02*
Y360207D01*
G01Y357790D02*
X-227641Y358207D01*
X-227224Y358457D01*
X-226558Y358540D01*
X-226058Y358457D01*
X-225474Y358124D01*
X-225224Y357624D01*
Y355207D01*
G01X-222291Y357457D02*
X-219624D01*
X-219874Y358040D01*
X-220291Y358374D01*
X-220874Y358540D01*
X-221458Y358457D01*
X-221958Y358207D01*
X-222291Y357624D01*
X-222458Y357124D01*
Y356624D01*
X-222291Y356124D01*
X-221874Y355624D01*
X-221374Y355290D01*
X-220791Y355207D01*
X-220208Y355374D01*
X-219624Y355874D01*
G01X-216608Y355207D02*
Y358540D01*
G01Y357874D02*
X-216191Y358207D01*
X-215774Y358457D01*
X-215191Y358540D01*
X-214774Y358457D01*
X-214274Y358207D01*
G01X-212341Y355207D02*
Y358540D01*
G01Y357624D02*
X-212091Y358040D01*
X-211674Y358374D01*
X-211091Y358540D01*
X-210508Y358374D01*
X-210091Y358040D01*
X-209841Y357624D01*
Y355207D01*
G01Y357624D02*
X-209591Y358040D01*
X-209174Y358374D01*
X-208591Y358540D01*
X-208008Y358374D01*
X-207591Y358040D01*
X-207341Y357540D01*
Y355207D01*
G01X-202741D02*
Y358540D01*
G01Y357957D02*
X-203074Y358290D01*
X-203574Y358457D01*
X-204158Y358540D01*
X-204741Y358374D01*
X-205241Y358040D01*
X-205574Y357540D01*
X-205741Y356874D01*
X-205574Y356207D01*
X-205241Y355707D01*
X-204741Y355374D01*
X-204158Y355207D01*
X-203574Y355290D01*
X-203074Y355540D01*
X-202741Y355874D01*
G01X-198641Y355207D02*
Y360207D01*
G01X-188941Y353540D02*
Y358540D01*
G01Y357790D02*
X-188524Y358207D01*
X-188108Y358457D01*
X-187441Y358540D01*
X-186858Y358457D01*
X-186274Y358040D01*
X-186024Y357457D01*
X-185941Y356874D01*
X-186024Y356290D01*
X-186274Y355707D01*
X-186774Y355374D01*
X-187441Y355207D01*
X-188024Y355290D01*
X-188608Y355540D01*
X-188941Y355874D01*
G01X-180341Y355207D02*
Y358540D01*
G01Y357957D02*
X-180674Y358290D01*
X-181174Y358457D01*
X-181758Y358540D01*
X-182341Y358374D01*
X-182841Y358040D01*
X-183174Y357540D01*
X-183341Y356874D01*
X-183174Y356207D01*
X-182841Y355707D01*
X-182341Y355374D01*
X-181758Y355207D01*
X-181174Y355290D01*
X-180674Y355540D01*
X-180341Y355874D01*
G01X-174741Y360207D02*
Y355207D01*
G01Y355957D02*
X-175074Y355540D01*
X-175574Y355290D01*
X-176158Y355207D01*
X-176824Y355374D01*
X-177324Y355790D01*
X-177658Y356290D01*
X-177741Y356874D01*
X-177658Y357457D01*
X-177324Y357957D01*
X-176824Y358374D01*
X-176158Y358540D01*
X-175574Y358457D01*
X-175158Y358290D01*
X-174741Y357957D01*
G01X-163708Y358124D02*
X-164291Y358457D01*
X-164791Y358540D01*
X-165458Y358374D01*
X-165958Y358040D01*
X-166291Y357457D01*
X-166374Y356874D01*
X-166291Y356290D01*
X-165958Y355790D01*
X-165458Y355374D01*
X-164791Y355207D01*
X-164208Y355374D01*
X-163708Y355707D01*
G01X-157941Y355207D02*
Y358540D01*
G01Y357957D02*
X-158274Y358290D01*
X-158774Y358457D01*
X-159358Y358540D01*
X-159941Y358374D01*
X-160441Y358040D01*
X-160774Y357540D01*
X-160941Y356874D01*
X-160774Y356207D01*
X-160441Y355707D01*
X-159941Y355374D01*
X-159358Y355207D01*
X-158774Y355290D01*
X-158274Y355540D01*
X-157941Y355874D01*
G01X-155258Y355207D02*
Y358540D01*
G01Y357707D02*
X-154924Y358124D01*
X-154424Y358457D01*
X-153758Y358540D01*
X-153174Y358457D01*
X-152674Y358124D01*
X-152424Y357540D01*
Y355207D01*
G01X-141308Y358124D02*
X-141891Y358457D01*
X-142391Y358540D01*
X-143058Y358374D01*
X-143558Y358040D01*
X-143891Y357457D01*
X-143974Y356874D01*
X-143891Y356290D01*
X-143558Y355790D01*
X-143058Y355374D01*
X-142391Y355207D01*
X-141808Y355374D01*
X-141308Y355707D01*
G01X-138458Y355207D02*
Y360207D01*
G01Y357790D02*
X-138041Y358207D01*
X-137624Y358457D01*
X-136958Y358540D01*
X-136458Y358457D01*
X-135874Y358124D01*
X-135624Y357624D01*
Y355207D01*
G01X-129941D02*
Y358540D01*
G01Y357957D02*
X-130274Y358290D01*
X-130774Y358457D01*
X-131358Y358540D01*
X-131941Y358374D01*
X-132441Y358040D01*
X-132774Y357540D01*
X-132941Y356874D01*
X-132774Y356207D01*
X-132441Y355707D01*
X-131941Y355374D01*
X-131358Y355207D01*
X-130774Y355290D01*
X-130274Y355540D01*
X-129941Y355874D01*
G01X-127258Y355207D02*
Y358540D01*
G01Y357707D02*
X-126924Y358124D01*
X-126424Y358457D01*
X-125758Y358540D01*
X-125174Y358457D01*
X-124674Y358124D01*
X-124424Y357540D01*
Y355207D01*
G01X-121408Y353957D02*
X-120824Y353624D01*
X-120158Y353540D01*
X-119574Y353624D01*
X-119074Y354040D01*
X-118741Y354624D01*
Y358540D01*
G01Y357874D02*
X-119074Y358207D01*
X-119574Y358457D01*
X-120158Y358540D01*
X-120824Y358374D01*
X-121241Y358040D01*
X-121574Y357457D01*
X-121741Y356874D01*
X-121658Y356374D01*
X-121324Y355790D01*
X-120824Y355374D01*
X-120158Y355207D01*
X-119658Y355290D01*
X-119074Y355624D01*
X-118741Y355957D01*
G01X-115891Y357457D02*
X-113224D01*
X-113474Y358040D01*
X-113891Y358374D01*
X-114474Y358540D01*
X-115058Y358457D01*
X-115558Y358207D01*
X-115891Y357624D01*
X-116058Y357124D01*
Y356624D01*
X-115891Y356124D01*
X-115474Y355624D01*
X-114974Y355290D01*
X-114391Y355207D01*
X-113808Y355374D01*
X-113224Y355874D01*
G01X-103441Y358540D02*
Y355207D01*
G01Y359874D02*
X-103608Y359957D01*
Y360124D01*
X-103441Y360207D01*
X-103274Y360124D01*
Y359957D01*
X-103441Y359874D01*
G01X-99258Y355207D02*
Y358540D01*
G01Y357707D02*
X-98924Y358124D01*
X-98424Y358457D01*
X-97758Y358540D01*
X-97174Y358457D01*
X-96674Y358124D01*
X-96424Y357540D01*
Y355207D01*
G01X-92241Y360207D02*
Y355207D01*
G01X-93408Y358540D02*
X-91074D01*
G01X-86641Y355207D02*
X-87141Y355290D01*
X-87641Y355624D01*
X-87974Y356207D01*
X-88141Y356874D01*
X-87974Y357540D01*
X-87641Y358124D01*
X-87141Y358457D01*
X-86641Y358540D01*
X-86141Y358457D01*
X-85641Y358124D01*
X-85308Y357540D01*
X-85224Y356874D01*
X-85308Y356207D01*
X-85641Y355624D01*
X-86141Y355290D01*
X-86641Y355207D01*
G01X-75941D02*
Y359457D01*
X-75774Y359874D01*
X-75441Y360124D01*
X-74941Y360207D01*
X-74441Y360040D01*
X-74191Y359624D01*
G01X-75191Y358207D02*
X-76858D01*
G01X-71258Y358540D02*
Y356207D01*
X-70924Y355624D01*
X-70424Y355290D01*
X-69841Y355207D01*
X-69258Y355290D01*
X-68758Y355624D01*
X-68424Y356207D01*
G01Y355207D02*
Y358540D01*
G01X-64241Y355207D02*
Y360207D01*
G01X-58641Y355207D02*
Y360207D01*
G01X-46108Y358124D02*
X-46691Y358457D01*
X-47191Y358540D01*
X-47858Y358374D01*
X-48358Y358040D01*
X-48691Y357457D01*
X-48774Y356874D01*
X-48691Y356290D01*
X-48358Y355790D01*
X-47858Y355374D01*
X-47191Y355207D01*
X-46608Y355374D01*
X-46108Y355707D01*
G01X-41841Y355207D02*
X-42341Y355290D01*
X-42841Y355624D01*
X-43174Y356207D01*
X-43341Y356874D01*
X-43174Y357540D01*
X-42841Y358124D01*
X-42341Y358457D01*
X-41841Y358540D01*
X-41341Y358457D01*
X-40841Y358124D01*
X-40508Y357540D01*
X-40424Y356874D01*
X-40508Y356207D01*
X-40841Y355624D01*
X-41341Y355290D01*
X-41841Y355207D01*
G01X-37658D02*
Y358540D01*
G01Y357707D02*
X-37324Y358124D01*
X-36824Y358457D01*
X-36158Y358540D01*
X-35574Y358457D01*
X-35074Y358124D01*
X-34824Y357540D01*
Y355207D01*
G01X-30641Y360207D02*
Y355207D01*
G01X-31808Y358540D02*
X-29474D01*
G01X-23541Y355207D02*
Y358540D01*
G01Y357957D02*
X-23874Y358290D01*
X-24374Y358457D01*
X-24958Y358540D01*
X-25541Y358374D01*
X-26041Y358040D01*
X-26374Y357540D01*
X-26541Y356874D01*
X-26374Y356207D01*
X-26041Y355707D01*
X-25541Y355374D01*
X-24958Y355207D01*
X-24374Y355290D01*
X-23874Y355540D01*
X-23541Y355874D01*
G01X-18108Y358124D02*
X-18691Y358457D01*
X-19191Y358540D01*
X-19858Y358374D01*
X-20358Y358040D01*
X-20691Y357457D01*
X-20774Y356874D01*
X-20691Y356290D01*
X-20358Y355790D01*
X-19858Y355374D01*
X-19191Y355207D01*
X-18608Y355374D01*
X-18108Y355707D01*
G01X-13841Y360207D02*
Y355207D01*
G01X-15008Y358540D02*
X-12674D01*
G01X-234824Y339707D02*
X-232741Y344707D01*
X-230658Y339707D01*
G01X-231408Y341457D02*
X-234074D01*
G01X-228558Y339707D02*
Y343040D01*
G01Y342207D02*
X-228224Y342624D01*
X-227724Y342957D01*
X-227058Y343040D01*
X-226474Y342957D01*
X-225974Y342624D01*
X-225724Y342040D01*
Y339707D01*
G01X-223291Y338207D02*
X-222791Y338040D01*
X-222124Y338207D01*
X-221708Y338540D01*
X-221374Y338957D01*
X-220874Y340290D01*
X-219791Y343040D01*
G01X-222458D02*
X-220874Y340290D01*
G01X-211758Y339707D02*
Y344707D01*
G01Y342290D02*
X-211341Y342707D01*
X-210924Y342957D01*
X-210258Y343040D01*
X-209758Y342957D01*
X-209174Y342624D01*
X-208924Y342124D01*
Y339707D01*
G01X-204741D02*
X-205241Y339790D01*
X-205741Y340124D01*
X-206074Y340707D01*
X-206241Y341374D01*
X-206074Y342040D01*
X-205741Y342624D01*
X-205241Y342957D01*
X-204741Y343040D01*
X-204241Y342957D01*
X-203741Y342624D01*
X-203408Y342040D01*
X-203324Y341374D01*
X-203408Y340707D01*
X-203741Y340124D01*
X-204241Y339790D01*
X-204741Y339707D01*
G01X-199141D02*
Y344707D01*
G01X-194791Y341957D02*
X-192124D01*
X-192374Y342540D01*
X-192791Y342874D01*
X-193374Y343040D01*
X-193958Y342957D01*
X-194458Y342707D01*
X-194791Y342124D01*
X-194958Y341624D01*
Y341124D01*
X-194791Y340624D01*
X-194374Y340124D01*
X-193874Y339790D01*
X-193291Y339707D01*
X-192708Y339874D01*
X-192124Y340374D01*
G01X-182341Y344707D02*
Y339707D01*
G01X-183508Y343040D02*
X-181174D01*
G01X-176741Y339707D02*
X-177241Y339790D01*
X-177741Y340124D01*
X-178074Y340707D01*
X-178241Y341374D01*
X-178074Y342040D01*
X-177741Y342624D01*
X-177241Y342957D01*
X-176741Y343040D01*
X-176241Y342957D01*
X-175741Y342624D01*
X-175408Y342040D01*
X-175324Y341374D01*
X-175408Y340707D01*
X-175741Y340124D01*
X-176241Y339790D01*
X-176741Y339707D01*
G01X-166958D02*
Y344707D01*
G01Y342290D02*
X-166541Y342707D01*
X-166124Y342957D01*
X-165458Y343040D01*
X-164958Y342957D01*
X-164374Y342624D01*
X-164124Y342124D01*
Y339707D01*
G01X-159941D02*
X-160441Y339790D01*
X-160941Y340124D01*
X-161274Y340707D01*
X-161441Y341374D01*
X-161274Y342040D01*
X-160941Y342624D01*
X-160441Y342957D01*
X-159941Y343040D01*
X-159441Y342957D01*
X-158941Y342624D01*
X-158608Y342040D01*
X-158524Y341374D01*
X-158608Y340707D01*
X-158941Y340124D01*
X-159441Y339790D01*
X-159941Y339707D01*
G01X-154341D02*
Y344707D01*
G01X-149991Y341957D02*
X-147324D01*
X-147574Y342540D01*
X-147991Y342874D01*
X-148574Y343040D01*
X-149158Y342957D01*
X-149658Y342707D01*
X-149991Y342124D01*
X-150158Y341624D01*
Y341124D01*
X-149991Y340624D01*
X-149574Y340124D01*
X-149074Y339790D01*
X-148491Y339707D01*
X-147908Y339874D01*
X-147324Y340374D01*
G01X-234324Y370207D02*
X-232241Y375207D01*
X-230158Y370207D01*
G01X-230908Y371957D02*
X-233574D01*
G01X-228058Y370207D02*
Y373540D01*
G01Y372707D02*
X-227724Y373124D01*
X-227224Y373457D01*
X-226558Y373540D01*
X-225974Y373457D01*
X-225474Y373124D01*
X-225224Y372540D01*
Y370207D01*
G01X-221041Y375207D02*
Y370207D01*
G01X-222208Y373540D02*
X-219874D01*
G01X-215441D02*
Y370207D01*
G01Y374874D02*
X-215608Y374957D01*
Y375124D01*
X-215441Y375207D01*
X-215274Y375124D01*
Y374957D01*
X-215441Y374874D01*
G01X-210924Y371874D02*
X-208758D01*
G01X-205741Y368540D02*
Y373540D01*
G01Y372790D02*
X-205324Y373207D01*
X-204908Y373457D01*
X-204241Y373540D01*
X-203658Y373457D01*
X-203074Y373040D01*
X-202824Y372457D01*
X-202741Y371874D01*
X-202824Y371290D01*
X-203074Y370707D01*
X-203574Y370374D01*
X-204241Y370207D01*
X-204824Y370290D01*
X-205408Y370540D01*
X-205741Y370874D01*
G01X-197141Y370207D02*
Y373540D01*
G01Y372957D02*
X-197474Y373290D01*
X-197974Y373457D01*
X-198558Y373540D01*
X-199141Y373374D01*
X-199641Y373040D01*
X-199974Y372540D01*
X-200141Y371874D01*
X-199974Y371207D01*
X-199641Y370707D01*
X-199141Y370374D01*
X-198558Y370207D01*
X-197974Y370290D01*
X-197474Y370540D01*
X-197141Y370874D01*
G01X-191541Y375207D02*
Y370207D01*
G01Y370957D02*
X-191874Y370540D01*
X-192374Y370290D01*
X-192958Y370207D01*
X-193624Y370374D01*
X-194124Y370790D01*
X-194458Y371290D01*
X-194541Y371874D01*
X-194458Y372457D01*
X-194124Y372957D01*
X-193624Y373374D01*
X-192958Y373540D01*
X-192374Y373457D01*
X-191958Y373290D01*
X-191541Y372957D01*
G01X-183091Y370790D02*
X-182674Y370457D01*
X-182091Y370207D01*
X-181591D01*
X-181091Y370374D01*
X-180758Y370624D01*
X-180591Y370957D01*
X-180674Y371457D01*
X-181008Y371707D01*
X-182508Y372207D01*
X-182841Y372790D01*
X-182674Y373207D01*
X-182341Y373457D01*
X-181841Y373540D01*
X-181341Y373457D01*
X-180841Y373207D01*
G01X-176241Y373540D02*
Y370207D01*
G01Y374874D02*
X-176408Y374957D01*
Y375124D01*
X-176241Y375207D01*
X-176074Y375124D01*
Y374957D01*
X-176241Y374874D01*
G01X-171891Y373540D02*
X-169391D01*
X-171891Y370207D01*
X-169391D01*
G01X-166291Y372457D02*
X-163624D01*
X-163874Y373040D01*
X-164291Y373374D01*
X-164874Y373540D01*
X-165458Y373457D01*
X-165958Y373207D01*
X-166291Y372624D01*
X-166458Y372124D01*
Y371624D01*
X-166291Y371124D01*
X-165874Y370624D01*
X-165374Y370290D01*
X-164791Y370207D01*
X-164208Y370374D01*
X-163624Y370874D01*
G01X-234408Y326207D02*
Y331207D01*
X-232408D01*
X-231741Y330957D01*
X-231241Y330374D01*
X-231074Y329707D01*
X-231241Y329040D01*
X-231658Y328540D01*
X-232408Y328290D01*
X-234408D01*
G01X-227141Y326207D02*
Y331207D01*
G01X-222958Y329540D02*
Y327207D01*
X-222624Y326624D01*
X-222124Y326290D01*
X-221541Y326207D01*
X-220958Y326290D01*
X-220458Y326624D01*
X-220124Y327207D01*
G01Y326207D02*
Y329540D01*
G01X-217108Y324957D02*
X-216524Y324624D01*
X-215858Y324540D01*
X-215274Y324624D01*
X-214774Y325040D01*
X-214441Y325624D01*
Y329540D01*
G01Y328874D02*
X-214774Y329207D01*
X-215274Y329457D01*
X-215858Y329540D01*
X-216524Y329374D01*
X-216941Y329040D01*
X-217274Y328457D01*
X-217441Y327874D01*
X-217358Y327374D01*
X-217024Y326790D01*
X-216524Y326374D01*
X-215858Y326207D01*
X-215358Y326290D01*
X-214774Y326624D01*
X-214441Y326957D01*
G01X-211508Y324957D02*
X-210924Y324624D01*
X-210258Y324540D01*
X-209674Y324624D01*
X-209174Y325040D01*
X-208841Y325624D01*
Y329540D01*
G01Y328874D02*
X-209174Y329207D01*
X-209674Y329457D01*
X-210258Y329540D01*
X-210924Y329374D01*
X-211341Y329040D01*
X-211674Y328457D01*
X-211841Y327874D01*
X-211758Y327374D01*
X-211424Y326790D01*
X-210924Y326374D01*
X-210258Y326207D01*
X-209758Y326290D01*
X-209174Y326624D01*
X-208841Y326957D01*
G01X-205991Y328457D02*
X-203324D01*
X-203574Y329040D01*
X-203991Y329374D01*
X-204574Y329540D01*
X-205158Y329457D01*
X-205658Y329207D01*
X-205991Y328624D01*
X-206158Y328124D01*
Y327624D01*
X-205991Y327124D01*
X-205574Y326624D01*
X-205074Y326290D01*
X-204491Y326207D01*
X-203908Y326374D01*
X-203324Y326874D01*
G01X-197641Y331207D02*
Y326207D01*
G01Y326957D02*
X-197974Y326540D01*
X-198474Y326290D01*
X-199058Y326207D01*
X-199724Y326374D01*
X-200224Y326790D01*
X-200558Y327290D01*
X-200641Y327874D01*
X-200558Y328457D01*
X-200224Y328957D01*
X-199724Y329374D01*
X-199058Y329540D01*
X-198474Y329457D01*
X-198058Y329290D01*
X-197641Y328957D01*
G01X-190024Y331207D02*
X-187941Y326207D01*
X-185858Y331207D01*
G01X-182341Y329540D02*
Y326207D01*
G01Y330874D02*
X-182508Y330957D01*
Y331124D01*
X-182341Y331207D01*
X-182174Y331124D01*
Y330957D01*
X-182341Y330874D01*
G01X-175241Y326207D02*
Y329540D01*
G01Y328957D02*
X-175574Y329290D01*
X-176074Y329457D01*
X-176658Y329540D01*
X-177241Y329374D01*
X-177741Y329040D01*
X-178074Y328540D01*
X-178241Y327874D01*
X-178074Y327207D01*
X-177741Y326707D01*
X-177241Y326374D01*
X-176658Y326207D01*
X-176074Y326290D01*
X-175574Y326540D01*
X-175241Y326874D01*
G01X-171558Y324540D02*
X-172391Y325374D01*
X-172808Y326207D01*
Y329540D01*
X-172391Y330374D01*
X-171558Y331207D01*
G01X-166958Y326207D02*
Y331207D01*
G01Y328790D02*
X-166541Y329207D01*
X-166124Y329457D01*
X-165458Y329540D01*
X-164958Y329457D01*
X-164374Y329124D01*
X-164124Y328624D01*
Y326207D01*
G01X-159941D02*
X-160441Y326290D01*
X-160941Y326624D01*
X-161274Y327207D01*
X-161441Y327874D01*
X-161274Y328540D01*
X-160941Y329124D01*
X-160441Y329457D01*
X-159941Y329540D01*
X-159441Y329457D01*
X-158941Y329124D01*
X-158608Y328540D01*
X-158524Y327874D01*
X-158608Y327207D01*
X-158941Y326624D01*
X-159441Y326290D01*
X-159941Y326207D01*
G01X-154341D02*
Y331207D01*
G01X-149991Y328457D02*
X-147324D01*
X-147574Y329040D01*
X-147991Y329374D01*
X-148574Y329540D01*
X-149158Y329457D01*
X-149658Y329207D01*
X-149991Y328624D01*
X-150158Y328124D01*
Y327624D01*
X-149991Y327124D01*
X-149574Y326624D01*
X-149074Y326290D01*
X-148491Y326207D01*
X-147908Y326374D01*
X-147324Y326874D01*
G01X-138791Y326790D02*
X-138374Y326457D01*
X-137791Y326207D01*
X-137291D01*
X-136791Y326374D01*
X-136458Y326624D01*
X-136291Y326957D01*
X-136374Y327457D01*
X-136708Y327707D01*
X-138208Y328207D01*
X-138541Y328790D01*
X-138374Y329207D01*
X-138041Y329457D01*
X-137541Y329540D01*
X-137041Y329457D01*
X-136541Y329207D01*
G01X-131941Y329540D02*
Y326207D01*
G01Y330874D02*
X-132108Y330957D01*
Y331124D01*
X-131941Y331207D01*
X-131774Y331124D01*
Y330957D01*
X-131941Y330874D01*
G01X-127591Y329540D02*
X-125091D01*
X-127591Y326207D01*
X-125091D01*
G01X-121991Y328457D02*
X-119324D01*
X-119574Y329040D01*
X-119991Y329374D01*
X-120574Y329540D01*
X-121158Y329457D01*
X-121658Y329207D01*
X-121991Y328624D01*
X-122158Y328124D01*
Y327624D01*
X-121991Y327124D01*
X-121574Y326624D01*
X-121074Y326290D01*
X-120491Y326207D01*
X-119908Y326374D01*
X-119324Y326874D01*
G01X-113474Y326207D02*
X-116808Y327874D01*
X-113474Y329540D01*
G01X-109541Y326207D02*
Y331207D01*
X-110541Y330207D01*
G01Y326207D02*
X-108541D01*
G01X-105524Y328290D02*
X-104941Y328874D01*
X-104441Y329207D01*
X-103774Y329374D01*
X-103191Y329207D01*
X-102774Y328874D01*
X-102441Y328374D01*
X-102358Y327790D01*
X-102441Y327290D01*
X-102774Y326790D01*
X-103274Y326374D01*
X-103858Y326207D01*
X-104524Y326374D01*
X-105108Y326874D01*
X-105441Y327624D01*
X-105524Y328457D01*
X-105358Y329540D01*
X-105108Y330124D01*
X-104691Y330707D01*
X-104108Y331124D01*
X-103524Y331207D01*
X-102941Y331040D01*
X-102524Y330624D01*
G01X-95241Y326207D02*
Y329540D01*
G01Y328624D02*
X-94991Y329040D01*
X-94574Y329374D01*
X-93991Y329540D01*
X-93408Y329374D01*
X-92991Y329040D01*
X-92741Y328624D01*
Y326207D01*
G01Y328624D02*
X-92491Y329040D01*
X-92074Y329374D01*
X-91491Y329540D01*
X-90908Y329374D01*
X-90491Y329040D01*
X-90241Y328540D01*
Y326207D01*
G01X-87141Y329540D02*
Y326207D01*
G01Y330874D02*
X-87308Y330957D01*
Y331124D01*
X-87141Y331207D01*
X-86974Y331124D01*
Y330957D01*
X-87141Y330874D01*
G01X-81541Y326207D02*
Y331207D01*
G01X-75524Y324540D02*
X-74691Y325374D01*
X-74274Y326207D01*
Y329540D01*
X-74691Y330374D01*
X-75524Y331207D01*
G01X-234408Y311207D02*
Y316207D01*
X-232408D01*
X-231741Y315957D01*
X-231241Y315374D01*
X-231074Y314707D01*
X-231241Y314040D01*
X-231658Y313540D01*
X-232408Y313290D01*
X-234408D01*
G01X-227141Y311207D02*
Y316207D01*
G01X-222958Y314540D02*
Y312207D01*
X-222624Y311624D01*
X-222124Y311290D01*
X-221541Y311207D01*
X-220958Y311290D01*
X-220458Y311624D01*
X-220124Y312207D01*
G01Y311207D02*
Y314540D01*
G01X-217108Y309957D02*
X-216524Y309624D01*
X-215858Y309540D01*
X-215274Y309624D01*
X-214774Y310040D01*
X-214441Y310624D01*
Y314540D01*
G01Y313874D02*
X-214774Y314207D01*
X-215274Y314457D01*
X-215858Y314540D01*
X-216524Y314374D01*
X-216941Y314040D01*
X-217274Y313457D01*
X-217441Y312874D01*
X-217358Y312374D01*
X-217024Y311790D01*
X-216524Y311374D01*
X-215858Y311207D01*
X-215358Y311290D01*
X-214774Y311624D01*
X-214441Y311957D01*
G01X-211508Y309957D02*
X-210924Y309624D01*
X-210258Y309540D01*
X-209674Y309624D01*
X-209174Y310040D01*
X-208841Y310624D01*
Y314540D01*
G01Y313874D02*
X-209174Y314207D01*
X-209674Y314457D01*
X-210258Y314540D01*
X-210924Y314374D01*
X-211341Y314040D01*
X-211674Y313457D01*
X-211841Y312874D01*
X-211758Y312374D01*
X-211424Y311790D01*
X-210924Y311374D01*
X-210258Y311207D01*
X-209758Y311290D01*
X-209174Y311624D01*
X-208841Y311957D01*
G01X-205991Y313457D02*
X-203324D01*
X-203574Y314040D01*
X-203991Y314374D01*
X-204574Y314540D01*
X-205158Y314457D01*
X-205658Y314207D01*
X-205991Y313624D01*
X-206158Y313124D01*
Y312624D01*
X-205991Y312124D01*
X-205574Y311624D01*
X-205074Y311290D01*
X-204491Y311207D01*
X-203908Y311374D01*
X-203324Y311874D01*
G01X-197641Y316207D02*
Y311207D01*
G01Y311957D02*
X-197974Y311540D01*
X-198474Y311290D01*
X-199058Y311207D01*
X-199724Y311374D01*
X-200224Y311790D01*
X-200558Y312290D01*
X-200641Y312874D01*
X-200558Y313457D01*
X-200224Y313957D01*
X-199724Y314374D01*
X-199058Y314540D01*
X-198474Y314457D01*
X-198058Y314290D01*
X-197641Y313957D01*
G01X-189608Y311207D02*
Y316207D01*
X-187608D01*
X-186941Y315957D01*
X-186441Y315374D01*
X-186274Y314707D01*
X-186441Y314040D01*
X-186858Y313540D01*
X-187608Y313290D01*
X-189608D01*
G01X-182341Y316207D02*
Y311207D01*
G01X-184258Y316207D02*
X-180424D01*
G01X-178491Y311207D02*
Y316207D01*
G01X-174991D02*
Y311207D01*
G01Y313707D02*
X-178491D01*
G01X-171558Y309540D02*
X-172391Y310374D01*
X-172808Y311207D01*
Y314540D01*
X-172391Y315374D01*
X-171558Y316207D01*
G01X-166958Y311207D02*
Y316207D01*
G01Y313790D02*
X-166541Y314207D01*
X-166124Y314457D01*
X-165458Y314540D01*
X-164958Y314457D01*
X-164374Y314124D01*
X-164124Y313624D01*
Y311207D01*
G01X-159941D02*
X-160441Y311290D01*
X-160941Y311624D01*
X-161274Y312207D01*
X-161441Y312874D01*
X-161274Y313540D01*
X-160941Y314124D01*
X-160441Y314457D01*
X-159941Y314540D01*
X-159441Y314457D01*
X-158941Y314124D01*
X-158608Y313540D01*
X-158524Y312874D01*
X-158608Y312207D01*
X-158941Y311624D01*
X-159441Y311290D01*
X-159941Y311207D01*
G01X-154341D02*
Y316207D01*
G01X-149991Y313457D02*
X-147324D01*
X-147574Y314040D01*
X-147991Y314374D01*
X-148574Y314540D01*
X-149158Y314457D01*
X-149658Y314207D01*
X-149991Y313624D01*
X-150158Y313124D01*
Y312624D01*
X-149991Y312124D01*
X-149574Y311624D01*
X-149074Y311290D01*
X-148491Y311207D01*
X-147908Y311374D01*
X-147324Y311874D01*
G01X-138791Y311790D02*
X-138374Y311457D01*
X-137791Y311207D01*
X-137291D01*
X-136791Y311374D01*
X-136458Y311624D01*
X-136291Y311957D01*
X-136374Y312457D01*
X-136708Y312707D01*
X-138208Y313207D01*
X-138541Y313790D01*
X-138374Y314207D01*
X-138041Y314457D01*
X-137541Y314540D01*
X-137041Y314457D01*
X-136541Y314207D01*
G01X-131941Y314540D02*
Y311207D01*
G01Y315874D02*
X-132108Y315957D01*
Y316124D01*
X-131941Y316207D01*
X-131774Y316124D01*
Y315957D01*
X-131941Y315874D01*
G01X-127591Y314540D02*
X-125091D01*
X-127591Y311207D01*
X-125091D01*
G01X-121991Y313457D02*
X-119324D01*
X-119574Y314040D01*
X-119991Y314374D01*
X-120574Y314540D01*
X-121158Y314457D01*
X-121658Y314207D01*
X-121991Y313624D01*
X-122158Y313124D01*
Y312624D01*
X-121991Y312124D01*
X-121574Y311624D01*
X-121074Y311290D01*
X-120491Y311207D01*
X-119908Y311374D01*
X-119324Y311874D01*
G01X-116808Y311207D02*
X-113474Y312874D01*
X-116808Y314540D01*
G01X-110624Y312124D02*
X-108458D01*
G01Y313624D02*
X-110624D01*
G01X-103941Y311207D02*
Y316207D01*
X-104941Y315207D01*
G01Y311207D02*
X-102941D01*
G01X-99924Y313290D02*
X-99341Y313874D01*
X-98841Y314207D01*
X-98174Y314374D01*
X-97591Y314207D01*
X-97174Y313874D01*
X-96841Y313374D01*
X-96758Y312790D01*
X-96841Y312290D01*
X-97174Y311790D01*
X-97674Y311374D01*
X-98258Y311207D01*
X-98924Y311374D01*
X-99508Y311874D01*
X-99841Y312624D01*
X-99924Y313457D01*
X-99758Y314540D01*
X-99508Y315124D01*
X-99091Y315707D01*
X-98508Y316124D01*
X-97924Y316207D01*
X-97341Y316040D01*
X-96924Y315624D01*
G01X-89641Y311207D02*
Y314540D01*
G01Y313624D02*
X-89391Y314040D01*
X-88974Y314374D01*
X-88391Y314540D01*
X-87808Y314374D01*
X-87391Y314040D01*
X-87141Y313624D01*
Y311207D01*
G01Y313624D02*
X-86891Y314040D01*
X-86474Y314374D01*
X-85891Y314540D01*
X-85308Y314374D01*
X-84891Y314040D01*
X-84641Y313540D01*
Y311207D01*
G01X-81541Y314540D02*
Y311207D01*
G01Y315874D02*
X-81708Y315957D01*
Y316124D01*
X-81541Y316207D01*
X-81374Y316124D01*
Y315957D01*
X-81541Y315874D01*
G01X-75941Y311207D02*
Y316207D01*
G01X-69924Y309540D02*
X-69091Y310374D01*
X-68674Y311207D01*
Y314540D01*
X-69091Y315374D01*
X-69924Y316207D01*
G01X-242741Y305207D02*
X189259D01*
G01X-242741Y320207D02*
X189259D01*
G01X-235524Y388780D02*
X-234524Y385447D01*
X-233441Y388780D01*
X-232358Y385447D01*
X-231358Y388780D01*
G01X-227841D02*
Y385447D01*
G01Y390114D02*
X-228008Y390197D01*
Y390364D01*
X-227841Y390447D01*
X-227674Y390364D01*
Y390197D01*
X-227841Y390114D01*
G01X-222241Y390447D02*
Y385447D01*
G01X-223408Y388780D02*
X-221074D01*
G01X-218058Y385447D02*
Y390447D01*
G01Y388030D02*
X-217641Y388447D01*
X-217224Y388697D01*
X-216558Y388780D01*
X-216058Y388697D01*
X-215474Y388364D01*
X-215224Y387864D01*
Y385447D01*
G01X-211041D02*
X-211541Y385530D01*
X-212041Y385864D01*
X-212374Y386447D01*
X-212541Y387114D01*
X-212374Y387780D01*
X-212041Y388364D01*
X-211541Y388697D01*
X-211041Y388780D01*
X-210541Y388697D01*
X-210041Y388364D01*
X-209708Y387780D01*
X-209624Y387114D01*
X-209708Y386447D01*
X-210041Y385864D01*
X-210541Y385530D01*
X-211041Y385447D01*
G01X-206858Y388780D02*
Y386447D01*
X-206524Y385864D01*
X-206024Y385530D01*
X-205441Y385447D01*
X-204858Y385530D01*
X-204358Y385864D01*
X-204024Y386447D01*
G01Y385447D02*
Y388780D01*
G01X-199841Y390447D02*
Y385447D01*
G01X-201008Y388780D02*
X-198674D01*
G01X-187308Y388364D02*
X-187891Y388697D01*
X-188391Y388780D01*
X-189058Y388614D01*
X-189558Y388280D01*
X-189891Y387697D01*
X-189974Y387114D01*
X-189891Y386530D01*
X-189558Y386030D01*
X-189058Y385614D01*
X-188391Y385447D01*
X-187808Y385614D01*
X-187308Y385947D01*
G01X-183041Y385447D02*
X-183541Y385530D01*
X-184041Y385864D01*
X-184374Y386447D01*
X-184541Y387114D01*
X-184374Y387780D01*
X-184041Y388364D01*
X-183541Y388697D01*
X-183041Y388780D01*
X-182541Y388697D01*
X-182041Y388364D01*
X-181708Y387780D01*
X-181624Y387114D01*
X-181708Y386447D01*
X-182041Y385864D01*
X-182541Y385530D01*
X-183041Y385447D01*
G01X-178858D02*
Y388780D01*
G01Y387947D02*
X-178524Y388364D01*
X-178024Y388697D01*
X-177358Y388780D01*
X-176774Y388697D01*
X-176274Y388364D01*
X-176024Y387780D01*
Y385447D01*
G01X-173258D02*
Y388780D01*
G01Y387947D02*
X-172924Y388364D01*
X-172424Y388697D01*
X-171758Y388780D01*
X-171174Y388697D01*
X-170674Y388364D01*
X-170424Y387780D01*
Y385447D01*
G01X-167491Y387697D02*
X-164824D01*
X-165074Y388280D01*
X-165491Y388614D01*
X-166074Y388780D01*
X-166658Y388697D01*
X-167158Y388447D01*
X-167491Y387864D01*
X-167658Y387364D01*
Y386864D01*
X-167491Y386364D01*
X-167074Y385864D01*
X-166574Y385530D01*
X-165991Y385447D01*
X-165408Y385614D01*
X-164824Y386114D01*
G01X-159308Y388364D02*
X-159891Y388697D01*
X-160391Y388780D01*
X-161058Y388614D01*
X-161558Y388280D01*
X-161891Y387697D01*
X-161974Y387114D01*
X-161891Y386530D01*
X-161558Y386030D01*
X-161058Y385614D01*
X-160391Y385447D01*
X-159808Y385614D01*
X-159308Y385947D01*
G01X-155041Y390447D02*
Y385447D01*
G01X-156208Y388780D02*
X-153874D01*
G01X-149441D02*
Y385447D01*
G01Y390114D02*
X-149608Y390197D01*
Y390364D01*
X-149441Y390447D01*
X-149274Y390364D01*
Y390197D01*
X-149441Y390114D01*
G01X-145258Y385447D02*
Y388780D01*
G01Y387947D02*
X-144924Y388364D01*
X-144424Y388697D01*
X-143758Y388780D01*
X-143174Y388697D01*
X-142674Y388364D01*
X-142424Y387780D01*
Y385447D01*
G01X-139408Y384197D02*
X-138824Y383864D01*
X-138158Y383780D01*
X-137574Y383864D01*
X-137074Y384280D01*
X-136741Y384864D01*
Y388780D01*
G01Y388114D02*
X-137074Y388447D01*
X-137574Y388697D01*
X-138158Y388780D01*
X-138824Y388614D01*
X-139241Y388280D01*
X-139574Y387697D01*
X-139741Y387114D01*
X-139658Y386614D01*
X-139324Y386030D01*
X-138824Y385614D01*
X-138158Y385447D01*
X-137658Y385530D01*
X-137074Y385864D01*
X-136741Y386197D01*
G01X-127041Y390447D02*
Y385447D01*
G01X-128208Y388780D02*
X-125874D01*
G01X-121441Y385447D02*
X-121941Y385530D01*
X-122441Y385864D01*
X-122774Y386447D01*
X-122941Y387114D01*
X-122774Y387780D01*
X-122441Y388364D01*
X-121941Y388697D01*
X-121441Y388780D01*
X-120941Y388697D01*
X-120441Y388364D01*
X-120108Y387780D01*
X-120024Y387114D01*
X-120108Y386447D01*
X-120441Y385864D01*
X-120941Y385530D01*
X-121441Y385447D01*
G01X-110241D02*
X-110741Y385530D01*
X-111241Y385864D01*
X-111574Y386447D01*
X-111741Y387114D01*
X-111574Y387780D01*
X-111241Y388364D01*
X-110741Y388697D01*
X-110241Y388780D01*
X-109741Y388697D01*
X-109241Y388364D01*
X-108908Y387780D01*
X-108824Y387114D01*
X-108908Y386447D01*
X-109241Y385864D01*
X-109741Y385530D01*
X-110241Y385447D01*
G01X-104641Y390447D02*
Y385447D01*
G01X-105808Y388780D02*
X-103474D01*
G01X-100458Y385447D02*
Y390447D01*
G01Y388030D02*
X-100041Y388447D01*
X-99624Y388697D01*
X-98958Y388780D01*
X-98458Y388697D01*
X-97874Y388364D01*
X-97624Y387864D01*
Y385447D01*
G01X-94691Y387697D02*
X-92024D01*
X-92274Y388280D01*
X-92691Y388614D01*
X-93274Y388780D01*
X-93858Y388697D01*
X-94358Y388447D01*
X-94691Y387864D01*
X-94858Y387364D01*
Y386864D01*
X-94691Y386364D01*
X-94274Y385864D01*
X-93774Y385530D01*
X-93191Y385447D01*
X-92608Y385614D01*
X-92024Y386114D01*
G01X-89008Y385447D02*
Y388780D01*
G01Y388114D02*
X-88591Y388447D01*
X-88174Y388697D01*
X-87591Y388780D01*
X-87174Y388697D01*
X-86674Y388447D01*
G01X-76641Y385447D02*
Y390447D01*
G01X-69541Y385447D02*
Y388780D01*
G01Y388197D02*
X-69874Y388530D01*
X-70374Y388697D01*
X-70958Y388780D01*
X-71541Y388614D01*
X-72041Y388280D01*
X-72374Y387780D01*
X-72541Y387114D01*
X-72374Y386447D01*
X-72041Y385947D01*
X-71541Y385614D01*
X-70958Y385447D01*
X-70374Y385530D01*
X-69874Y385780D01*
X-69541Y386114D01*
G01X-67191Y383947D02*
X-66691Y383780D01*
X-66024Y383947D01*
X-65608Y384280D01*
X-65274Y384697D01*
X-64774Y386030D01*
X-63691Y388780D01*
G01X-66358D02*
X-64774Y386030D01*
G01X-61091Y387697D02*
X-58424D01*
X-58674Y388280D01*
X-59091Y388614D01*
X-59674Y388780D01*
X-60258Y388697D01*
X-60758Y388447D01*
X-61091Y387864D01*
X-61258Y387364D01*
Y386864D01*
X-61091Y386364D01*
X-60674Y385864D01*
X-60174Y385530D01*
X-59591Y385447D01*
X-59008Y385614D01*
X-58424Y386114D01*
G01X-55408Y385447D02*
Y388780D01*
G01Y388114D02*
X-54991Y388447D01*
X-54574Y388697D01*
X-53991Y388780D01*
X-53574Y388697D01*
X-53074Y388447D01*
G01X-49891Y386030D02*
X-49474Y385697D01*
X-48891Y385447D01*
X-48391D01*
X-47891Y385614D01*
X-47558Y385864D01*
X-47391Y386197D01*
X-47474Y386697D01*
X-47808Y386947D01*
X-49308Y387447D01*
X-49641Y388030D01*
X-49474Y388447D01*
X-49141Y388697D01*
X-48641Y388780D01*
X-48141Y388697D01*
X-47641Y388447D01*
G01X-42624Y383780D02*
X-41791Y384614D01*
X-41374Y385447D01*
Y388780D01*
X-41791Y389614D01*
X-42624Y390447D01*
G01X-234984Y396157D02*
Y401157D01*
X-233318D01*
X-232651Y400907D01*
X-232151Y400574D01*
X-231734Y400074D01*
X-231401Y399490D01*
X-231318Y398657D01*
X-231401Y397824D01*
X-231734Y397240D01*
X-232151Y396740D01*
X-232651Y396407D01*
X-233318Y396157D01*
X-234984D01*
G01X-228801Y398407D02*
X-226134D01*
X-226384Y398990D01*
X-226801Y399324D01*
X-227384Y399490D01*
X-227968Y399407D01*
X-228468Y399157D01*
X-228801Y398574D01*
X-228968Y398074D01*
Y397574D01*
X-228801Y397074D01*
X-228384Y396574D01*
X-227884Y396240D01*
X-227301Y396157D01*
X-226718Y396324D01*
X-226134Y396824D01*
G01X-221951Y396157D02*
Y401157D01*
G01X-217601Y398407D02*
X-214934D01*
X-215184Y398990D01*
X-215601Y399324D01*
X-216184Y399490D01*
X-216768Y399407D01*
X-217268Y399157D01*
X-217601Y398574D01*
X-217768Y398074D01*
Y397574D01*
X-217601Y397074D01*
X-217184Y396574D01*
X-216684Y396240D01*
X-216101Y396157D01*
X-215518Y396324D01*
X-214934Y396824D01*
G01X-210751Y401157D02*
Y396157D01*
G01X-211918Y399490D02*
X-209584D01*
G01X-206401Y398407D02*
X-203734D01*
X-203984Y398990D01*
X-204401Y399324D01*
X-204984Y399490D01*
X-205568Y399407D01*
X-206068Y399157D01*
X-206401Y398574D01*
X-206568Y398074D01*
Y397574D01*
X-206401Y397074D01*
X-205984Y396574D01*
X-205484Y396240D01*
X-204901Y396157D01*
X-204318Y396324D01*
X-203734Y396824D01*
G01X-195368Y396157D02*
Y399490D01*
G01Y398657D02*
X-195034Y399074D01*
X-194534Y399407D01*
X-193868Y399490D01*
X-193284Y399407D01*
X-192784Y399074D01*
X-192534Y398490D01*
Y396157D01*
G01X-188351D02*
X-188851Y396240D01*
X-189351Y396574D01*
X-189684Y397157D01*
X-189851Y397824D01*
X-189684Y398490D01*
X-189351Y399074D01*
X-188851Y399407D01*
X-188351Y399490D01*
X-187851Y399407D01*
X-187351Y399074D01*
X-187018Y398490D01*
X-186934Y397824D01*
X-187018Y397157D01*
X-187351Y396574D01*
X-187851Y396240D01*
X-188351Y396157D01*
G01X-184168D02*
Y399490D01*
G01Y398657D02*
X-183834Y399074D01*
X-183334Y399407D01*
X-182668Y399490D01*
X-182084Y399407D01*
X-181584Y399074D01*
X-181334Y398490D01*
Y396157D01*
G01X-178234Y397824D02*
X-176068D01*
G01X-172051Y396157D02*
Y400407D01*
X-171884Y400824D01*
X-171551Y401074D01*
X-171051Y401157D01*
X-170551Y400990D01*
X-170301Y400574D01*
G01X-171301Y399157D02*
X-172968D01*
G01X-167368Y399490D02*
Y397157D01*
X-167034Y396574D01*
X-166534Y396240D01*
X-165951Y396157D01*
X-165368Y396240D01*
X-164868Y396574D01*
X-164534Y397157D01*
G01Y396157D02*
Y399490D01*
G01X-161768Y396157D02*
Y399490D01*
G01Y398657D02*
X-161434Y399074D01*
X-160934Y399407D01*
X-160268Y399490D01*
X-159684Y399407D01*
X-159184Y399074D01*
X-158934Y398490D01*
Y396157D01*
G01X-153418Y399074D02*
X-154001Y399407D01*
X-154501Y399490D01*
X-155168Y399324D01*
X-155668Y398990D01*
X-156001Y398407D01*
X-156084Y397824D01*
X-156001Y397240D01*
X-155668Y396740D01*
X-155168Y396324D01*
X-154501Y396157D01*
X-153918Y396324D01*
X-153418Y396657D01*
G01X-149151Y401157D02*
Y396157D01*
G01X-150318Y399490D02*
X-147984D01*
G01X-143551D02*
Y396157D01*
G01Y400824D02*
X-143718Y400907D01*
Y401074D01*
X-143551Y401157D01*
X-143384Y401074D01*
Y400907D01*
X-143551Y400824D01*
G01X-137951Y396157D02*
X-138451Y396240D01*
X-138951Y396574D01*
X-139284Y397157D01*
X-139451Y397824D01*
X-139284Y398490D01*
X-138951Y399074D01*
X-138451Y399407D01*
X-137951Y399490D01*
X-137451Y399407D01*
X-136951Y399074D01*
X-136618Y398490D01*
X-136534Y397824D01*
X-136618Y397157D01*
X-136951Y396574D01*
X-137451Y396240D01*
X-137951Y396157D01*
G01X-133768D02*
Y399490D01*
G01Y398657D02*
X-133434Y399074D01*
X-132934Y399407D01*
X-132268Y399490D01*
X-131684Y399407D01*
X-131184Y399074D01*
X-130934Y398490D01*
Y396157D01*
G01X-125251D02*
Y399490D01*
G01Y398907D02*
X-125584Y399240D01*
X-126084Y399407D01*
X-126668Y399490D01*
X-127251Y399324D01*
X-127751Y398990D01*
X-128084Y398490D01*
X-128251Y397824D01*
X-128084Y397157D01*
X-127751Y396657D01*
X-127251Y396324D01*
X-126668Y396157D01*
X-126084Y396240D01*
X-125584Y396490D01*
X-125251Y396824D01*
G01X-121151Y396157D02*
Y401157D01*
G01X-111451Y394490D02*
Y399490D01*
G01Y398740D02*
X-111034Y399157D01*
X-110618Y399407D01*
X-109951Y399490D01*
X-109368Y399407D01*
X-108784Y398990D01*
X-108534Y398407D01*
X-108451Y397824D01*
X-108534Y397240D01*
X-108784Y396657D01*
X-109284Y396324D01*
X-109951Y396157D01*
X-110534Y396240D01*
X-111118Y396490D01*
X-111451Y396824D01*
G01X-102851Y396157D02*
Y399490D01*
G01Y398907D02*
X-103184Y399240D01*
X-103684Y399407D01*
X-104268Y399490D01*
X-104851Y399324D01*
X-105351Y398990D01*
X-105684Y398490D01*
X-105851Y397824D01*
X-105684Y397157D01*
X-105351Y396657D01*
X-104851Y396324D01*
X-104268Y396157D01*
X-103684Y396240D01*
X-103184Y396490D01*
X-102851Y396824D01*
G01X-97251Y401157D02*
Y396157D01*
G01Y396907D02*
X-97584Y396490D01*
X-98084Y396240D01*
X-98668Y396157D01*
X-99334Y396324D01*
X-99834Y396740D01*
X-100168Y397240D01*
X-100251Y397824D01*
X-100168Y398407D01*
X-99834Y398907D01*
X-99334Y399324D01*
X-98668Y399490D01*
X-98084Y399407D01*
X-97668Y399240D01*
X-97251Y398907D01*
G01X-87551Y399490D02*
Y396157D01*
G01Y400824D02*
X-87718Y400907D01*
Y401074D01*
X-87551Y401157D01*
X-87384Y401074D01*
Y400907D01*
X-87551Y400824D01*
G01X-83368Y396157D02*
Y399490D01*
G01Y398657D02*
X-83034Y399074D01*
X-82534Y399407D01*
X-81868Y399490D01*
X-81284Y399407D01*
X-80784Y399074D01*
X-80534Y398490D01*
Y396157D01*
G01X-69251D02*
Y399490D01*
G01Y398907D02*
X-69584Y399240D01*
X-70084Y399407D01*
X-70668Y399490D01*
X-71251Y399324D01*
X-71751Y398990D01*
X-72084Y398490D01*
X-72251Y397824D01*
X-72084Y397157D01*
X-71751Y396657D01*
X-71251Y396324D01*
X-70668Y396157D01*
X-70084Y396240D01*
X-69584Y396490D01*
X-69251Y396824D01*
G01X-65151Y396157D02*
Y401157D01*
G01X-59551Y396157D02*
Y401157D01*
G01X-49851Y394490D02*
Y399490D01*
G01Y398740D02*
X-49434Y399157D01*
X-49018Y399407D01*
X-48351Y399490D01*
X-47768Y399407D01*
X-47184Y398990D01*
X-46934Y398407D01*
X-46851Y397824D01*
X-46934Y397240D01*
X-47184Y396657D01*
X-47684Y396324D01*
X-48351Y396157D01*
X-48934Y396240D01*
X-49518Y396490D01*
X-49851Y396824D01*
G01X-43918Y396157D02*
Y399490D01*
G01Y398824D02*
X-43501Y399157D01*
X-43084Y399407D01*
X-42501Y399490D01*
X-42084Y399407D01*
X-41584Y399157D01*
G01X-37151Y396157D02*
X-37651Y396240D01*
X-38151Y396574D01*
X-38484Y397157D01*
X-38651Y397824D01*
X-38484Y398490D01*
X-38151Y399074D01*
X-37651Y399407D01*
X-37151Y399490D01*
X-36651Y399407D01*
X-36151Y399074D01*
X-35818Y398490D01*
X-35734Y397824D01*
X-35818Y397157D01*
X-36151Y396574D01*
X-36651Y396240D01*
X-37151Y396157D01*
G01X-30051Y401157D02*
Y396157D01*
G01Y396907D02*
X-30384Y396490D01*
X-30884Y396240D01*
X-31468Y396157D01*
X-32134Y396324D01*
X-32634Y396740D01*
X-32968Y397240D01*
X-33051Y397824D01*
X-32968Y398407D01*
X-32634Y398907D01*
X-32134Y399324D01*
X-31468Y399490D01*
X-30884Y399407D01*
X-30468Y399240D01*
X-30051Y398907D01*
G01X-27368Y399490D02*
Y397157D01*
X-27034Y396574D01*
X-26534Y396240D01*
X-25951Y396157D01*
X-25368Y396240D01*
X-24868Y396574D01*
X-24534Y397157D01*
G01Y396157D02*
Y399490D01*
G01X-19018Y399074D02*
X-19601Y399407D01*
X-20101Y399490D01*
X-20768Y399324D01*
X-21268Y398990D01*
X-21601Y398407D01*
X-21684Y397824D01*
X-21601Y397240D01*
X-21268Y396740D01*
X-20768Y396324D01*
X-20101Y396157D01*
X-19518Y396324D01*
X-19018Y396657D01*
G01X-14751Y401157D02*
Y396157D01*
G01X-15918Y399490D02*
X-13584D01*
G01X-10401Y396740D02*
X-9984Y396407D01*
X-9401Y396157D01*
X-8901D01*
X-8401Y396324D01*
X-8068Y396574D01*
X-7901Y396907D01*
X-7984Y397407D01*
X-8318Y397657D01*
X-9818Y398157D01*
X-10151Y398740D01*
X-9984Y399157D01*
X-9651Y399407D01*
X-9151Y399490D01*
X-8651Y399407D01*
X-8151Y399157D01*
G01X-3551Y395990D02*
X-3718Y396074D01*
Y396240D01*
X-3551Y396324D01*
X-3384Y396240D01*
Y396074D01*
X-3551Y395990D01*
G01X1632Y394490D02*
X799Y395324D01*
X382Y396157D01*
Y399490D01*
X799Y400324D01*
X1632Y401157D01*
G01X6649D02*
X8649D01*
G01X7649D02*
Y396157D01*
G01X6649D02*
X8649D01*
G01X11999Y396740D02*
X12416Y396407D01*
X12999Y396157D01*
X13499D01*
X13999Y396324D01*
X14332Y396574D01*
X14499Y396907D01*
X14416Y397407D01*
X14082Y397657D01*
X12582Y398157D01*
X12249Y398740D01*
X12416Y399157D01*
X12749Y399407D01*
X13249Y399490D01*
X13749Y399407D01*
X14249Y399157D01*
G01X18849Y396157D02*
X18349Y396240D01*
X17849Y396574D01*
X17516Y397157D01*
X17349Y397824D01*
X17516Y398490D01*
X17849Y399074D01*
X18349Y399407D01*
X18849Y399490D01*
X19349Y399407D01*
X19849Y399074D01*
X20182Y398490D01*
X20266Y397824D01*
X20182Y397157D01*
X19849Y396574D01*
X19349Y396240D01*
X18849Y396157D01*
G01X24449D02*
Y401157D01*
G01X31549Y396157D02*
Y399490D01*
G01Y398907D02*
X31216Y399240D01*
X30716Y399407D01*
X30132Y399490D01*
X29549Y399324D01*
X29049Y398990D01*
X28716Y398490D01*
X28549Y397824D01*
X28716Y397157D01*
X29049Y396657D01*
X29549Y396324D01*
X30132Y396157D01*
X30716Y396240D01*
X31216Y396490D01*
X31549Y396824D01*
G01X35649Y401157D02*
Y396157D01*
G01X34482Y399490D02*
X36816D01*
G01X39999Y398407D02*
X42666D01*
X42416Y398990D01*
X41999Y399324D01*
X41416Y399490D01*
X40832Y399407D01*
X40332Y399157D01*
X39999Y398574D01*
X39832Y398074D01*
Y397574D01*
X39999Y397074D01*
X40416Y396574D01*
X40916Y396240D01*
X41499Y396157D01*
X42082Y396324D01*
X42666Y396824D01*
G01X50949Y394490D02*
Y399490D01*
G01Y398740D02*
X51366Y399157D01*
X51782Y399407D01*
X52449Y399490D01*
X53032Y399407D01*
X53616Y398990D01*
X53866Y398407D01*
X53949Y397824D01*
X53866Y397240D01*
X53616Y396657D01*
X53116Y396324D01*
X52449Y396157D01*
X51866Y396240D01*
X51282Y396490D01*
X50949Y396824D01*
G01X59549Y396157D02*
Y399490D01*
G01Y398907D02*
X59216Y399240D01*
X58716Y399407D01*
X58132Y399490D01*
X57549Y399324D01*
X57049Y398990D01*
X56716Y398490D01*
X56549Y397824D01*
X56716Y397157D01*
X57049Y396657D01*
X57549Y396324D01*
X58132Y396157D01*
X58716Y396240D01*
X59216Y396490D01*
X59549Y396824D01*
G01X65149Y401157D02*
Y396157D01*
G01Y396907D02*
X64816Y396490D01*
X64316Y396240D01*
X63732Y396157D01*
X63066Y396324D01*
X62566Y396740D01*
X62232Y397240D01*
X62149Y397824D01*
X62232Y398407D01*
X62566Y398907D01*
X63066Y399324D01*
X63732Y399490D01*
X64316Y399407D01*
X64732Y399240D01*
X65149Y398907D01*
G01X-182618Y55170D02*
X-182351Y55370D01*
X-182151Y55704D01*
X-182018Y56170D01*
X-182151Y56570D01*
X-182418Y56837D01*
X-182884Y57037D01*
X-184684D01*
Y53037D01*
X-182484D01*
X-182018Y53304D01*
X-181751Y53704D01*
X-181618Y54170D01*
X-181751Y54637D01*
X-182151Y55037D01*
X-182618Y55170D01*
X-184684D01*
G01X-184818Y102537D02*
X-183151Y106537D01*
X-181484Y102537D01*
G01X-182084Y103937D02*
X-184218D01*
G01X-102264Y-18906D02*
X-101931Y-18656D01*
X-101681Y-18240D01*
X-101514Y-17656D01*
X-101681Y-17156D01*
X-102014Y-16823D01*
X-102598Y-16573D01*
X-104848D01*
Y-21573D01*
X-102098D01*
X-101514Y-21240D01*
X-101181Y-20740D01*
X-101014Y-20156D01*
X-101181Y-19573D01*
X-101681Y-19073D01*
X-102264Y-18906D01*
X-104848D01*
G01X-98748Y-18240D02*
Y-20573D01*
X-98414Y-21156D01*
X-97914Y-21490D01*
X-97331Y-21573D01*
X-96748Y-21490D01*
X-96248Y-21156D01*
X-95914Y-20573D01*
G01Y-21573D02*
Y-18240D01*
G01X-94231Y-21573D02*
Y-18240D01*
G01Y-19156D02*
X-93981Y-18740D01*
X-93564Y-18406D01*
X-92981Y-18240D01*
X-92398Y-18406D01*
X-91981Y-18740D01*
X-91731Y-19156D01*
Y-21573D01*
G01Y-19156D02*
X-91481Y-18740D01*
X-91064Y-18406D01*
X-90481Y-18240D01*
X-89898Y-18406D01*
X-89481Y-18740D01*
X-89231Y-19240D01*
Y-21573D01*
G01X-87631Y-23240D02*
Y-18240D01*
G01Y-18990D02*
X-87214Y-18573D01*
X-86798Y-18323D01*
X-86131Y-18240D01*
X-85548Y-18323D01*
X-84964Y-18740D01*
X-84714Y-19323D01*
X-84631Y-19906D01*
X-84714Y-20490D01*
X-84964Y-21073D01*
X-85464Y-21406D01*
X-86131Y-21573D01*
X-86714Y-21490D01*
X-87298Y-21240D01*
X-87631Y-20906D01*
G01X-110241Y115707D02*
Y-73293D01*
G01X-103721Y19420D02*
X-102221Y16087D01*
X-100721Y19420D01*
G01X-96621D02*
Y16087D01*
G01Y20754D02*
X-96788Y20837D01*
Y21004D01*
X-96621Y21087D01*
X-96454Y21004D01*
Y20837D01*
X-96621Y20754D01*
G01X-89521Y16087D02*
Y19420D01*
G01Y18837D02*
X-89854Y19170D01*
X-90354Y19337D01*
X-90938Y19420D01*
X-91521Y19254D01*
X-92021Y18920D01*
X-92354Y18420D01*
X-92521Y17754D01*
X-92354Y17087D01*
X-92021Y16587D01*
X-91521Y16254D01*
X-90938Y16087D01*
X-90354Y16170D01*
X-89854Y16420D01*
X-89521Y16754D01*
G01X-104174Y28567D02*
Y33567D01*
X-102508D01*
X-101841Y33317D01*
X-101341Y32984D01*
X-100924Y32484D01*
X-100591Y31900D01*
X-100508Y31067D01*
X-100591Y30234D01*
X-100924Y29650D01*
X-101341Y29150D01*
X-101841Y28817D01*
X-102508Y28567D01*
X-104174D01*
G01X-96741Y31900D02*
Y28567D01*
G01Y33234D02*
X-96908Y33317D01*
Y33484D01*
X-96741Y33567D01*
X-96574Y33484D01*
Y33317D01*
X-96741Y33234D01*
G01X-93641Y28567D02*
Y31900D01*
G01Y30984D02*
X-93391Y31400D01*
X-92974Y31734D01*
X-92391Y31900D01*
X-91808Y31734D01*
X-91391Y31400D01*
X-91141Y30984D01*
Y28567D01*
G01Y30984D02*
X-90891Y31400D01*
X-90474Y31734D01*
X-89891Y31900D01*
X-89308Y31734D01*
X-88891Y31400D01*
X-88641Y30900D01*
Y28567D01*
G01X-87041Y26900D02*
Y31900D01*
G01Y31150D02*
X-86624Y31567D01*
X-86208Y31817D01*
X-85541Y31900D01*
X-84958Y31817D01*
X-84374Y31400D01*
X-84124Y30817D01*
X-84041Y30234D01*
X-84124Y29650D01*
X-84374Y29067D01*
X-84874Y28734D01*
X-85541Y28567D01*
X-86124Y28650D01*
X-86708Y28900D01*
X-87041Y29234D01*
G01X-79941Y28567D02*
Y33567D01*
G01X-75591Y30817D02*
X-72924D01*
X-73174Y31400D01*
X-73591Y31734D01*
X-74174Y31900D01*
X-74758Y31817D01*
X-75258Y31567D01*
X-75591Y30984D01*
X-75758Y30484D01*
Y29984D01*
X-75591Y29484D01*
X-75174Y28984D01*
X-74674Y28650D01*
X-74091Y28567D01*
X-73508Y28734D01*
X-72924Y29234D01*
G01X-63641Y28567D02*
Y32817D01*
X-63474Y33234D01*
X-63141Y33484D01*
X-62641Y33567D01*
X-62141Y33400D01*
X-61891Y32984D01*
G01X-62891Y31567D02*
X-64558D01*
G01X-57541Y28567D02*
X-58041Y28650D01*
X-58541Y28984D01*
X-58874Y29567D01*
X-59041Y30234D01*
X-58874Y30900D01*
X-58541Y31484D01*
X-58041Y31817D01*
X-57541Y31900D01*
X-57041Y31817D01*
X-56541Y31484D01*
X-56208Y30900D01*
X-56124Y30234D01*
X-56208Y29567D01*
X-56541Y28984D01*
X-57041Y28650D01*
X-57541Y28567D01*
G01X-53108D02*
Y31900D01*
G01Y31234D02*
X-52691Y31567D01*
X-52274Y31817D01*
X-51691Y31900D01*
X-51274Y31817D01*
X-50774Y31567D01*
G01X-40741Y28567D02*
X-41241Y28650D01*
X-41741Y28984D01*
X-42074Y29567D01*
X-42241Y30234D01*
X-42074Y30900D01*
X-41741Y31484D01*
X-41241Y31817D01*
X-40741Y31900D01*
X-40241Y31817D01*
X-39741Y31484D01*
X-39408Y30900D01*
X-39324Y30234D01*
X-39408Y29567D01*
X-39741Y28984D01*
X-40241Y28650D01*
X-40741Y28567D01*
G01X-36558Y31900D02*
Y29567D01*
X-36224Y28984D01*
X-35724Y28650D01*
X-35141Y28567D01*
X-34558Y28650D01*
X-34058Y28984D01*
X-33724Y29567D01*
G01Y28567D02*
Y31900D01*
G01X-29541Y33567D02*
Y28567D01*
G01X-30708Y31900D02*
X-28374D01*
G01X-25191Y30817D02*
X-22524D01*
X-22774Y31400D01*
X-23191Y31734D01*
X-23774Y31900D01*
X-24358Y31817D01*
X-24858Y31567D01*
X-25191Y30984D01*
X-25358Y30484D01*
Y29984D01*
X-25191Y29484D01*
X-24774Y28984D01*
X-24274Y28650D01*
X-23691Y28567D01*
X-23108Y28734D01*
X-22524Y29234D01*
G01X-19508Y28567D02*
Y31900D01*
G01Y31234D02*
X-19091Y31567D01*
X-18674Y31817D01*
X-18091Y31900D01*
X-17674Y31817D01*
X-17174Y31567D01*
G01X-5641Y28567D02*
Y31900D01*
G01Y31317D02*
X-5974Y31650D01*
X-6474Y31817D01*
X-7058Y31900D01*
X-7641Y31734D01*
X-8141Y31400D01*
X-8474Y30900D01*
X-8641Y30234D01*
X-8474Y29567D01*
X-8141Y29067D01*
X-7641Y28734D01*
X-7058Y28567D01*
X-6474Y28650D01*
X-5974Y28900D01*
X-5641Y29234D01*
G01X-2958Y28567D02*
Y31900D01*
G01Y31067D02*
X-2624Y31484D01*
X-2124Y31817D01*
X-1458Y31900D01*
X-874Y31817D01*
X-374Y31484D01*
X-124Y30900D01*
Y28567D01*
G01X5559Y33567D02*
Y28567D01*
G01Y29317D02*
X5226Y28900D01*
X4726Y28650D01*
X4142Y28567D01*
X3476Y28734D01*
X2976Y29150D01*
X2642Y29650D01*
X2559Y30234D01*
X2642Y30817D01*
X2976Y31317D01*
X3476Y31734D01*
X4142Y31900D01*
X4726Y31817D01*
X5142Y31650D01*
X5559Y31317D01*
G01X15259Y31900D02*
Y28567D01*
G01Y33234D02*
X15092Y33317D01*
Y33484D01*
X15259Y33567D01*
X15426Y33484D01*
Y33317D01*
X15259Y33234D01*
G01X19442Y28567D02*
Y31900D01*
G01Y31067D02*
X19776Y31484D01*
X20276Y31817D01*
X20942Y31900D01*
X21526Y31817D01*
X22026Y31484D01*
X22276Y30900D01*
Y28567D01*
G01X25042D02*
Y31900D01*
G01Y31067D02*
X25376Y31484D01*
X25876Y31817D01*
X26542Y31900D01*
X27126Y31817D01*
X27626Y31484D01*
X27876Y30900D01*
Y28567D01*
G01X30809Y30817D02*
X33476D01*
X33226Y31400D01*
X32809Y31734D01*
X32226Y31900D01*
X31642Y31817D01*
X31142Y31567D01*
X30809Y30984D01*
X30642Y30484D01*
Y29984D01*
X30809Y29484D01*
X31226Y28984D01*
X31726Y28650D01*
X32309Y28567D01*
X32892Y28734D01*
X33476Y29234D01*
G01X36492Y28567D02*
Y31900D01*
G01Y31234D02*
X36909Y31567D01*
X37326Y31817D01*
X37909Y31900D01*
X38326Y31817D01*
X38826Y31567D01*
G01X48859Y28567D02*
Y33567D01*
G01X55959Y28567D02*
Y31900D01*
G01Y31317D02*
X55626Y31650D01*
X55126Y31817D01*
X54542Y31900D01*
X53959Y31734D01*
X53459Y31400D01*
X53126Y30900D01*
X52959Y30234D01*
X53126Y29567D01*
X53459Y29067D01*
X53959Y28734D01*
X54542Y28567D01*
X55126Y28650D01*
X55626Y28900D01*
X55959Y29234D01*
G01X58809Y29150D02*
X59226Y28817D01*
X59809Y28567D01*
X60309D01*
X60809Y28734D01*
X61142Y28984D01*
X61309Y29317D01*
X61226Y29817D01*
X60892Y30067D01*
X59392Y30567D01*
X59059Y31150D01*
X59226Y31567D01*
X59559Y31817D01*
X60059Y31900D01*
X60559Y31817D01*
X61059Y31567D01*
G01X64409Y30817D02*
X67076D01*
X66826Y31400D01*
X66409Y31734D01*
X65826Y31900D01*
X65242Y31817D01*
X64742Y31567D01*
X64409Y30984D01*
X64242Y30484D01*
Y29984D01*
X64409Y29484D01*
X64826Y28984D01*
X65326Y28650D01*
X65909Y28567D01*
X66492Y28734D01*
X67076Y29234D01*
G01X70092Y28567D02*
Y31900D01*
G01Y31234D02*
X70509Y31567D01*
X70926Y31817D01*
X71509Y31900D01*
X71926Y31817D01*
X72426Y31567D01*
G01X-103414Y46747D02*
X-101331Y51747D01*
X-99248Y46747D01*
G01X-99998Y48497D02*
X-102664D01*
G01X-97148Y46747D02*
Y50080D01*
G01Y49247D02*
X-96814Y49664D01*
X-96314Y49997D01*
X-95648Y50080D01*
X-95064Y49997D01*
X-94564Y49664D01*
X-94314Y49080D01*
Y46747D01*
G01X-91298Y45497D02*
X-90714Y45164D01*
X-90048Y45080D01*
X-89464Y45164D01*
X-88964Y45580D01*
X-88631Y46164D01*
Y50080D01*
G01Y49414D02*
X-88964Y49747D01*
X-89464Y49997D01*
X-90048Y50080D01*
X-90714Y49914D01*
X-91131Y49580D01*
X-91464Y48997D01*
X-91631Y48414D01*
X-91548Y47914D01*
X-91214Y47330D01*
X-90714Y46914D01*
X-90048Y46747D01*
X-89548Y46830D01*
X-88964Y47164D01*
X-88631Y47497D01*
G01X-84531Y46747D02*
Y51747D01*
G01X-80181Y48997D02*
X-77514D01*
X-77764Y49580D01*
X-78181Y49914D01*
X-78764Y50080D01*
X-79348Y49997D01*
X-79848Y49747D01*
X-80181Y49164D01*
X-80348Y48664D01*
Y48164D01*
X-80181Y47664D01*
X-79764Y47164D01*
X-79264Y46830D01*
X-78681Y46747D01*
X-78098Y46914D01*
X-77514Y47414D01*
G01X-73748Y45080D02*
X-74581Y45914D01*
X-74998Y46747D01*
Y50080D01*
X-74581Y50914D01*
X-73748Y51747D01*
G01X-56114Y45080D02*
X-55281Y45914D01*
X-54864Y46747D01*
Y50080D01*
X-55281Y50914D01*
X-56114Y51747D01*
G01X-110241Y56707D02*
X189259D01*
G01X-144124Y79744D02*
X-144524Y79944D01*
X-144991Y80077D01*
X-145524D01*
X-146124Y79877D01*
X-146591Y79544D01*
X-146924Y79144D01*
X-147191Y78477D01*
X-147258Y77877D01*
X-147124Y77277D01*
X-146924Y76877D01*
X-146524Y76477D01*
X-146058Y76210D01*
X-145591Y76077D01*
X-145124D01*
X-144658Y76210D01*
X-144258Y76410D01*
X-143924Y76677D01*
G01X-103464Y83134D02*
X-103131Y83384D01*
X-102881Y83800D01*
X-102714Y84384D01*
X-102881Y84884D01*
X-103214Y85217D01*
X-103798Y85467D01*
X-106048D01*
Y80467D01*
X-103298D01*
X-102714Y80800D01*
X-102381Y81300D01*
X-102214Y81884D01*
X-102381Y82467D01*
X-102881Y82967D01*
X-103464Y83134D01*
X-106048D01*
G01X-100031Y80300D02*
X-97031Y85467D01*
G01X-95014Y80467D02*
X-92931Y85467D01*
X-90848Y80467D01*
G01X-91598Y82217D02*
X-94264D01*
G01X-104608Y110167D02*
Y105167D01*
X-101274D01*
G01X-95841D02*
Y108500D01*
G01Y107917D02*
X-96174Y108250D01*
X-96674Y108417D01*
X-97258Y108500D01*
X-97841Y108334D01*
X-98341Y108000D01*
X-98674Y107500D01*
X-98841Y106834D01*
X-98674Y106167D01*
X-98341Y105667D01*
X-97841Y105334D01*
X-97258Y105167D01*
X-96674Y105250D01*
X-96174Y105500D01*
X-95841Y105834D01*
G01X-92991Y105750D02*
X-92574Y105417D01*
X-91991Y105167D01*
X-91491D01*
X-90991Y105334D01*
X-90658Y105584D01*
X-90491Y105917D01*
X-90574Y106417D01*
X-90908Y106667D01*
X-92408Y107167D01*
X-92741Y107750D01*
X-92574Y108167D01*
X-92241Y108417D01*
X-91741Y108500D01*
X-91241Y108417D01*
X-90741Y108167D01*
G01X-87391Y107417D02*
X-84724D01*
X-84974Y108000D01*
X-85391Y108334D01*
X-85974Y108500D01*
X-86558Y108417D01*
X-87058Y108167D01*
X-87391Y107584D01*
X-87558Y107084D01*
Y106584D01*
X-87391Y106084D01*
X-86974Y105584D01*
X-86474Y105250D01*
X-85891Y105167D01*
X-85308Y105334D01*
X-84724Y105834D01*
G01X-81708Y105167D02*
Y108500D01*
G01Y107834D02*
X-81291Y108167D01*
X-80874Y108417D01*
X-80291Y108500D01*
X-79874Y108417D01*
X-79374Y108167D01*
G01X-70841Y108500D02*
X-69341Y105167D01*
X-67841Y108500D01*
G01X-63741D02*
Y105167D01*
G01Y109834D02*
X-63908Y109917D01*
Y110084D01*
X-63741Y110167D01*
X-63574Y110084D01*
Y109917D01*
X-63741Y109834D01*
G01X-56641Y105167D02*
Y108500D01*
G01Y107917D02*
X-56974Y108250D01*
X-57474Y108417D01*
X-58058Y108500D01*
X-58641Y108334D01*
X-59141Y108000D01*
X-59474Y107500D01*
X-59641Y106834D01*
X-59474Y106167D01*
X-59141Y105667D01*
X-58641Y105334D01*
X-58058Y105167D01*
X-57474Y105250D01*
X-56974Y105500D01*
X-56641Y105834D01*
G01X-48191Y105750D02*
X-47774Y105417D01*
X-47191Y105167D01*
X-46691D01*
X-46191Y105334D01*
X-45858Y105584D01*
X-45691Y105917D01*
X-45774Y106417D01*
X-46108Y106667D01*
X-47608Y107167D01*
X-47941Y107750D01*
X-47774Y108167D01*
X-47441Y108417D01*
X-46941Y108500D01*
X-46441Y108417D01*
X-45941Y108167D01*
G01X-41341Y108500D02*
Y105167D01*
G01Y109834D02*
X-41508Y109917D01*
Y110084D01*
X-41341Y110167D01*
X-41174Y110084D01*
Y109917D01*
X-41341Y109834D01*
G01X-36991Y108500D02*
X-34491D01*
X-36991Y105167D01*
X-34491D01*
G01X-31391Y107417D02*
X-28724D01*
X-28974Y108000D01*
X-29391Y108334D01*
X-29974Y108500D01*
X-30558Y108417D01*
X-31058Y108167D01*
X-31391Y107584D01*
X-31558Y107084D01*
Y106584D01*
X-31391Y106084D01*
X-30974Y105584D01*
X-30474Y105250D01*
X-29891Y105167D01*
X-29308Y105334D01*
X-28724Y105834D01*
G01X-21024Y108500D02*
X-20024Y105167D01*
X-18941Y108500D01*
X-17858Y105167D01*
X-16858Y108500D01*
G01X-13341D02*
Y105167D01*
G01Y109834D02*
X-13508Y109917D01*
Y110084D01*
X-13341Y110167D01*
X-13174Y110084D01*
Y109917D01*
X-13341Y109834D01*
G01X-7741Y110167D02*
Y105167D01*
G01X-8908Y108500D02*
X-6574D01*
G01X-3558Y105167D02*
Y110167D01*
G01Y107750D02*
X-3141Y108167D01*
X-2724Y108417D01*
X-2058Y108500D01*
X-1558Y108417D01*
X-974Y108084D01*
X-724Y107584D01*
Y105167D01*
G01X3459D02*
X2959Y105250D01*
X2459Y105584D01*
X2126Y106167D01*
X1959Y106834D01*
X2126Y107500D01*
X2459Y108084D01*
X2959Y108417D01*
X3459Y108500D01*
X3959Y108417D01*
X4459Y108084D01*
X4792Y107500D01*
X4876Y106834D01*
X4792Y106167D01*
X4459Y105584D01*
X3959Y105250D01*
X3459Y105167D01*
G01X7642Y108500D02*
Y106167D01*
X7976Y105584D01*
X8476Y105250D01*
X9059Y105167D01*
X9642Y105250D01*
X10142Y105584D01*
X10476Y106167D01*
G01Y105167D02*
Y108500D01*
G01X14659Y110167D02*
Y105167D01*
G01X13492Y108500D02*
X15826D01*
G01X24359Y103500D02*
Y108500D01*
G01Y107750D02*
X24776Y108167D01*
X25192Y108417D01*
X25859Y108500D01*
X26442Y108417D01*
X27026Y108000D01*
X27276Y107417D01*
X27359Y106834D01*
X27276Y106250D01*
X27026Y105667D01*
X26526Y105334D01*
X25859Y105167D01*
X25276Y105250D01*
X24692Y105500D01*
X24359Y105834D01*
G01X31459Y105167D02*
Y110167D01*
G01X38559Y105167D02*
Y108500D01*
G01Y107917D02*
X38226Y108250D01*
X37726Y108417D01*
X37142Y108500D01*
X36559Y108334D01*
X36059Y108000D01*
X35726Y107500D01*
X35559Y106834D01*
X35726Y106167D01*
X36059Y105667D01*
X36559Y105334D01*
X37142Y105167D01*
X37726Y105250D01*
X38226Y105500D01*
X38559Y105834D01*
G01X42659Y110167D02*
Y105167D01*
G01X41492Y108500D02*
X43826D01*
G01X48259D02*
Y105167D01*
G01Y109834D02*
X48092Y109917D01*
Y110084D01*
X48259Y110167D01*
X48426Y110084D01*
Y109917D01*
X48259Y109834D01*
G01X52442Y105167D02*
Y108500D01*
G01Y107667D02*
X52776Y108084D01*
X53276Y108417D01*
X53942Y108500D01*
X54526Y108417D01*
X55026Y108084D01*
X55276Y107500D01*
Y105167D01*
G01X58292Y103917D02*
X58876Y103584D01*
X59542Y103500D01*
X60126Y103584D01*
X60626Y104000D01*
X60959Y104584D01*
Y108500D01*
G01Y107834D02*
X60626Y108167D01*
X60126Y108417D01*
X59542Y108500D01*
X58876Y108334D01*
X58459Y108000D01*
X58126Y107417D01*
X57959Y106834D01*
X58042Y106334D01*
X58376Y105750D01*
X58876Y105334D01*
X59542Y105167D01*
X60042Y105250D01*
X60626Y105584D01*
X60959Y105917D01*
G01X70242Y103500D02*
X69409Y104334D01*
X68992Y105167D01*
Y108500D01*
X69409Y109334D01*
X70242Y110167D01*
G01X76926Y107834D02*
X77259Y108084D01*
X77509Y108500D01*
X77676Y109084D01*
X77509Y109584D01*
X77176Y109917D01*
X76592Y110167D01*
X74342D01*
Y105167D01*
X77092D01*
X77676Y105500D01*
X78009Y106000D01*
X78176Y106584D01*
X78009Y107167D01*
X77509Y107667D01*
X76926Y107834D01*
X74342D01*
G01X82276Y103500D02*
X83109Y104334D01*
X83526Y105167D01*
Y108500D01*
X83109Y109334D01*
X82276Y110167D01*
G01X-110241Y88707D02*
X189259D01*
G01X-100741Y418040D02*
Y414707D01*
G01Y419374D02*
X-100908Y419457D01*
Y419624D01*
X-100741Y419707D01*
X-100574Y419624D01*
Y419457D01*
X-100741Y419374D01*
G01X-95141Y419707D02*
Y414707D01*
G01X-96308Y418040D02*
X-93974D01*
G01X-90791Y416957D02*
X-88124D01*
X-88374Y417540D01*
X-88791Y417874D01*
X-89374Y418040D01*
X-89958Y417957D01*
X-90458Y417707D01*
X-90791Y417124D01*
X-90958Y416624D01*
Y416124D01*
X-90791Y415624D01*
X-90374Y415124D01*
X-89874Y414790D01*
X-89291Y414707D01*
X-88708Y414874D01*
X-88124Y415374D01*
G01X-86441Y414707D02*
Y418040D01*
G01Y417124D02*
X-86191Y417540D01*
X-85774Y417874D01*
X-85191Y418040D01*
X-84608Y417874D01*
X-84191Y417540D01*
X-83941Y417124D01*
Y414707D01*
G01Y417124D02*
X-83691Y417540D01*
X-83274Y417874D01*
X-82691Y418040D01*
X-82108Y417874D01*
X-81691Y417540D01*
X-81441Y417040D01*
Y414707D01*
G01X-61044Y51134D02*
X-61444Y51334D01*
X-61911Y51467D01*
X-62444D01*
X-63044Y51267D01*
X-63511Y50934D01*
X-63844Y50534D01*
X-64111Y49867D01*
X-64178Y49267D01*
X-64044Y48667D01*
X-63844Y48267D01*
X-63444Y47867D01*
X-62978Y47600D01*
X-62511Y47467D01*
X-62044D01*
X-61578Y47600D01*
X-61178Y47800D01*
X-60844Y48067D01*
G01X100092Y-313793D02*
Y-308793D01*
X102259Y-312960D01*
X104426Y-308793D01*
Y-313793D01*
G01X106442Y-310460D02*
Y-312793D01*
X106776Y-313376D01*
X107276Y-313710D01*
X107859Y-313793D01*
X108442Y-313710D01*
X108942Y-313376D01*
X109276Y-312793D01*
G01Y-313793D02*
Y-310460D01*
G01X112209Y-313210D02*
X112626Y-313543D01*
X113209Y-313793D01*
X113709D01*
X114209Y-313626D01*
X114542Y-313376D01*
X114709Y-313043D01*
X114626Y-312543D01*
X114292Y-312293D01*
X112792Y-311793D01*
X112459Y-311210D01*
X112626Y-310793D01*
X112959Y-310543D01*
X113459Y-310460D01*
X113959Y-310543D01*
X114459Y-310793D01*
G01X119059Y-308793D02*
Y-313793D01*
G01X117892Y-310460D02*
X120226D01*
G01X129759Y-313793D02*
Y-309543D01*
X129926Y-309126D01*
X130259Y-308876D01*
X130759Y-308793D01*
X131259Y-308960D01*
X131509Y-309376D01*
G01X130509Y-310793D02*
X128842D01*
G01X135859Y-313793D02*
X135359Y-313710D01*
X134859Y-313376D01*
X134526Y-312793D01*
X134359Y-312126D01*
X134526Y-311460D01*
X134859Y-310876D01*
X135359Y-310543D01*
X135859Y-310460D01*
X136359Y-310543D01*
X136859Y-310876D01*
X137192Y-311460D01*
X137276Y-312126D01*
X137192Y-312793D01*
X136859Y-313376D01*
X136359Y-313710D01*
X135859Y-313793D01*
G01X141459D02*
Y-308793D01*
G01X147059Y-313793D02*
Y-308793D01*
G01X152659Y-313793D02*
X152159Y-313710D01*
X151659Y-313376D01*
X151326Y-312793D01*
X151159Y-312126D01*
X151326Y-311460D01*
X151659Y-310876D01*
X152159Y-310543D01*
X152659Y-310460D01*
X153159Y-310543D01*
X153659Y-310876D01*
X153992Y-311460D01*
X154076Y-312126D01*
X153992Y-312793D01*
X153659Y-313376D01*
X153159Y-313710D01*
X152659Y-313793D01*
G01X156176Y-310460D02*
X157176Y-313793D01*
X158259Y-310460D01*
X159342Y-313793D01*
X160342Y-310460D01*
G01X90259Y-318293D02*
Y189207D01*
G01X102259Y-277293D02*
X101592Y-277460D01*
X101092Y-277876D01*
X100759Y-278376D01*
X100509Y-279043D01*
X100426Y-279793D01*
X100509Y-280543D01*
X100759Y-281210D01*
X101092Y-281710D01*
X101592Y-282126D01*
X102259Y-282293D01*
X102926Y-282126D01*
X103426Y-281710D01*
X103759Y-281210D01*
X104009Y-280543D01*
X104092Y-279793D01*
X104009Y-279043D01*
X103759Y-278376D01*
X103426Y-277876D01*
X102926Y-277460D01*
X102259Y-277293D01*
G01X107859Y-282460D02*
X107692Y-282376D01*
Y-282210D01*
X107859Y-282126D01*
X108026Y-282210D01*
Y-282376D01*
X107859Y-282460D01*
G01X111626Y-281293D02*
X112126Y-281876D01*
X112792Y-282210D01*
X113542Y-282293D01*
X114209Y-282210D01*
X114876Y-281793D01*
X115292Y-281293D01*
X115376Y-280793D01*
X115209Y-280210D01*
X114626Y-279793D01*
X114042Y-279626D01*
X113292D01*
G01X114042D02*
X114542Y-279376D01*
X114959Y-278960D01*
X115126Y-278460D01*
X114959Y-277960D01*
X114542Y-277543D01*
X113792Y-277293D01*
X113042Y-277376D01*
X112292Y-277710D01*
G01X116559Y-280626D02*
X117392Y-278960D01*
X118226D01*
X119892Y-282293D01*
X120726D01*
X121559Y-280626D01*
G01X124659Y-277293D02*
X123992Y-277460D01*
X123492Y-277876D01*
X123159Y-278376D01*
X122909Y-279043D01*
X122826Y-279793D01*
X122909Y-280543D01*
X123159Y-281210D01*
X123492Y-281710D01*
X123992Y-282126D01*
X124659Y-282293D01*
X125326Y-282126D01*
X125826Y-281710D01*
X126159Y-281210D01*
X126409Y-280543D01*
X126492Y-279793D01*
X126409Y-279043D01*
X126159Y-278376D01*
X125826Y-277876D01*
X125326Y-277460D01*
X124659Y-277293D01*
G01X130259Y-282460D02*
X130092Y-282376D01*
Y-282210D01*
X130259Y-282126D01*
X130426Y-282210D01*
Y-282376D01*
X130259Y-282460D01*
G01X135692Y-282293D02*
X135859Y-281210D01*
X136109Y-280293D01*
X136442Y-279460D01*
X136859Y-278543D01*
X137526Y-277293D01*
X134192D01*
G01X138959Y-282293D02*
Y-278960D01*
G01Y-279876D02*
X139209Y-279460D01*
X139626Y-279126D01*
X140209Y-278960D01*
X140792Y-279126D01*
X141209Y-279460D01*
X141459Y-279876D01*
Y-282293D01*
G01Y-279876D02*
X141709Y-279460D01*
X142126Y-279126D01*
X142709Y-278960D01*
X143292Y-279126D01*
X143709Y-279460D01*
X143959Y-279960D01*
Y-282293D01*
G01X147059Y-278960D02*
Y-282293D01*
G01Y-277626D02*
X146892Y-277543D01*
Y-277376D01*
X147059Y-277293D01*
X147226Y-277376D01*
Y-277543D01*
X147059Y-277626D01*
G01X152659Y-282293D02*
Y-277293D01*
G01X102259Y-263793D02*
X101592Y-263960D01*
X101092Y-264376D01*
X100759Y-264876D01*
X100509Y-265543D01*
X100426Y-266293D01*
X100509Y-267043D01*
X100759Y-267710D01*
X101092Y-268210D01*
X101592Y-268626D01*
X102259Y-268793D01*
X102926Y-268626D01*
X103426Y-268210D01*
X103759Y-267710D01*
X104009Y-267043D01*
X104092Y-266293D01*
X104009Y-265543D01*
X103759Y-264876D01*
X103426Y-264376D01*
X102926Y-263960D01*
X102259Y-263793D01*
G01X107859Y-268960D02*
X107692Y-268876D01*
Y-268710D01*
X107859Y-268626D01*
X108026Y-268710D01*
Y-268876D01*
X107859Y-268960D01*
G01X111626Y-267793D02*
X112126Y-268376D01*
X112792Y-268710D01*
X113542Y-268793D01*
X114209Y-268710D01*
X114876Y-268293D01*
X115292Y-267793D01*
X115376Y-267293D01*
X115209Y-266710D01*
X114626Y-266293D01*
X114042Y-266126D01*
X113292D01*
G01X114042D02*
X114542Y-265876D01*
X114959Y-265460D01*
X115126Y-264960D01*
X114959Y-264460D01*
X114542Y-264043D01*
X113792Y-263793D01*
X113042Y-263876D01*
X112292Y-264210D01*
G01X116559Y-267126D02*
X117392Y-265460D01*
X118226D01*
X119892Y-268793D01*
X120726D01*
X121559Y-267126D01*
G01X124659Y-263793D02*
X123992Y-263960D01*
X123492Y-264376D01*
X123159Y-264876D01*
X122909Y-265543D01*
X122826Y-266293D01*
X122909Y-267043D01*
X123159Y-267710D01*
X123492Y-268210D01*
X123992Y-268626D01*
X124659Y-268793D01*
X125326Y-268626D01*
X125826Y-268210D01*
X126159Y-267710D01*
X126409Y-267043D01*
X126492Y-266293D01*
X126409Y-265543D01*
X126159Y-264876D01*
X125826Y-264376D01*
X125326Y-263960D01*
X124659Y-263793D01*
G01X130259Y-268960D02*
X130092Y-268876D01*
Y-268710D01*
X130259Y-268626D01*
X130426Y-268710D01*
Y-268876D01*
X130259Y-268960D01*
G01X135692Y-268793D02*
X135859Y-267710D01*
X136109Y-266793D01*
X136442Y-265960D01*
X136859Y-265043D01*
X137526Y-263793D01*
X134192D01*
G01X138959Y-268793D02*
Y-265460D01*
G01Y-266376D02*
X139209Y-265960D01*
X139626Y-265626D01*
X140209Y-265460D01*
X140792Y-265626D01*
X141209Y-265960D01*
X141459Y-266376D01*
Y-268793D01*
G01Y-266376D02*
X141709Y-265960D01*
X142126Y-265626D01*
X142709Y-265460D01*
X143292Y-265626D01*
X143709Y-265960D01*
X143959Y-266460D01*
Y-268793D01*
G01X147059Y-265460D02*
Y-268793D01*
G01Y-264126D02*
X146892Y-264043D01*
Y-263876D01*
X147059Y-263793D01*
X147226Y-263876D01*
Y-264043D01*
X147059Y-264126D01*
G01X152659Y-268793D02*
Y-263793D01*
G01X103926Y-297293D02*
X100592Y-295626D01*
X103926Y-293960D01*
G01X106776Y-296376D02*
X108942D01*
G01Y-294876D02*
X106776D01*
G01X113459Y-297293D02*
Y-292293D01*
X112459Y-293293D01*
G01Y-297293D02*
X114459D01*
G01X119059Y-297460D02*
X118892Y-297376D01*
Y-297210D01*
X119059Y-297126D01*
X119226Y-297210D01*
Y-297376D01*
X119059Y-297460D01*
G01X125659Y-297293D02*
Y-292293D01*
X122576Y-295876D01*
X126742D01*
G01X127759Y-297293D02*
Y-293960D01*
G01Y-294876D02*
X128009Y-294460D01*
X128426Y-294126D01*
X129009Y-293960D01*
X129592Y-294126D01*
X130009Y-294460D01*
X130259Y-294876D01*
Y-297293D01*
G01Y-294876D02*
X130509Y-294460D01*
X130926Y-294126D01*
X131509Y-293960D01*
X132092Y-294126D01*
X132509Y-294460D01*
X132759Y-294960D01*
Y-297293D01*
G01X135859Y-293960D02*
Y-297293D01*
G01Y-292626D02*
X135692Y-292543D01*
Y-292376D01*
X135859Y-292293D01*
X136026Y-292376D01*
Y-292543D01*
X135859Y-292626D01*
G01X141459Y-297293D02*
Y-292293D01*
G01X101342Y-250626D02*
X103342D01*
G01X102259Y-249543D02*
Y-251710D01*
G01X106359Y-252460D02*
X109359Y-247293D01*
G01X112376Y-250626D02*
X114542D01*
G01X119059Y-252293D02*
Y-247293D01*
X118059Y-248293D01*
G01Y-252293D02*
X120059D01*
G01X122159D02*
Y-248960D01*
G01Y-249876D02*
X122409Y-249460D01*
X122826Y-249126D01*
X123409Y-248960D01*
X123992Y-249126D01*
X124409Y-249460D01*
X124659Y-249876D01*
Y-252293D01*
G01Y-249876D02*
X124909Y-249460D01*
X125326Y-249126D01*
X125909Y-248960D01*
X126492Y-249126D01*
X126909Y-249460D01*
X127159Y-249960D01*
Y-252293D01*
G01X130259Y-248960D02*
Y-252293D01*
G01Y-247626D02*
X130092Y-247543D01*
Y-247376D01*
X130259Y-247293D01*
X130426Y-247376D01*
Y-247543D01*
X130259Y-247626D01*
G01X135859Y-252293D02*
Y-247293D01*
G01X101342Y-235626D02*
X103342D01*
G01X102259Y-234543D02*
Y-236710D01*
G01X106359Y-237460D02*
X109359Y-232293D01*
G01X112376Y-235626D02*
X114542D01*
G01X117476Y-233126D02*
X117976Y-232626D01*
X118559Y-232376D01*
X119226Y-232293D01*
X120059Y-232460D01*
X120642Y-232876D01*
X120809Y-233376D01*
X120726Y-233876D01*
X120392Y-234293D01*
X118726Y-235126D01*
X117976Y-235710D01*
X117476Y-236543D01*
X117309Y-237293D01*
X120809D01*
G01X122159D02*
Y-233960D01*
G01Y-234876D02*
X122409Y-234460D01*
X122826Y-234126D01*
X123409Y-233960D01*
X123992Y-234126D01*
X124409Y-234460D01*
X124659Y-234876D01*
Y-237293D01*
G01Y-234876D02*
X124909Y-234460D01*
X125326Y-234126D01*
X125909Y-233960D01*
X126492Y-234126D01*
X126909Y-234460D01*
X127159Y-234960D01*
Y-237293D01*
G01X130259Y-233960D02*
Y-237293D01*
G01Y-232626D02*
X130092Y-232543D01*
Y-232376D01*
X130259Y-232293D01*
X130426Y-232376D01*
Y-232543D01*
X130259Y-232626D01*
G01X135859Y-237293D02*
Y-232293D01*
G01X101342Y-224126D02*
X103342D01*
G01X102259Y-223043D02*
Y-225210D01*
G01X106359Y-225960D02*
X109359Y-220793D01*
G01X112376Y-224126D02*
X114542D01*
G01X119059Y-225793D02*
Y-220793D01*
X118059Y-221793D01*
G01Y-225793D02*
X120059D01*
G01X122159D02*
Y-222460D01*
G01Y-223376D02*
X122409Y-222960D01*
X122826Y-222626D01*
X123409Y-222460D01*
X123992Y-222626D01*
X124409Y-222960D01*
X124659Y-223376D01*
Y-225793D01*
G01Y-223376D02*
X124909Y-222960D01*
X125326Y-222626D01*
X125909Y-222460D01*
X126492Y-222626D01*
X126909Y-222960D01*
X127159Y-223460D01*
Y-225793D01*
G01X130259Y-222460D02*
Y-225793D01*
G01Y-221126D02*
X130092Y-221043D01*
Y-220876D01*
X130259Y-220793D01*
X130426Y-220876D01*
Y-221043D01*
X130259Y-221126D01*
G01X135859Y-225793D02*
Y-220793D01*
G01X101342Y-165626D02*
X103342D01*
G01X102259Y-164543D02*
Y-166710D01*
G01X106359Y-167460D02*
X109359Y-162293D01*
G01X112376Y-165626D02*
X114542D01*
G01X119059Y-167293D02*
Y-162293D01*
X118059Y-163293D01*
G01Y-167293D02*
X120059D01*
G01X122159D02*
Y-163960D01*
G01Y-164876D02*
X122409Y-164460D01*
X122826Y-164126D01*
X123409Y-163960D01*
X123992Y-164126D01*
X124409Y-164460D01*
X124659Y-164876D01*
Y-167293D01*
G01Y-164876D02*
X124909Y-164460D01*
X125326Y-164126D01*
X125909Y-163960D01*
X126492Y-164126D01*
X126909Y-164460D01*
X127159Y-164960D01*
Y-167293D01*
G01X130259Y-163960D02*
Y-167293D01*
G01Y-162626D02*
X130092Y-162543D01*
Y-162376D01*
X130259Y-162293D01*
X130426Y-162376D01*
Y-162543D01*
X130259Y-162626D01*
G01X135859Y-167293D02*
Y-162293D01*
G01X101342Y-180626D02*
X103342D01*
G01X102259Y-179543D02*
Y-181710D01*
G01X106359Y-182460D02*
X109359Y-177293D01*
G01X112376Y-180626D02*
X114542D01*
G01X119059Y-182293D02*
Y-177293D01*
X118059Y-178293D01*
G01Y-182293D02*
X120059D01*
G01X122826Y-181543D02*
X123326Y-181960D01*
X123909Y-182210D01*
X124659Y-182293D01*
X125409Y-182126D01*
X125992Y-181793D01*
X126409Y-181210D01*
X126492Y-180543D01*
X126326Y-179876D01*
X125909Y-179460D01*
X125326Y-179126D01*
X124742Y-179043D01*
X124159Y-179126D01*
X123409Y-179460D01*
X123659Y-177293D01*
X125909D01*
G01X128759Y-182460D02*
X131759Y-177293D01*
G01X128759D02*
X128259Y-177460D01*
X128009Y-177710D01*
X127842Y-178210D01*
X128009Y-178710D01*
X128259Y-178960D01*
X128759Y-179126D01*
X129259Y-178960D01*
X129509Y-178710D01*
X129676Y-178210D01*
X129509Y-177710D01*
X129259Y-177460D01*
X128759Y-177293D01*
G01X131759Y-180626D02*
X131259Y-180793D01*
X131009Y-181043D01*
X130842Y-181543D01*
X131009Y-182043D01*
X131259Y-182293D01*
X131759Y-182460D01*
X132259Y-182293D01*
X132509Y-182043D01*
X132676Y-181543D01*
X132509Y-181043D01*
X132259Y-180793D01*
X131759Y-180626D01*
G01X101342Y-200126D02*
X103342D01*
G01X102259Y-199043D02*
Y-201210D01*
G01X106359Y-201960D02*
X109359Y-196793D01*
G01X112376Y-200126D02*
X114542D01*
G01X117476Y-197626D02*
X117976Y-197126D01*
X118559Y-196876D01*
X119226Y-196793D01*
X120059Y-196960D01*
X120642Y-197376D01*
X120809Y-197876D01*
X120726Y-198376D01*
X120392Y-198793D01*
X118726Y-199626D01*
X117976Y-200210D01*
X117476Y-201043D01*
X117309Y-201793D01*
X120809D01*
G01X122159D02*
Y-198460D01*
G01Y-199376D02*
X122409Y-198960D01*
X122826Y-198626D01*
X123409Y-198460D01*
X123992Y-198626D01*
X124409Y-198960D01*
X124659Y-199376D01*
Y-201793D01*
G01Y-199376D02*
X124909Y-198960D01*
X125326Y-198626D01*
X125909Y-198460D01*
X126492Y-198626D01*
X126909Y-198960D01*
X127159Y-199460D01*
Y-201793D01*
G01X130259Y-198460D02*
Y-201793D01*
G01Y-197126D02*
X130092Y-197043D01*
Y-196876D01*
X130259Y-196793D01*
X130426Y-196876D01*
Y-197043D01*
X130259Y-197126D01*
G01X135859Y-201793D02*
Y-196793D01*
G01X100592Y-82293D02*
X103926Y-80626D01*
X100592Y-78960D01*
G01X106776Y-81376D02*
X108942D01*
G01Y-79876D02*
X106776D01*
G01X113459Y-82293D02*
Y-77293D01*
X112459Y-78293D01*
G01Y-82293D02*
X114459D01*
G01X119059Y-82460D02*
X118892Y-82376D01*
Y-82210D01*
X119059Y-82126D01*
X119226Y-82210D01*
Y-82376D01*
X119059Y-82460D01*
G01X122826Y-81293D02*
X123326Y-81876D01*
X123992Y-82210D01*
X124742Y-82293D01*
X125409Y-82210D01*
X126076Y-81793D01*
X126492Y-81293D01*
X126576Y-80793D01*
X126409Y-80210D01*
X125826Y-79793D01*
X125242Y-79626D01*
X124492D01*
G01X125242D02*
X125742Y-79376D01*
X126159Y-78960D01*
X126326Y-78460D01*
X126159Y-77960D01*
X125742Y-77543D01*
X124992Y-77293D01*
X124242Y-77376D01*
X123492Y-77710D01*
G01X127759Y-82293D02*
Y-78960D01*
G01Y-79876D02*
X128009Y-79460D01*
X128426Y-79126D01*
X129009Y-78960D01*
X129592Y-79126D01*
X130009Y-79460D01*
X130259Y-79876D01*
Y-82293D01*
G01Y-79876D02*
X130509Y-79460D01*
X130926Y-79126D01*
X131509Y-78960D01*
X132092Y-79126D01*
X132509Y-79460D01*
X132759Y-79960D01*
Y-82293D01*
G01X135859Y-78960D02*
Y-82293D01*
G01Y-77626D02*
X135692Y-77543D01*
Y-77376D01*
X135859Y-77293D01*
X136026Y-77376D01*
Y-77543D01*
X135859Y-77626D01*
G01X141459Y-82293D02*
Y-77293D01*
G01X100592Y-104793D02*
X103926Y-103126D01*
X100592Y-101460D01*
G01X106776Y-103876D02*
X108942D01*
G01Y-102376D02*
X106776D01*
G01X113459Y-104793D02*
Y-99793D01*
X112459Y-100793D01*
G01Y-104793D02*
X114459D01*
G01X119059Y-104960D02*
X118892Y-104876D01*
Y-104710D01*
X119059Y-104626D01*
X119226Y-104710D01*
Y-104876D01*
X119059Y-104960D01*
G01X122826Y-104043D02*
X123326Y-104460D01*
X123909Y-104710D01*
X124659Y-104793D01*
X125409Y-104626D01*
X125992Y-104293D01*
X126409Y-103710D01*
X126492Y-103043D01*
X126326Y-102376D01*
X125909Y-101960D01*
X125326Y-101626D01*
X124742Y-101543D01*
X124159Y-101626D01*
X123409Y-101960D01*
X123659Y-99793D01*
X125909D01*
G01X127759Y-104793D02*
Y-101460D01*
G01Y-102376D02*
X128009Y-101960D01*
X128426Y-101626D01*
X129009Y-101460D01*
X129592Y-101626D01*
X130009Y-101960D01*
X130259Y-102376D01*
Y-104793D01*
G01Y-102376D02*
X130509Y-101960D01*
X130926Y-101626D01*
X131509Y-101460D01*
X132092Y-101626D01*
X132509Y-101960D01*
X132759Y-102460D01*
Y-104793D01*
G01X135859Y-101460D02*
Y-104793D01*
G01Y-100126D02*
X135692Y-100043D01*
Y-99876D01*
X135859Y-99793D01*
X136026Y-99876D01*
Y-100043D01*
X135859Y-100126D01*
G01X141459Y-104793D02*
Y-99793D01*
G01X100592Y-122293D02*
X103926Y-120626D01*
X100592Y-118960D01*
G01X106776Y-121376D02*
X108942D01*
G01Y-119876D02*
X106776D01*
G01X113459Y-122293D02*
Y-117293D01*
X112459Y-118293D01*
G01Y-122293D02*
X114459D01*
G01X119059Y-122460D02*
X118892Y-122376D01*
Y-122210D01*
X119059Y-122126D01*
X119226Y-122210D01*
Y-122376D01*
X119059Y-122460D01*
G01X124659Y-117293D02*
X123992Y-117460D01*
X123492Y-117876D01*
X123159Y-118376D01*
X122909Y-119043D01*
X122826Y-119793D01*
X122909Y-120543D01*
X123159Y-121210D01*
X123492Y-121710D01*
X123992Y-122126D01*
X124659Y-122293D01*
X125326Y-122126D01*
X125826Y-121710D01*
X126159Y-121210D01*
X126409Y-120543D01*
X126492Y-119793D01*
X126409Y-119043D01*
X126159Y-118376D01*
X125826Y-117876D01*
X125326Y-117460D01*
X124659Y-117293D01*
G01X127759Y-122293D02*
Y-118960D01*
G01Y-119876D02*
X128009Y-119460D01*
X128426Y-119126D01*
X129009Y-118960D01*
X129592Y-119126D01*
X130009Y-119460D01*
X130259Y-119876D01*
Y-122293D01*
G01Y-119876D02*
X130509Y-119460D01*
X130926Y-119126D01*
X131509Y-118960D01*
X132092Y-119126D01*
X132509Y-119460D01*
X132759Y-119960D01*
Y-122293D01*
G01X135859Y-118960D02*
Y-122293D01*
G01Y-117626D02*
X135692Y-117543D01*
Y-117376D01*
X135859Y-117293D01*
X136026Y-117376D01*
Y-117543D01*
X135859Y-117626D01*
G01X141459Y-122293D02*
Y-117293D01*
G01X101342Y-150626D02*
X103342D01*
G01X102259Y-149543D02*
Y-151710D01*
G01X106359Y-152460D02*
X109359Y-147293D01*
G01X112376Y-150626D02*
X114542D01*
G01X117476Y-148126D02*
X117976Y-147626D01*
X118559Y-147376D01*
X119226Y-147293D01*
X120059Y-147460D01*
X120642Y-147876D01*
X120809Y-148376D01*
X120726Y-148876D01*
X120392Y-149293D01*
X118726Y-150126D01*
X117976Y-150710D01*
X117476Y-151543D01*
X117309Y-152293D01*
X120809D01*
G01X124659Y-147293D02*
X123992Y-147460D01*
X123492Y-147876D01*
X123159Y-148376D01*
X122909Y-149043D01*
X122826Y-149793D01*
X122909Y-150543D01*
X123159Y-151210D01*
X123492Y-151710D01*
X123992Y-152126D01*
X124659Y-152293D01*
X125326Y-152126D01*
X125826Y-151710D01*
X126159Y-151210D01*
X126409Y-150543D01*
X126492Y-149793D01*
X126409Y-149043D01*
X126159Y-148376D01*
X125826Y-147876D01*
X125326Y-147460D01*
X124659Y-147293D01*
G01X128759Y-152460D02*
X131759Y-147293D01*
G01X128759D02*
X128259Y-147460D01*
X128009Y-147710D01*
X127842Y-148210D01*
X128009Y-148710D01*
X128259Y-148960D01*
X128759Y-149126D01*
X129259Y-148960D01*
X129509Y-148710D01*
X129676Y-148210D01*
X129509Y-147710D01*
X129259Y-147460D01*
X128759Y-147293D01*
G01X131759Y-150626D02*
X131259Y-150793D01*
X131009Y-151043D01*
X130842Y-151543D01*
X131009Y-152043D01*
X131259Y-152293D01*
X131759Y-152460D01*
X132259Y-152293D01*
X132509Y-152043D01*
X132676Y-151543D01*
X132509Y-151043D01*
X132259Y-150793D01*
X131759Y-150626D01*
G01X101342Y-135626D02*
X103342D01*
G01X102259Y-134543D02*
Y-136710D01*
G01X106359Y-137460D02*
X109359Y-132293D01*
G01X112376Y-135626D02*
X114542D01*
G01X117226Y-136293D02*
X117726Y-136876D01*
X118392Y-137210D01*
X119142Y-137293D01*
X119809Y-137210D01*
X120476Y-136793D01*
X120892Y-136293D01*
X120976Y-135793D01*
X120809Y-135210D01*
X120226Y-134793D01*
X119642Y-134626D01*
X118892D01*
G01X119642D02*
X120142Y-134376D01*
X120559Y-133960D01*
X120726Y-133460D01*
X120559Y-132960D01*
X120142Y-132543D01*
X119392Y-132293D01*
X118642Y-132376D01*
X117892Y-132710D01*
G01X122159Y-137293D02*
Y-133960D01*
G01Y-134876D02*
X122409Y-134460D01*
X122826Y-134126D01*
X123409Y-133960D01*
X123992Y-134126D01*
X124409Y-134460D01*
X124659Y-134876D01*
Y-137293D01*
G01Y-134876D02*
X124909Y-134460D01*
X125326Y-134126D01*
X125909Y-133960D01*
X126492Y-134126D01*
X126909Y-134460D01*
X127159Y-134960D01*
Y-137293D01*
G01X130259Y-133960D02*
Y-137293D01*
G01Y-132626D02*
X130092Y-132543D01*
Y-132376D01*
X130259Y-132293D01*
X130426Y-132376D01*
Y-132543D01*
X130259Y-132626D01*
G01X135859Y-137293D02*
Y-132293D01*
G01X107736Y-48303D02*
X104402Y-46636D01*
X107736Y-44970D01*
G01X111669Y-43303D02*
X111002Y-43470D01*
X110502Y-43886D01*
X110169Y-44386D01*
X109919Y-45053D01*
X109836Y-45803D01*
X109919Y-46553D01*
X110169Y-47220D01*
X110502Y-47720D01*
X111002Y-48136D01*
X111669Y-48303D01*
X112336Y-48136D01*
X112836Y-47720D01*
X113169Y-47220D01*
X113419Y-46553D01*
X113502Y-45803D01*
X113419Y-45053D01*
X113169Y-44386D01*
X112836Y-43886D01*
X112336Y-43470D01*
X111669Y-43303D01*
G01X117269Y-48470D02*
X117102Y-48386D01*
Y-48220D01*
X117269Y-48136D01*
X117436Y-48220D01*
Y-48386D01*
X117269Y-48470D01*
G01X121036Y-47303D02*
X121536Y-47886D01*
X122202Y-48220D01*
X122952Y-48303D01*
X123619Y-48220D01*
X124286Y-47803D01*
X124702Y-47303D01*
X124786Y-46803D01*
X124619Y-46220D01*
X124036Y-45803D01*
X123452Y-45636D01*
X122702D01*
G01X123452D02*
X123952Y-45386D01*
X124369Y-44970D01*
X124536Y-44470D01*
X124369Y-43970D01*
X123952Y-43553D01*
X123202Y-43303D01*
X122452Y-43386D01*
X121702Y-43720D01*
G01X125969Y-48303D02*
Y-44970D01*
G01Y-45886D02*
X126219Y-45470D01*
X126636Y-45136D01*
X127219Y-44970D01*
X127802Y-45136D01*
X128219Y-45470D01*
X128469Y-45886D01*
Y-48303D01*
G01Y-45886D02*
X128719Y-45470D01*
X129136Y-45136D01*
X129719Y-44970D01*
X130302Y-45136D01*
X130719Y-45470D01*
X130969Y-45970D01*
Y-48303D01*
G01X134069Y-44970D02*
Y-48303D01*
G01Y-43636D02*
X133902Y-43553D01*
Y-43386D01*
X134069Y-43303D01*
X134236Y-43386D01*
Y-43553D01*
X134069Y-43636D01*
G01X139669Y-48303D02*
Y-43303D01*
G01X96879Y61677D02*
Y65010D01*
G01Y64094D02*
X97129Y64510D01*
X97546Y64844D01*
X98129Y65010D01*
X98712Y64844D01*
X99129Y64510D01*
X99379Y64094D01*
Y61677D01*
G01Y64094D02*
X99629Y64510D01*
X100046Y64844D01*
X100629Y65010D01*
X101212Y64844D01*
X101629Y64510D01*
X101879Y64010D01*
Y61677D01*
G01X103562Y65010D02*
Y62677D01*
X103896Y62094D01*
X104396Y61760D01*
X104979Y61677D01*
X105562Y61760D01*
X106062Y62094D01*
X106396Y62677D01*
G01Y61677D02*
Y65010D01*
G01X109329Y62260D02*
X109746Y61927D01*
X110329Y61677D01*
X110829D01*
X111329Y61844D01*
X111662Y62094D01*
X111829Y62427D01*
X111746Y62927D01*
X111412Y63177D01*
X109912Y63677D01*
X109579Y64260D01*
X109746Y64677D01*
X110079Y64927D01*
X110579Y65010D01*
X111079Y64927D01*
X111579Y64677D01*
G01X116179Y66677D02*
Y61677D01*
G01X115012Y65010D02*
X117346D01*
G01X123446Y61677D02*
X120112Y63344D01*
X123446Y65010D01*
G01X125296Y61677D02*
X127379Y66677D01*
X129462Y61677D01*
G01X128712Y63427D02*
X126046D01*
G01X140079Y66677D02*
Y61677D01*
G01Y62427D02*
X139746Y62010D01*
X139246Y61760D01*
X138662Y61677D01*
X137996Y61844D01*
X137496Y62260D01*
X137162Y62760D01*
X137079Y63344D01*
X137162Y63927D01*
X137496Y64427D01*
X137996Y64844D01*
X138662Y65010D01*
X139246Y64927D01*
X139662Y64760D01*
X140079Y64427D01*
G01X144179Y65010D02*
Y61677D01*
G01Y66344D02*
X144012Y66427D01*
Y66594D01*
X144179Y66677D01*
X144346Y66594D01*
Y66427D01*
X144179Y66344D01*
G01X151279Y61677D02*
Y65010D01*
G01Y64427D02*
X150946Y64760D01*
X150446Y64927D01*
X149862Y65010D01*
X149279Y64844D01*
X148779Y64510D01*
X148446Y64010D01*
X148279Y63344D01*
X148446Y62677D01*
X148779Y62177D01*
X149279Y61844D01*
X149862Y61677D01*
X150446Y61760D01*
X150946Y62010D01*
X151279Y62344D01*
G01X152879Y61677D02*
Y65010D01*
G01Y64094D02*
X153129Y64510D01*
X153546Y64844D01*
X154129Y65010D01*
X154712Y64844D01*
X155129Y64510D01*
X155379Y64094D01*
Y61677D01*
G01Y64094D02*
X155629Y64510D01*
X156046Y64844D01*
X156629Y65010D01*
X157212Y64844D01*
X157629Y64510D01*
X157879Y64010D01*
Y61677D01*
G01X159729Y63927D02*
X162396D01*
X162146Y64510D01*
X161729Y64844D01*
X161146Y65010D01*
X160562Y64927D01*
X160062Y64677D01*
X159729Y64094D01*
X159562Y63594D01*
Y63094D01*
X159729Y62594D01*
X160146Y62094D01*
X160646Y61760D01*
X161229Y61677D01*
X161812Y61844D01*
X162396Y62344D01*
G01X166579Y66677D02*
Y61677D01*
G01X165412Y65010D02*
X167746D01*
G01X170929Y63927D02*
X173596D01*
X173346Y64510D01*
X172929Y64844D01*
X172346Y65010D01*
X171762Y64927D01*
X171262Y64677D01*
X170929Y64094D01*
X170762Y63594D01*
Y63094D01*
X170929Y62594D01*
X171346Y62094D01*
X171846Y61760D01*
X172429Y61677D01*
X173012Y61844D01*
X173596Y62344D01*
G01X176612Y61677D02*
Y65010D01*
G01Y64344D02*
X177029Y64677D01*
X177446Y64927D01*
X178029Y65010D01*
X178446Y64927D01*
X178946Y64677D01*
G01X97459Y70447D02*
Y75447D01*
G01Y72947D02*
X97876Y73447D01*
X98376Y73697D01*
X98876Y73780D01*
X99626Y73614D01*
X100126Y73280D01*
X100459Y72697D01*
Y72030D01*
X100292Y71364D01*
X99959Y70864D01*
X99376Y70530D01*
X98876Y70447D01*
X98376Y70530D01*
X97876Y70780D01*
X97459Y71197D01*
G01X103142Y73780D02*
Y71447D01*
X103476Y70864D01*
X103976Y70530D01*
X104559Y70447D01*
X105142Y70530D01*
X105642Y70864D01*
X105976Y71447D01*
G01Y70447D02*
Y73780D01*
G01X110159Y75447D02*
Y70447D01*
G01X108992Y73780D02*
X111326D01*
G01X122026Y73114D02*
X122359Y73364D01*
X122609Y73780D01*
X122776Y74364D01*
X122609Y74864D01*
X122276Y75197D01*
X121692Y75447D01*
X119442D01*
Y70447D01*
X122192D01*
X122776Y70780D01*
X123109Y71280D01*
X123276Y71864D01*
X123109Y72447D01*
X122609Y72947D01*
X122026Y73114D01*
X119442D01*
G01X134059Y75447D02*
Y70447D01*
G01Y71197D02*
X133726Y70780D01*
X133226Y70530D01*
X132642Y70447D01*
X131976Y70614D01*
X131476Y71030D01*
X131142Y71530D01*
X131059Y72114D01*
X131142Y72697D01*
X131476Y73197D01*
X131976Y73614D01*
X132642Y73780D01*
X133226Y73697D01*
X133642Y73530D01*
X134059Y73197D01*
G01X138159Y73780D02*
Y70447D01*
G01Y75114D02*
X137992Y75197D01*
Y75364D01*
X138159Y75447D01*
X138326Y75364D01*
Y75197D01*
X138159Y75114D01*
G01X145259Y70447D02*
Y73780D01*
G01Y73197D02*
X144926Y73530D01*
X144426Y73697D01*
X143842Y73780D01*
X143259Y73614D01*
X142759Y73280D01*
X142426Y72780D01*
X142259Y72114D01*
X142426Y71447D01*
X142759Y70947D01*
X143259Y70614D01*
X143842Y70447D01*
X144426Y70530D01*
X144926Y70780D01*
X145259Y71114D01*
G01X146859Y70447D02*
Y73780D01*
G01Y72864D02*
X147109Y73280D01*
X147526Y73614D01*
X148109Y73780D01*
X148692Y73614D01*
X149109Y73280D01*
X149359Y72864D01*
Y70447D01*
G01Y72864D02*
X149609Y73280D01*
X150026Y73614D01*
X150609Y73780D01*
X151192Y73614D01*
X151609Y73280D01*
X151859Y72780D01*
Y70447D01*
G01X153709Y72697D02*
X156376D01*
X156126Y73280D01*
X155709Y73614D01*
X155126Y73780D01*
X154542Y73697D01*
X154042Y73447D01*
X153709Y72864D01*
X153542Y72364D01*
Y71864D01*
X153709Y71364D01*
X154126Y70864D01*
X154626Y70530D01*
X155209Y70447D01*
X155792Y70614D01*
X156376Y71114D01*
G01X160559Y75447D02*
Y70447D01*
G01X159392Y73780D02*
X161726D01*
G01X164909Y72697D02*
X167576D01*
X167326Y73280D01*
X166909Y73614D01*
X166326Y73780D01*
X165742Y73697D01*
X165242Y73447D01*
X164909Y72864D01*
X164742Y72364D01*
Y71864D01*
X164909Y71364D01*
X165326Y70864D01*
X165826Y70530D01*
X166409Y70447D01*
X166992Y70614D01*
X167576Y71114D01*
G01X170592Y70447D02*
Y73780D01*
G01Y73114D02*
X171009Y73447D01*
X171426Y73697D01*
X172009Y73780D01*
X172426Y73697D01*
X172926Y73447D01*
G01X107136Y6887D02*
X103802Y8554D01*
X107136Y10220D01*
G01X111069Y6887D02*
Y11887D01*
X110069Y10887D01*
G01Y6887D02*
X112069D01*
G01X114169D02*
Y10220D01*
G01Y9304D02*
X114419Y9720D01*
X114836Y10054D01*
X115419Y10220D01*
X116002Y10054D01*
X116419Y9720D01*
X116669Y9304D01*
Y6887D01*
G01Y9304D02*
X116919Y9720D01*
X117336Y10054D01*
X117919Y10220D01*
X118502Y10054D01*
X118919Y9720D01*
X119169Y9220D01*
Y6887D01*
G01X122269Y10220D02*
Y6887D01*
G01Y11554D02*
X122102Y11637D01*
Y11804D01*
X122269Y11887D01*
X122436Y11804D01*
Y11637D01*
X122269Y11554D01*
G01X127869Y6887D02*
Y11887D01*
G01X103156Y46437D02*
X99822Y48104D01*
X103156Y49770D01*
G01X105672Y47020D02*
X106256Y46604D01*
X106922Y46437D01*
X107589Y46604D01*
X108172Y47104D01*
X108589Y47854D01*
X108756Y48604D01*
Y49520D01*
X108589Y50270D01*
X108172Y50937D01*
X107672Y51270D01*
X107089Y51437D01*
X106422Y51270D01*
X105922Y50937D01*
X105589Y50437D01*
X105422Y49770D01*
X105589Y49187D01*
X106006Y48604D01*
X106506Y48270D01*
X107089Y48187D01*
X107756Y48354D01*
X108256Y48770D01*
X108756Y49520D01*
G01X112689Y51437D02*
X112022Y51270D01*
X111522Y50854D01*
X111189Y50354D01*
X110939Y49687D01*
X110856Y48937D01*
X110939Y48187D01*
X111189Y47520D01*
X111522Y47020D01*
X112022Y46604D01*
X112689Y46437D01*
X113356Y46604D01*
X113856Y47020D01*
X114189Y47520D01*
X114439Y48187D01*
X114522Y48937D01*
X114439Y49687D01*
X114189Y50354D01*
X113856Y50854D01*
X113356Y51270D01*
X112689Y51437D01*
G01X125389D02*
Y46437D01*
G01Y47187D02*
X125056Y46770D01*
X124556Y46520D01*
X123972Y46437D01*
X123306Y46604D01*
X122806Y47020D01*
X122472Y47520D01*
X122389Y48104D01*
X122472Y48687D01*
X122806Y49187D01*
X123306Y49604D01*
X123972Y49770D01*
X124556Y49687D01*
X124972Y49520D01*
X125389Y49187D01*
G01X128239Y48687D02*
X130906D01*
X130656Y49270D01*
X130239Y49604D01*
X129656Y49770D01*
X129072Y49687D01*
X128572Y49437D01*
X128239Y48854D01*
X128072Y48354D01*
Y47854D01*
X128239Y47354D01*
X128656Y46854D01*
X129156Y46520D01*
X129739Y46437D01*
X130322Y46604D01*
X130906Y47104D01*
G01X133922Y45187D02*
X134506Y44854D01*
X135172Y44770D01*
X135756Y44854D01*
X136256Y45270D01*
X136589Y45854D01*
Y49770D01*
G01Y49104D02*
X136256Y49437D01*
X135756Y49687D01*
X135172Y49770D01*
X134506Y49604D01*
X134089Y49270D01*
X133756Y48687D01*
X133589Y48104D01*
X133672Y47604D01*
X134006Y47020D01*
X134506Y46604D01*
X135172Y46437D01*
X135672Y46520D01*
X136256Y46854D01*
X136589Y47187D01*
G01X139522Y46437D02*
Y49770D01*
G01Y49104D02*
X139939Y49437D01*
X140356Y49687D01*
X140939Y49770D01*
X141356Y49687D01*
X141856Y49437D01*
G01X145039Y48687D02*
X147706D01*
X147456Y49270D01*
X147039Y49604D01*
X146456Y49770D01*
X145872Y49687D01*
X145372Y49437D01*
X145039Y48854D01*
X144872Y48354D01*
Y47854D01*
X145039Y47354D01*
X145456Y46854D01*
X145956Y46520D01*
X146539Y46437D01*
X147122Y46604D01*
X147706Y47104D01*
G01X150639Y48687D02*
X153306D01*
X153056Y49270D01*
X152639Y49604D01*
X152056Y49770D01*
X151472Y49687D01*
X150972Y49437D01*
X150639Y48854D01*
X150472Y48354D01*
Y47854D01*
X150639Y47354D01*
X151056Y46854D01*
X151556Y46520D01*
X152139Y46437D01*
X152722Y46604D01*
X153306Y47104D01*
G01X98542Y80467D02*
X101876Y82134D01*
X98542Y83800D01*
G01X104726Y81384D02*
X106892D01*
G01Y82884D02*
X104726D01*
G01X111242Y80467D02*
X111409Y81550D01*
X111659Y82467D01*
X111992Y83300D01*
X112409Y84217D01*
X113076Y85467D01*
X109742D01*
G01X117009D02*
X116342Y85300D01*
X115842Y84884D01*
X115509Y84384D01*
X115259Y83717D01*
X115176Y82967D01*
X115259Y82217D01*
X115509Y81550D01*
X115842Y81050D01*
X116342Y80634D01*
X117009Y80467D01*
X117676Y80634D01*
X118176Y81050D01*
X118509Y81550D01*
X118759Y82217D01*
X118842Y82967D01*
X118759Y83717D01*
X118509Y84384D01*
X118176Y84884D01*
X117676Y85300D01*
X117009Y85467D01*
G01X121109Y80300D02*
X124109Y85467D01*
G01X121109D02*
X120609Y85300D01*
X120359Y85050D01*
X120192Y84550D01*
X120359Y84050D01*
X120609Y83800D01*
X121109Y83634D01*
X121609Y83800D01*
X121859Y84050D01*
X122026Y84550D01*
X121859Y85050D01*
X121609Y85300D01*
X121109Y85467D01*
G01X124109Y82134D02*
X123609Y81967D01*
X123359Y81717D01*
X123192Y81217D01*
X123359Y80717D01*
X123609Y80467D01*
X124109Y80300D01*
X124609Y80467D01*
X124859Y80717D01*
X125026Y81217D01*
X124859Y81717D01*
X124609Y81967D01*
X124109Y82134D01*
G01X128042Y79550D02*
X128376Y80634D01*
G01X100522Y100894D02*
X102522D01*
G01X101439Y101977D02*
Y99810D01*
G01X105539Y99060D02*
X108539Y104227D01*
G01X111556Y100894D02*
X113722D01*
G01X118239Y99227D02*
Y104227D01*
X117239Y103227D01*
G01Y99227D02*
X119239D01*
G01X121339D02*
Y102560D01*
G01Y101644D02*
X121589Y102060D01*
X122006Y102394D01*
X122589Y102560D01*
X123172Y102394D01*
X123589Y102060D01*
X123839Y101644D01*
Y99227D01*
G01Y101644D02*
X124089Y102060D01*
X124506Y102394D01*
X125089Y102560D01*
X125672Y102394D01*
X126089Y102060D01*
X126339Y101560D01*
Y99227D01*
G01X129439Y102560D02*
Y99227D01*
G01Y103894D02*
X129272Y103977D01*
Y104144D01*
X129439Y104227D01*
X129606Y104144D01*
Y103977D01*
X129439Y103894D01*
G01X135039Y99227D02*
Y104227D01*
G01X103092Y144207D02*
Y149207D01*
X105259Y145040D01*
X107426Y149207D01*
Y144207D01*
G01X109442Y147540D02*
Y145207D01*
X109776Y144624D01*
X110276Y144290D01*
X110859Y144207D01*
X111442Y144290D01*
X111942Y144624D01*
X112276Y145207D01*
G01Y144207D02*
Y147540D01*
G01X115209Y144790D02*
X115626Y144457D01*
X116209Y144207D01*
X116709D01*
X117209Y144374D01*
X117542Y144624D01*
X117709Y144957D01*
X117626Y145457D01*
X117292Y145707D01*
X115792Y146207D01*
X115459Y146790D01*
X115626Y147207D01*
X115959Y147457D01*
X116459Y147540D01*
X116959Y147457D01*
X117459Y147207D01*
G01X122059Y149207D02*
Y144207D01*
G01X120892Y147540D02*
X123226D01*
G01X132759Y144207D02*
Y148457D01*
X132926Y148874D01*
X133259Y149124D01*
X133759Y149207D01*
X134259Y149040D01*
X134509Y148624D01*
G01X133509Y147207D02*
X131842D01*
G01X138859Y144207D02*
X138359Y144290D01*
X137859Y144624D01*
X137526Y145207D01*
X137359Y145874D01*
X137526Y146540D01*
X137859Y147124D01*
X138359Y147457D01*
X138859Y147540D01*
X139359Y147457D01*
X139859Y147124D01*
X140192Y146540D01*
X140276Y145874D01*
X140192Y145207D01*
X139859Y144624D01*
X139359Y144290D01*
X138859Y144207D01*
G01X144459D02*
Y149207D01*
G01X150059Y144207D02*
Y149207D01*
G01X155659Y144207D02*
X155159Y144290D01*
X154659Y144624D01*
X154326Y145207D01*
X154159Y145874D01*
X154326Y146540D01*
X154659Y147124D01*
X155159Y147457D01*
X155659Y147540D01*
X156159Y147457D01*
X156659Y147124D01*
X156992Y146540D01*
X157076Y145874D01*
X156992Y145207D01*
X156659Y144624D01*
X156159Y144290D01*
X155659Y144207D01*
G01X159176Y147540D02*
X160176Y144207D01*
X161259Y147540D01*
X162342Y144207D01*
X163342Y147540D01*
G01X90259Y430207D02*
Y147207D01*
G01X101342Y222874D02*
X103342D01*
G01X102259Y223957D02*
Y221790D01*
G01X106359Y221040D02*
X109359Y226207D01*
G01X112376Y222874D02*
X114542D01*
G01X117226Y221957D02*
X117726Y221540D01*
X118309Y221290D01*
X119059Y221207D01*
X119809Y221374D01*
X120392Y221707D01*
X120809Y222290D01*
X120892Y222957D01*
X120726Y223624D01*
X120309Y224040D01*
X119726Y224374D01*
X119142Y224457D01*
X118559Y224374D01*
X117809Y224040D01*
X118059Y226207D01*
X120309D01*
G01X122159Y221207D02*
Y224540D01*
G01Y223624D02*
X122409Y224040D01*
X122826Y224374D01*
X123409Y224540D01*
X123992Y224374D01*
X124409Y224040D01*
X124659Y223624D01*
Y221207D01*
G01Y223624D02*
X124909Y224040D01*
X125326Y224374D01*
X125909Y224540D01*
X126492Y224374D01*
X126909Y224040D01*
X127159Y223540D01*
Y221207D01*
G01X130259Y224540D02*
Y221207D01*
G01Y225874D02*
X130092Y225957D01*
Y226124D01*
X130259Y226207D01*
X130426Y226124D01*
Y225957D01*
X130259Y225874D01*
G01X135859Y221207D02*
Y226207D01*
G01X100569Y181197D02*
Y185447D01*
X100736Y185864D01*
X101069Y186114D01*
X101569Y186197D01*
X102069Y186030D01*
X102319Y185614D01*
G01X101319Y184197D02*
X99652D01*
G01X106669Y181197D02*
X106169Y181280D01*
X105669Y181614D01*
X105336Y182197D01*
X105169Y182864D01*
X105336Y183530D01*
X105669Y184114D01*
X106169Y184447D01*
X106669Y184530D01*
X107169Y184447D01*
X107669Y184114D01*
X108002Y183530D01*
X108086Y182864D01*
X108002Y182197D01*
X107669Y181614D01*
X107169Y181280D01*
X106669Y181197D01*
G01X112269D02*
Y186197D01*
G01X117869Y181197D02*
Y186197D01*
G01X123469Y181197D02*
X122969Y181280D01*
X122469Y181614D01*
X122136Y182197D01*
X121969Y182864D01*
X122136Y183530D01*
X122469Y184114D01*
X122969Y184447D01*
X123469Y184530D01*
X123969Y184447D01*
X124469Y184114D01*
X124802Y183530D01*
X124886Y182864D01*
X124802Y182197D01*
X124469Y181614D01*
X123969Y181280D01*
X123469Y181197D01*
G01X126986Y184530D02*
X127986Y181197D01*
X129069Y184530D01*
X130152Y181197D01*
X131152Y184530D01*
G01X141769Y186197D02*
Y181197D01*
G01Y181947D02*
X141436Y181530D01*
X140936Y181280D01*
X140352Y181197D01*
X139686Y181364D01*
X139186Y181780D01*
X138852Y182280D01*
X138769Y182864D01*
X138852Y183447D01*
X139186Y183947D01*
X139686Y184364D01*
X140352Y184530D01*
X140936Y184447D01*
X141352Y184280D01*
X141769Y183947D01*
G01X144702Y181197D02*
Y184530D01*
G01Y183864D02*
X145119Y184197D01*
X145536Y184447D01*
X146119Y184530D01*
X146536Y184447D01*
X147036Y184197D01*
G01X152969Y181197D02*
Y184530D01*
G01Y183947D02*
X152636Y184280D01*
X152136Y184447D01*
X151552Y184530D01*
X150969Y184364D01*
X150469Y184030D01*
X150136Y183530D01*
X149969Y182864D01*
X150136Y182197D01*
X150469Y181697D01*
X150969Y181364D01*
X151552Y181197D01*
X152136Y181280D01*
X152636Y181530D01*
X152969Y181864D01*
G01X154986Y184530D02*
X155986Y181197D01*
X157069Y184530D01*
X158152Y181197D01*
X159152Y184530D01*
G01X162669D02*
Y181197D01*
G01Y185864D02*
X162502Y185947D01*
Y186114D01*
X162669Y186197D01*
X162836Y186114D01*
Y185947D01*
X162669Y185864D01*
G01X166852Y181197D02*
Y184530D01*
G01Y183697D02*
X167186Y184114D01*
X167686Y184447D01*
X168352Y184530D01*
X168936Y184447D01*
X169436Y184114D01*
X169686Y183530D01*
Y181197D01*
G01X172702Y179947D02*
X173286Y179614D01*
X173952Y179530D01*
X174536Y179614D01*
X175036Y180030D01*
X175369Y180614D01*
Y184530D01*
G01Y183864D02*
X175036Y184197D01*
X174536Y184447D01*
X173952Y184530D01*
X173286Y184364D01*
X172869Y184030D01*
X172536Y183447D01*
X172369Y182864D01*
X172452Y182364D01*
X172786Y181780D01*
X173286Y181364D01*
X173952Y181197D01*
X174452Y181280D01*
X175036Y181614D01*
X175369Y181947D01*
G01X179886Y179530D02*
X180719Y180364D01*
X181136Y181197D01*
Y184530D01*
X180719Y185364D01*
X179886Y186197D01*
G01X145612Y189360D02*
X144779Y190194D01*
X144362Y191027D01*
Y194360D01*
X144779Y195194D01*
X145612Y196027D01*
G01X151629Y191027D02*
X151129Y191110D01*
X150629Y191444D01*
X150296Y192027D01*
X150129Y192694D01*
X150296Y193360D01*
X150629Y193944D01*
X151129Y194277D01*
X151629Y194360D01*
X152129Y194277D01*
X152629Y193944D01*
X152962Y193360D01*
X153046Y192694D01*
X152962Y192027D01*
X152629Y191444D01*
X152129Y191110D01*
X151629Y191027D01*
G01X156062D02*
Y194360D01*
G01Y193694D02*
X156479Y194027D01*
X156896Y194277D01*
X157479Y194360D01*
X157896Y194277D01*
X158396Y194027D01*
G01X101662Y191794D02*
X103662D01*
G01X102579Y192877D02*
Y190710D01*
G01X106679Y189960D02*
X109679Y195127D01*
G01X112696Y191794D02*
X114862D01*
G01X117546Y190877D02*
X118046Y190460D01*
X118629Y190210D01*
X119379Y190127D01*
X120129Y190294D01*
X120712Y190627D01*
X121129Y191210D01*
X121212Y191877D01*
X121046Y192544D01*
X120629Y192960D01*
X120046Y193294D01*
X119462Y193377D01*
X118879Y193294D01*
X118129Y192960D01*
X118379Y195127D01*
X120629D01*
G01X122479Y190127D02*
Y193460D01*
G01Y192544D02*
X122729Y192960D01*
X123146Y193294D01*
X123729Y193460D01*
X124312Y193294D01*
X124729Y192960D01*
X124979Y192544D01*
Y190127D01*
G01Y192544D02*
X125229Y192960D01*
X125646Y193294D01*
X126229Y193460D01*
X126812Y193294D01*
X127229Y192960D01*
X127479Y192460D01*
Y190127D01*
G01X130579Y193460D02*
Y190127D01*
G01Y194794D02*
X130412Y194877D01*
Y195044D01*
X130579Y195127D01*
X130746Y195044D01*
Y194877D01*
X130579Y194794D01*
G01X136179Y190127D02*
Y195127D01*
G01X102259Y203207D02*
Y208207D01*
X101259Y207207D01*
G01Y203207D02*
X103259D01*
G01X107859Y203040D02*
X107692Y203124D01*
Y203290D01*
X107859Y203374D01*
X108026Y203290D01*
Y203124D01*
X107859Y203040D01*
G01X113459Y208207D02*
X112792Y208040D01*
X112292Y207624D01*
X111959Y207124D01*
X111709Y206457D01*
X111626Y205707D01*
X111709Y204957D01*
X111959Y204290D01*
X112292Y203790D01*
X112792Y203374D01*
X113459Y203207D01*
X114126Y203374D01*
X114626Y203790D01*
X114959Y204290D01*
X115209Y204957D01*
X115292Y205707D01*
X115209Y206457D01*
X114959Y207124D01*
X114626Y207624D01*
X114126Y208040D01*
X113459Y208207D01*
G01X116559Y203207D02*
Y206540D01*
G01Y205624D02*
X116809Y206040D01*
X117226Y206374D01*
X117809Y206540D01*
X118392Y206374D01*
X118809Y206040D01*
X119059Y205624D01*
Y203207D01*
G01Y205624D02*
X119309Y206040D01*
X119726Y206374D01*
X120309Y206540D01*
X120892Y206374D01*
X121309Y206040D01*
X121559Y205540D01*
Y203207D01*
G01X124659Y206540D02*
Y203207D01*
G01Y207874D02*
X124492Y207957D01*
Y208124D01*
X124659Y208207D01*
X124826Y208124D01*
Y207957D01*
X124659Y207874D01*
G01X130259Y203207D02*
Y208207D01*
G01X138959Y203207D02*
Y206540D01*
G01Y205624D02*
X139209Y206040D01*
X139626Y206374D01*
X140209Y206540D01*
X140792Y206374D01*
X141209Y206040D01*
X141459Y205624D01*
Y203207D01*
G01Y205624D02*
X141709Y206040D01*
X142126Y206374D01*
X142709Y206540D01*
X143292Y206374D01*
X143709Y206040D01*
X143959Y205540D01*
Y203207D01*
G01X148559D02*
Y206540D01*
G01Y205957D02*
X148226Y206290D01*
X147726Y206457D01*
X147142Y206540D01*
X146559Y206374D01*
X146059Y206040D01*
X145726Y205540D01*
X145559Y204874D01*
X145726Y204207D01*
X146059Y203707D01*
X146559Y203374D01*
X147142Y203207D01*
X147726Y203290D01*
X148226Y203540D01*
X148559Y203874D01*
G01X151409Y206540D02*
X153909Y203207D01*
G01Y206540D02*
X151409Y203207D01*
G01X101342Y237874D02*
X103342D01*
G01X102259Y238957D02*
Y236790D01*
G01X106359Y236040D02*
X109359Y241207D01*
G01X112376Y237874D02*
X114542D01*
G01X117226Y236957D02*
X117726Y236540D01*
X118309Y236290D01*
X119059Y236207D01*
X119809Y236374D01*
X120392Y236707D01*
X120809Y237290D01*
X120892Y237957D01*
X120726Y238624D01*
X120309Y239040D01*
X119726Y239374D01*
X119142Y239457D01*
X118559Y239374D01*
X117809Y239040D01*
X118059Y241207D01*
X120309D01*
G01X122159Y236207D02*
Y239540D01*
G01Y238624D02*
X122409Y239040D01*
X122826Y239374D01*
X123409Y239540D01*
X123992Y239374D01*
X124409Y239040D01*
X124659Y238624D01*
Y236207D01*
G01Y238624D02*
X124909Y239040D01*
X125326Y239374D01*
X125909Y239540D01*
X126492Y239374D01*
X126909Y239040D01*
X127159Y238540D01*
Y236207D01*
G01X130259Y239540D02*
Y236207D01*
G01Y240874D02*
X130092Y240957D01*
Y241124D01*
X130259Y241207D01*
X130426Y241124D01*
Y240957D01*
X130259Y240874D01*
G01X135859Y236207D02*
Y241207D01*
G01X101342Y267874D02*
X103342D01*
G01X102259Y268957D02*
Y266790D01*
G01X106359Y266040D02*
X109359Y271207D01*
G01X112376Y267874D02*
X114542D01*
G01X117476Y270374D02*
X117976Y270874D01*
X118559Y271124D01*
X119226Y271207D01*
X120059Y271040D01*
X120642Y270624D01*
X120809Y270124D01*
X120726Y269624D01*
X120392Y269207D01*
X118726Y268374D01*
X117976Y267790D01*
X117476Y266957D01*
X117309Y266207D01*
X120809D01*
G01X122159D02*
Y269540D01*
G01Y268624D02*
X122409Y269040D01*
X122826Y269374D01*
X123409Y269540D01*
X123992Y269374D01*
X124409Y269040D01*
X124659Y268624D01*
Y266207D01*
G01Y268624D02*
X124909Y269040D01*
X125326Y269374D01*
X125909Y269540D01*
X126492Y269374D01*
X126909Y269040D01*
X127159Y268540D01*
Y266207D01*
G01X130259Y269540D02*
Y266207D01*
G01Y270874D02*
X130092Y270957D01*
Y271124D01*
X130259Y271207D01*
X130426Y271124D01*
Y270957D01*
X130259Y270874D01*
G01X135859Y266207D02*
Y271207D01*
G01X101342Y281374D02*
X103342D01*
G01X102259Y282457D02*
Y280290D01*
G01X106359Y279540D02*
X109359Y284707D01*
G01X112376Y281374D02*
X114542D01*
G01X117226Y280707D02*
X117726Y280124D01*
X118392Y279790D01*
X119142Y279707D01*
X119809Y279790D01*
X120476Y280207D01*
X120892Y280707D01*
X120976Y281207D01*
X120809Y281790D01*
X120226Y282207D01*
X119642Y282374D01*
X118892D01*
G01X119642D02*
X120142Y282624D01*
X120559Y283040D01*
X120726Y283540D01*
X120559Y284040D01*
X120142Y284457D01*
X119392Y284707D01*
X118642Y284624D01*
X117892Y284290D01*
G01X122159Y279707D02*
Y283040D01*
G01Y282124D02*
X122409Y282540D01*
X122826Y282874D01*
X123409Y283040D01*
X123992Y282874D01*
X124409Y282540D01*
X124659Y282124D01*
Y279707D01*
G01Y282124D02*
X124909Y282540D01*
X125326Y282874D01*
X125909Y283040D01*
X126492Y282874D01*
X126909Y282540D01*
X127159Y282040D01*
Y279707D01*
G01X130259Y283040D02*
Y279707D01*
G01Y284374D02*
X130092Y284457D01*
Y284624D01*
X130259Y284707D01*
X130426Y284624D01*
Y284457D01*
X130259Y284374D01*
G01X135859Y279707D02*
Y284707D01*
G01X101342Y297874D02*
X103342D01*
G01X102259Y298957D02*
Y296790D01*
G01X106359Y296040D02*
X109359Y301207D01*
G01X112376Y297874D02*
X114542D01*
G01X117476Y300374D02*
X117976Y300874D01*
X118559Y301124D01*
X119226Y301207D01*
X120059Y301040D01*
X120642Y300624D01*
X120809Y300124D01*
X120726Y299624D01*
X120392Y299207D01*
X118726Y298374D01*
X117976Y297790D01*
X117476Y296957D01*
X117309Y296207D01*
X120809D01*
G01X122159D02*
Y299540D01*
G01Y298624D02*
X122409Y299040D01*
X122826Y299374D01*
X123409Y299540D01*
X123992Y299374D01*
X124409Y299040D01*
X124659Y298624D01*
Y296207D01*
G01Y298624D02*
X124909Y299040D01*
X125326Y299374D01*
X125909Y299540D01*
X126492Y299374D01*
X126909Y299040D01*
X127159Y298540D01*
Y296207D01*
G01X130259Y299540D02*
Y296207D01*
G01Y300874D02*
X130092Y300957D01*
Y301124D01*
X130259Y301207D01*
X130426Y301124D01*
Y300957D01*
X130259Y300874D01*
G01X135859Y296207D02*
Y301207D01*
G01X101342Y252874D02*
X103342D01*
G01X102259Y253957D02*
Y251790D01*
G01X106026Y252207D02*
X106526Y251624D01*
X107192Y251290D01*
X107942Y251207D01*
X108609Y251290D01*
X109276Y251707D01*
X109692Y252207D01*
X109776Y252707D01*
X109609Y253290D01*
X109026Y253707D01*
X108442Y253874D01*
X107692D01*
G01X108442D02*
X108942Y254124D01*
X109359Y254540D01*
X109526Y255040D01*
X109359Y255540D01*
X108942Y255957D01*
X108192Y256207D01*
X107442Y256124D01*
X106692Y255790D01*
G01X111959Y251040D02*
X114959Y256207D01*
G01X117976Y252874D02*
X120142D01*
G01X124659Y256207D02*
X123992Y256040D01*
X123492Y255624D01*
X123159Y255124D01*
X122909Y254457D01*
X122826Y253707D01*
X122909Y252957D01*
X123159Y252290D01*
X123492Y251790D01*
X123992Y251374D01*
X124659Y251207D01*
X125326Y251374D01*
X125826Y251790D01*
X126159Y252290D01*
X126409Y252957D01*
X126492Y253707D01*
X126409Y254457D01*
X126159Y255124D01*
X125826Y255624D01*
X125326Y256040D01*
X124659Y256207D01*
G01X127759Y251207D02*
Y254540D01*
G01Y253624D02*
X128009Y254040D01*
X128426Y254374D01*
X129009Y254540D01*
X129592Y254374D01*
X130009Y254040D01*
X130259Y253624D01*
Y251207D01*
G01Y253624D02*
X130509Y254040D01*
X130926Y254374D01*
X131509Y254540D01*
X132092Y254374D01*
X132509Y254040D01*
X132759Y253540D01*
Y251207D01*
G01X135859Y254540D02*
Y251207D01*
G01Y255874D02*
X135692Y255957D01*
Y256124D01*
X135859Y256207D01*
X136026Y256124D01*
Y255957D01*
X135859Y255874D01*
G01X141459Y251207D02*
Y256207D01*
G01X101342Y312874D02*
X103342D01*
G01X102259Y313957D02*
Y311790D01*
G01X106359Y311040D02*
X109359Y316207D01*
G01X112376Y312874D02*
X114542D01*
G01X117476Y315374D02*
X117976Y315874D01*
X118559Y316124D01*
X119226Y316207D01*
X120059Y316040D01*
X120642Y315624D01*
X120809Y315124D01*
X120726Y314624D01*
X120392Y314207D01*
X118726Y313374D01*
X117976Y312790D01*
X117476Y311957D01*
X117309Y311207D01*
X120809D01*
G01X122159D02*
Y314540D01*
G01Y313624D02*
X122409Y314040D01*
X122826Y314374D01*
X123409Y314540D01*
X123992Y314374D01*
X124409Y314040D01*
X124659Y313624D01*
Y311207D01*
G01Y313624D02*
X124909Y314040D01*
X125326Y314374D01*
X125909Y314540D01*
X126492Y314374D01*
X126909Y314040D01*
X127159Y313540D01*
Y311207D01*
G01X130259Y314540D02*
Y311207D01*
G01Y315874D02*
X130092Y315957D01*
Y316124D01*
X130259Y316207D01*
X130426Y316124D01*
Y315957D01*
X130259Y315874D01*
G01X135859Y311207D02*
Y316207D01*
G01X101342Y342874D02*
X103342D01*
G01X102259Y343957D02*
Y341790D01*
G01X106359Y341040D02*
X109359Y346207D01*
G01X112376Y342874D02*
X114542D01*
G01X117226Y342207D02*
X117726Y341624D01*
X118392Y341290D01*
X119142Y341207D01*
X119809Y341290D01*
X120476Y341707D01*
X120892Y342207D01*
X120976Y342707D01*
X120809Y343290D01*
X120226Y343707D01*
X119642Y343874D01*
X118892D01*
G01X119642D02*
X120142Y344124D01*
X120559Y344540D01*
X120726Y345040D01*
X120559Y345540D01*
X120142Y345957D01*
X119392Y346207D01*
X118642Y346124D01*
X117892Y345790D01*
G01X122159Y341207D02*
Y344540D01*
G01Y343624D02*
X122409Y344040D01*
X122826Y344374D01*
X123409Y344540D01*
X123992Y344374D01*
X124409Y344040D01*
X124659Y343624D01*
Y341207D01*
G01Y343624D02*
X124909Y344040D01*
X125326Y344374D01*
X125909Y344540D01*
X126492Y344374D01*
X126909Y344040D01*
X127159Y343540D01*
Y341207D01*
G01X130259Y344540D02*
Y341207D01*
G01Y345874D02*
X130092Y345957D01*
Y346124D01*
X130259Y346207D01*
X130426Y346124D01*
Y345957D01*
X130259Y345874D01*
G01X135859Y341207D02*
Y346207D01*
G01X100176Y354707D02*
X102259Y359707D01*
X104342Y354707D01*
G01X103592Y356457D02*
X100926D01*
G01X107859Y354707D02*
Y359707D01*
G01X113459Y354707D02*
Y359707D01*
G01X119059Y354707D02*
X118559Y354790D01*
X118059Y355124D01*
X117726Y355707D01*
X117559Y356374D01*
X117726Y357040D01*
X118059Y357624D01*
X118559Y357957D01*
X119059Y358040D01*
X119559Y357957D01*
X120059Y357624D01*
X120392Y357040D01*
X120476Y356374D01*
X120392Y355707D01*
X120059Y355124D01*
X119559Y354790D01*
X119059Y354707D01*
G01X122576Y358040D02*
X123576Y354707D01*
X124659Y358040D01*
X125742Y354707D01*
X126742Y358040D01*
G01X101342Y326374D02*
X103342D01*
G01X102259Y327457D02*
Y325290D01*
G01X106276Y328874D02*
X106776Y329374D01*
X107359Y329624D01*
X108026Y329707D01*
X108859Y329540D01*
X109442Y329124D01*
X109609Y328624D01*
X109526Y328124D01*
X109192Y327707D01*
X107526Y326874D01*
X106776Y326290D01*
X106276Y325457D01*
X106109Y324707D01*
X109609D01*
G01X111959Y324540D02*
X114959Y329707D01*
G01X117976Y326374D02*
X120142D01*
G01X125659Y324707D02*
Y329707D01*
X122576Y326124D01*
X126742D01*
G01X127759Y324707D02*
Y328040D01*
G01Y327124D02*
X128009Y327540D01*
X128426Y327874D01*
X129009Y328040D01*
X129592Y327874D01*
X130009Y327540D01*
X130259Y327124D01*
Y324707D01*
G01Y327124D02*
X130509Y327540D01*
X130926Y327874D01*
X131509Y328040D01*
X132092Y327874D01*
X132509Y327540D01*
X132759Y327040D01*
Y324707D01*
G01X135859Y328040D02*
Y324707D01*
G01Y329374D02*
X135692Y329457D01*
Y329624D01*
X135859Y329707D01*
X136026Y329624D01*
Y329457D01*
X135859Y329374D01*
G01X141459Y324707D02*
Y329707D01*
G01X101342Y371374D02*
X103342D01*
G01X102259Y372457D02*
Y370290D01*
G01X106359Y369540D02*
X109359Y374707D01*
G01X112376Y371374D02*
X114542D01*
G01X117476Y373874D02*
X117976Y374374D01*
X118559Y374624D01*
X119226Y374707D01*
X120059Y374540D01*
X120642Y374124D01*
X120809Y373624D01*
X120726Y373124D01*
X120392Y372707D01*
X118726Y371874D01*
X117976Y371290D01*
X117476Y370457D01*
X117309Y369707D01*
X120809D01*
G01X122159D02*
Y373040D01*
G01Y372124D02*
X122409Y372540D01*
X122826Y372874D01*
X123409Y373040D01*
X123992Y372874D01*
X124409Y372540D01*
X124659Y372124D01*
Y369707D01*
G01Y372124D02*
X124909Y372540D01*
X125326Y372874D01*
X125909Y373040D01*
X126492Y372874D01*
X126909Y372540D01*
X127159Y372040D01*
Y369707D01*
G01X130259Y373040D02*
Y369707D01*
G01Y374374D02*
X130092Y374457D01*
Y374624D01*
X130259Y374707D01*
X130426Y374624D01*
Y374457D01*
X130259Y374374D01*
G01X135859Y369707D02*
Y374707D01*
G01X112259Y419707D02*
Y414707D01*
G01X110342Y419707D02*
X114176D01*
G01X117859Y414707D02*
X117359Y414790D01*
X116859Y415124D01*
X116526Y415707D01*
X116359Y416374D01*
X116526Y417040D01*
X116859Y417624D01*
X117359Y417957D01*
X117859Y418040D01*
X118359Y417957D01*
X118859Y417624D01*
X119192Y417040D01*
X119276Y416374D01*
X119192Y415707D01*
X118859Y415124D01*
X118359Y414790D01*
X117859Y414707D01*
G01X123459D02*
Y419707D01*
G01X127809Y416957D02*
X130476D01*
X130226Y417540D01*
X129809Y417874D01*
X129226Y418040D01*
X128642Y417957D01*
X128142Y417707D01*
X127809Y417124D01*
X127642Y416624D01*
Y416124D01*
X127809Y415624D01*
X128226Y415124D01*
X128726Y414790D01*
X129309Y414707D01*
X129892Y414874D01*
X130476Y415374D01*
G01X133492Y414707D02*
Y418040D01*
G01Y417374D02*
X133909Y417707D01*
X134326Y417957D01*
X134909Y418040D01*
X135326Y417957D01*
X135826Y417707D01*
G01X141759Y414707D02*
Y418040D01*
G01Y417457D02*
X141426Y417790D01*
X140926Y417957D01*
X140342Y418040D01*
X139759Y417874D01*
X139259Y417540D01*
X138926Y417040D01*
X138759Y416374D01*
X138926Y415707D01*
X139259Y415207D01*
X139759Y414874D01*
X140342Y414707D01*
X140926Y414790D01*
X141426Y415040D01*
X141759Y415374D01*
G01X144442Y414707D02*
Y418040D01*
G01Y417207D02*
X144776Y417624D01*
X145276Y417957D01*
X145942Y418040D01*
X146526Y417957D01*
X147026Y417624D01*
X147276Y417040D01*
Y414707D01*
G01X152792Y417624D02*
X152209Y417957D01*
X151709Y418040D01*
X151042Y417874D01*
X150542Y417540D01*
X150209Y416957D01*
X150126Y416374D01*
X150209Y415790D01*
X150542Y415290D01*
X151042Y414874D01*
X151709Y414707D01*
X152292Y414874D01*
X152792Y415207D01*
G01X155809Y416957D02*
X158476D01*
X158226Y417540D01*
X157809Y417874D01*
X157226Y418040D01*
X156642Y417957D01*
X156142Y417707D01*
X155809Y417124D01*
X155642Y416624D01*
Y416124D01*
X155809Y415624D01*
X156226Y415124D01*
X156726Y414790D01*
X157309Y414707D01*
X157892Y414874D01*
X158476Y415374D01*
G01X100112Y389907D02*
Y394907D01*
X102279Y390740D01*
X104446Y394907D01*
Y389907D01*
G01X106462Y393240D02*
Y390907D01*
X106796Y390324D01*
X107296Y389990D01*
X107879Y389907D01*
X108462Y389990D01*
X108962Y390324D01*
X109296Y390907D01*
G01Y389907D02*
Y393240D01*
G01X112229Y390490D02*
X112646Y390157D01*
X113229Y389907D01*
X113729D01*
X114229Y390074D01*
X114562Y390324D01*
X114729Y390657D01*
X114646Y391157D01*
X114312Y391407D01*
X112812Y391907D01*
X112479Y392490D01*
X112646Y392907D01*
X112979Y393157D01*
X113479Y393240D01*
X113979Y393157D01*
X114479Y392907D01*
G01X119079Y394907D02*
Y389907D01*
G01X117912Y393240D02*
X120246D01*
G01X129779Y389907D02*
Y394157D01*
X129946Y394574D01*
X130279Y394824D01*
X130779Y394907D01*
X131279Y394740D01*
X131529Y394324D01*
G01X130529Y392907D02*
X128862D01*
G01X135879Y389907D02*
X135379Y389990D01*
X134879Y390324D01*
X134546Y390907D01*
X134379Y391574D01*
X134546Y392240D01*
X134879Y392824D01*
X135379Y393157D01*
X135879Y393240D01*
X136379Y393157D01*
X136879Y392824D01*
X137212Y392240D01*
X137296Y391574D01*
X137212Y390907D01*
X136879Y390324D01*
X136379Y389990D01*
X135879Y389907D01*
G01X141479D02*
Y394907D01*
G01X147079Y389907D02*
Y394907D01*
G01X152679Y389907D02*
X152179Y389990D01*
X151679Y390324D01*
X151346Y390907D01*
X151179Y391574D01*
X151346Y392240D01*
X151679Y392824D01*
X152179Y393157D01*
X152679Y393240D01*
X153179Y393157D01*
X153679Y392824D01*
X154012Y392240D01*
X154096Y391574D01*
X154012Y390907D01*
X153679Y390324D01*
X153179Y389990D01*
X152679Y389907D01*
G01X156196Y393240D02*
X157196Y389907D01*
X158279Y393240D01*
X159362Y389907D01*
X160362Y393240D01*
G01X85176Y611207D02*
X87259Y606207D01*
X89342Y611207D01*
G01X91026Y607207D02*
X91526Y606624D01*
X92192Y606290D01*
X92942Y606207D01*
X93609Y606290D01*
X94276Y606707D01*
X94692Y607207D01*
X94776Y607707D01*
X94609Y608290D01*
X94026Y608707D01*
X93442Y608874D01*
X92692D01*
G01X93442D02*
X93942Y609124D01*
X94359Y609540D01*
X94526Y610040D01*
X94359Y610540D01*
X93942Y610957D01*
X93192Y611207D01*
X92442Y611124D01*
X91692Y610790D01*
G01X98459Y606040D02*
X98292Y606124D01*
Y606290D01*
X98459Y606374D01*
X98626Y606290D01*
Y606124D01*
X98459Y606040D01*
G01X105059Y606207D02*
Y611207D01*
X101976Y607624D01*
X106142D01*
G01X109659Y606040D02*
X109492Y606124D01*
Y606290D01*
X109659Y606374D01*
X109826Y606290D01*
Y606124D01*
X109659Y606040D01*
G01X115259Y606207D02*
Y611207D01*
X114259Y610207D01*
G01Y606207D02*
X116259D01*
G01X136076Y610374D02*
X136576Y610874D01*
X137159Y611124D01*
X137826Y611207D01*
X138659Y611040D01*
X139242Y610624D01*
X139409Y610124D01*
X139326Y609624D01*
X138992Y609207D01*
X137326Y608374D01*
X136576Y607790D01*
X136076Y606957D01*
X135909Y606207D01*
X139409D01*
G01X143259Y611207D02*
X142592Y611040D01*
X142092Y610624D01*
X141759Y610124D01*
X141509Y609457D01*
X141426Y608707D01*
X141509Y607957D01*
X141759Y607290D01*
X142092Y606790D01*
X142592Y606374D01*
X143259Y606207D01*
X143926Y606374D01*
X144426Y606790D01*
X144759Y607290D01*
X145009Y607957D01*
X145092Y608707D01*
X145009Y609457D01*
X144759Y610124D01*
X144426Y610624D01*
X143926Y611040D01*
X143259Y611207D01*
G01X148859Y606207D02*
Y611207D01*
X147859Y610207D01*
G01Y606207D02*
X149859D01*
G01X152626Y606957D02*
X153126Y606540D01*
X153709Y606290D01*
X154459Y606207D01*
X155209Y606374D01*
X155792Y606707D01*
X156209Y607290D01*
X156292Y607957D01*
X156126Y608624D01*
X155709Y609040D01*
X155126Y609374D01*
X154542Y609457D01*
X153959Y609374D01*
X153209Y609040D01*
X153459Y611207D01*
X155709D01*
G01X158559Y606040D02*
X161559Y611207D01*
G01X165659D02*
X164992Y611040D01*
X164492Y610624D01*
X164159Y610124D01*
X163909Y609457D01*
X163826Y608707D01*
X163909Y607957D01*
X164159Y607290D01*
X164492Y606790D01*
X164992Y606374D01*
X165659Y606207D01*
X166326Y606374D01*
X166826Y606790D01*
X167159Y607290D01*
X167409Y607957D01*
X167492Y608707D01*
X167409Y609457D01*
X167159Y610124D01*
X166826Y610624D01*
X166326Y611040D01*
X165659Y611207D01*
G01X169676Y608290D02*
X170259Y608874D01*
X170759Y609207D01*
X171426Y609374D01*
X172009Y609207D01*
X172426Y608874D01*
X172759Y608374D01*
X172842Y607790D01*
X172759Y607290D01*
X172426Y606790D01*
X171926Y606374D01*
X171342Y606207D01*
X170676Y606374D01*
X170092Y606874D01*
X169759Y607624D01*
X169676Y608457D01*
X169842Y609540D01*
X170092Y610124D01*
X170509Y610707D01*
X171092Y611124D01*
X171676Y611207D01*
X172259Y611040D01*
X172676Y610624D01*
G01X207759Y601707D02*
Y-321793D01*
X837759D01*
Y533207D01*
X207759D01*
G01X189259Y467207D02*
Y-318293D01*
G01X217426Y-287043D02*
X217926Y-287460D01*
X218509Y-287710D01*
X219259Y-287793D01*
X220009Y-287626D01*
X220592Y-287293D01*
X221009Y-286710D01*
X221092Y-286043D01*
X220926Y-285376D01*
X220509Y-284960D01*
X219926Y-284626D01*
X219342Y-284543D01*
X218759Y-284626D01*
X218009Y-284960D01*
X218259Y-282793D01*
X220509D01*
G01X224859Y-287960D02*
X224692Y-287876D01*
Y-287710D01*
X224859Y-287626D01*
X225026Y-287710D01*
Y-287876D01*
X224859Y-287960D01*
G01X234392Y-287793D02*
Y-282793D01*
X236476D01*
X237142Y-283043D01*
X237559Y-283376D01*
X237726Y-284043D01*
X237559Y-284710D01*
X237059Y-285126D01*
X236476Y-285376D01*
X234392D01*
G01X236476D02*
X237726Y-287793D01*
G01X240409Y-285543D02*
X243076D01*
X242826Y-284960D01*
X242409Y-284626D01*
X241826Y-284460D01*
X241242Y-284543D01*
X240742Y-284793D01*
X240409Y-285376D01*
X240242Y-285876D01*
Y-286376D01*
X240409Y-286876D01*
X240826Y-287376D01*
X241326Y-287710D01*
X241909Y-287793D01*
X242492Y-287626D01*
X243076Y-287126D01*
G01X244759Y-287793D02*
Y-284460D01*
G01Y-285376D02*
X245009Y-284960D01*
X245426Y-284626D01*
X246009Y-284460D01*
X246592Y-284626D01*
X247009Y-284960D01*
X247259Y-285376D01*
Y-287793D01*
G01Y-285376D02*
X247509Y-284960D01*
X247926Y-284626D01*
X248509Y-284460D01*
X249092Y-284626D01*
X249509Y-284960D01*
X249759Y-285460D01*
Y-287793D01*
G01X254359D02*
Y-284460D01*
G01Y-285043D02*
X254026Y-284710D01*
X253526Y-284543D01*
X252942Y-284460D01*
X252359Y-284626D01*
X251859Y-284960D01*
X251526Y-285460D01*
X251359Y-286126D01*
X251526Y-286793D01*
X251859Y-287293D01*
X252359Y-287626D01*
X252942Y-287793D01*
X253526Y-287710D01*
X254026Y-287460D01*
X254359Y-287126D01*
G01X257292Y-287793D02*
Y-284460D01*
G01Y-285126D02*
X257709Y-284793D01*
X258126Y-284543D01*
X258709Y-284460D01*
X259126Y-284543D01*
X259626Y-284793D01*
G01X262642Y-287793D02*
Y-282793D01*
G01X265309Y-284460D02*
X262642Y-286376D01*
G01X263726Y-285626D02*
X265476Y-287793D01*
G01X267826Y-287960D02*
X271492Y-284293D01*
G01X269659Y-283626D02*
Y-288626D01*
G01X271492Y-287960D02*
X267826Y-284293D01*
G01X267159Y-286126D02*
X272159D01*
G01X207759Y-301793D02*
X837759D01*
G01X207759Y-271793D02*
X837759D01*
G01X207759Y-163293D02*
X837759D01*
G01X216166Y125880D02*
X219832Y129547D01*
G01X217999Y130214D02*
Y125214D01*
G01X219832Y125880D02*
X216166Y129547D01*
G01X215499Y127714D02*
X220499D01*
G01X223182Y124380D02*
X222349Y125214D01*
X221932Y126047D01*
Y129380D01*
X222349Y130214D01*
X223182Y131047D01*
G01X227366Y126797D02*
X227866Y126380D01*
X228449Y126130D01*
X229199Y126047D01*
X229949Y126214D01*
X230532Y126547D01*
X230949Y127130D01*
X231032Y127797D01*
X230866Y128464D01*
X230449Y128880D01*
X229866Y129214D01*
X229282Y129297D01*
X228699Y129214D01*
X227949Y128880D01*
X228199Y131047D01*
X230449D01*
G01X234799Y125880D02*
X234632Y125964D01*
Y126130D01*
X234799Y126214D01*
X234966Y126130D01*
Y125964D01*
X234799Y125880D01*
G01X240399Y126047D02*
Y131047D01*
X239399Y130047D01*
G01Y126047D02*
X241399D01*
G01X246416Y124380D02*
X247249Y125214D01*
X247666Y126047D01*
Y129380D01*
X247249Y130214D01*
X246416Y131047D01*
G01X220259Y100707D02*
Y105707D01*
X217176Y102124D01*
X221342D01*
G01X224859Y100540D02*
X224692Y100624D01*
Y100790D01*
X224859Y100874D01*
X225026Y100790D01*
Y100624D01*
X224859Y100540D01*
G01X234559Y100707D02*
Y105707D01*
G01Y103207D02*
X234976Y103707D01*
X235476Y103957D01*
X235976Y104040D01*
X236726Y103874D01*
X237226Y103540D01*
X237559Y102957D01*
Y102290D01*
X237392Y101624D01*
X237059Y101124D01*
X236476Y100790D01*
X235976Y100707D01*
X235476Y100790D01*
X234976Y101040D01*
X234559Y101457D01*
G01X243159Y100707D02*
Y104040D01*
G01Y103457D02*
X242826Y103790D01*
X242326Y103957D01*
X241742Y104040D01*
X241159Y103874D01*
X240659Y103540D01*
X240326Y103040D01*
X240159Y102374D01*
X240326Y101707D01*
X240659Y101207D01*
X241159Y100874D01*
X241742Y100707D01*
X242326Y100790D01*
X242826Y101040D01*
X243159Y101374D01*
G01X248592Y103624D02*
X248009Y103957D01*
X247509Y104040D01*
X246842Y103874D01*
X246342Y103540D01*
X246009Y102957D01*
X245926Y102374D01*
X246009Y101790D01*
X246342Y101290D01*
X246842Y100874D01*
X247509Y100707D01*
X248092Y100874D01*
X248592Y101207D01*
G01X251442Y100707D02*
Y105707D01*
G01X254109Y104040D02*
X251442Y102124D01*
G01X252526Y102874D02*
X254276Y100707D01*
G01X259959Y105707D02*
Y100707D01*
G01Y101457D02*
X259626Y101040D01*
X259126Y100790D01*
X258542Y100707D01*
X257876Y100874D01*
X257376Y101290D01*
X257042Y101790D01*
X256959Y102374D01*
X257042Y102957D01*
X257376Y103457D01*
X257876Y103874D01*
X258542Y104040D01*
X259126Y103957D01*
X259542Y103790D01*
X259959Y103457D01*
G01X262892Y100707D02*
Y104040D01*
G01Y103374D02*
X263309Y103707D01*
X263726Y103957D01*
X264309Y104040D01*
X264726Y103957D01*
X265226Y103707D01*
G01X269659Y104040D02*
Y100707D01*
G01Y105374D02*
X269492Y105457D01*
Y105624D01*
X269659Y105707D01*
X269826Y105624D01*
Y105457D01*
X269659Y105374D01*
G01X275259Y100707D02*
Y105707D01*
G01X280859Y100707D02*
Y105707D01*
G01X293559Y100707D02*
Y104040D01*
G01Y103457D02*
X293226Y103790D01*
X292726Y103957D01*
X292142Y104040D01*
X291559Y103874D01*
X291059Y103540D01*
X290726Y103040D01*
X290559Y102374D01*
X290726Y101707D01*
X291059Y101207D01*
X291559Y100874D01*
X292142Y100707D01*
X292726Y100790D01*
X293226Y101040D01*
X293559Y101374D01*
G01X296242Y100707D02*
Y104040D01*
G01Y103207D02*
X296576Y103624D01*
X297076Y103957D01*
X297742Y104040D01*
X298326Y103957D01*
X298826Y103624D01*
X299076Y103040D01*
Y100707D01*
G01X304759Y105707D02*
Y100707D01*
G01Y101457D02*
X304426Y101040D01*
X303926Y100790D01*
X303342Y100707D01*
X302676Y100874D01*
X302176Y101290D01*
X301842Y101790D01*
X301759Y102374D01*
X301842Y102957D01*
X302176Y103457D01*
X302676Y103874D01*
X303342Y104040D01*
X303926Y103957D01*
X304342Y103790D01*
X304759Y103457D01*
G01X313209Y101290D02*
X313626Y100957D01*
X314209Y100707D01*
X314709D01*
X315209Y100874D01*
X315542Y101124D01*
X315709Y101457D01*
X315626Y101957D01*
X315292Y102207D01*
X313792Y102707D01*
X313459Y103290D01*
X313626Y103707D01*
X313959Y103957D01*
X314459Y104040D01*
X314959Y103957D01*
X315459Y103707D01*
G01X321559Y99040D02*
Y104040D01*
G01Y103290D02*
X321142Y103707D01*
X320642Y103957D01*
X320059Y104040D01*
X319559Y103957D01*
X318976Y103540D01*
X318642Y102957D01*
X318559Y102374D01*
X318642Y101790D01*
X318976Y101207D01*
X319559Y100790D01*
X320059Y100707D01*
X320642Y100790D01*
X321142Y101040D01*
X321559Y101457D01*
G01X324242Y104040D02*
Y101707D01*
X324576Y101124D01*
X325076Y100790D01*
X325659Y100707D01*
X326242Y100790D01*
X326742Y101124D01*
X327076Y101707D01*
G01Y100707D02*
Y104040D01*
G01X332759Y100707D02*
Y104040D01*
G01Y103457D02*
X332426Y103790D01*
X331926Y103957D01*
X331342Y104040D01*
X330759Y103874D01*
X330259Y103540D01*
X329926Y103040D01*
X329759Y102374D01*
X329926Y101707D01*
X330259Y101207D01*
X330759Y100874D01*
X331342Y100707D01*
X331926Y100790D01*
X332426Y101040D01*
X332759Y101374D01*
G01X335692Y100707D02*
Y104040D01*
G01Y103374D02*
X336109Y103707D01*
X336526Y103957D01*
X337109Y104040D01*
X337526Y103957D01*
X338026Y103707D01*
G01X341209Y102957D02*
X343876D01*
X343626Y103540D01*
X343209Y103874D01*
X342626Y104040D01*
X342042Y103957D01*
X341542Y103707D01*
X341209Y103124D01*
X341042Y102624D01*
Y102124D01*
X341209Y101624D01*
X341626Y101124D01*
X342126Y100790D01*
X342709Y100707D01*
X343292Y100874D01*
X343876Y101374D01*
G01X352242Y100707D02*
Y105707D01*
G01Y103290D02*
X352659Y103707D01*
X353076Y103957D01*
X353742Y104040D01*
X354242Y103957D01*
X354826Y103624D01*
X355076Y103124D01*
Y100707D01*
G01X359259D02*
X358759Y100790D01*
X358259Y101124D01*
X357926Y101707D01*
X357759Y102374D01*
X357926Y103040D01*
X358259Y103624D01*
X358759Y103957D01*
X359259Y104040D01*
X359759Y103957D01*
X360259Y103624D01*
X360592Y103040D01*
X360676Y102374D01*
X360592Y101707D01*
X360259Y101124D01*
X359759Y100790D01*
X359259Y100707D01*
G01X364859D02*
Y105707D01*
G01X369209Y102957D02*
X371876D01*
X371626Y103540D01*
X371209Y103874D01*
X370626Y104040D01*
X370042Y103957D01*
X369542Y103707D01*
X369209Y103124D01*
X369042Y102624D01*
Y102124D01*
X369209Y101624D01*
X369626Y101124D01*
X370126Y100790D01*
X370709Y100707D01*
X371292Y100874D01*
X371876Y101374D01*
G01X376059Y100540D02*
X375892Y100624D01*
Y100790D01*
X376059Y100874D01*
X376226Y100790D01*
Y100624D01*
X376059Y100540D01*
G01Y102790D02*
X375892Y102874D01*
Y103040D01*
X376059Y103124D01*
X376226Y103040D01*
Y102874D01*
X376059Y102790D01*
G01X215976Y142947D02*
X218059Y137947D01*
X220142Y142947D01*
G01X223659Y141280D02*
Y137947D01*
G01Y142614D02*
X223492Y142697D01*
Y142864D01*
X223659Y142947D01*
X223826Y142864D01*
Y142697D01*
X223659Y142614D01*
G01X230759Y137947D02*
Y141280D01*
G01Y140697D02*
X230426Y141030D01*
X229926Y141197D01*
X229342Y141280D01*
X228759Y141114D01*
X228259Y140780D01*
X227926Y140280D01*
X227759Y139614D01*
X227926Y138947D01*
X228259Y138447D01*
X228759Y138114D01*
X229342Y137947D01*
X229926Y138030D01*
X230426Y138280D01*
X230759Y138614D01*
G01X239459Y142947D02*
X241459D01*
G01X240459D02*
Y137947D01*
G01X239459D02*
X241459D01*
G01X244642D02*
Y141280D01*
G01Y140447D02*
X244976Y140864D01*
X245476Y141197D01*
X246142Y141280D01*
X246726Y141197D01*
X247226Y140864D01*
X247476Y140280D01*
Y137947D01*
G01X255592D02*
Y142947D01*
X257592D01*
X258259Y142697D01*
X258759Y142114D01*
X258926Y141447D01*
X258759Y140780D01*
X258342Y140280D01*
X257592Y140030D01*
X255592D01*
G01X264359Y137947D02*
Y141280D01*
G01Y140697D02*
X264026Y141030D01*
X263526Y141197D01*
X262942Y141280D01*
X262359Y141114D01*
X261859Y140780D01*
X261526Y140280D01*
X261359Y139614D01*
X261526Y138947D01*
X261859Y138447D01*
X262359Y138114D01*
X262942Y137947D01*
X263526Y138030D01*
X264026Y138280D01*
X264359Y138614D01*
G01X269959Y142947D02*
Y137947D01*
G01Y138697D02*
X269626Y138280D01*
X269126Y138030D01*
X268542Y137947D01*
X267876Y138114D01*
X267376Y138530D01*
X267042Y139030D01*
X266959Y139614D01*
X267042Y140197D01*
X267376Y140697D01*
X267876Y141114D01*
X268542Y141280D01*
X269126Y141197D01*
X269542Y141030D01*
X269959Y140697D01*
G01X273642Y136280D02*
X272809Y137114D01*
X272392Y137947D01*
Y141280D01*
X272809Y142114D01*
X273642Y142947D01*
G01X277576D02*
X279659Y137947D01*
X281742Y142947D01*
G01X284259D02*
X286259D01*
G01X285259D02*
Y137947D01*
G01X284259D02*
X286259D01*
G01X289192D02*
Y142947D01*
X291192D01*
X291859Y142697D01*
X292359Y142114D01*
X292526Y141447D01*
X292359Y140780D01*
X291942Y140280D01*
X291192Y140030D01*
X289192D01*
G01X296876Y136280D02*
X297709Y137114D01*
X298126Y137947D01*
Y141280D01*
X297709Y142114D01*
X296876Y142947D01*
G01X207759Y86707D02*
X837759D01*
G01X207759Y116707D02*
X837759D01*
G01X215866Y159510D02*
X219532Y163177D01*
G01X217699Y163844D02*
Y158844D01*
G01X219532Y159510D02*
X215866Y163177D01*
G01X215199Y161344D02*
X220199D01*
G01X222882Y158010D02*
X222049Y158844D01*
X221632Y159677D01*
Y163010D01*
X222049Y163844D01*
X222882Y164677D01*
G01X227066Y160427D02*
X227566Y160010D01*
X228149Y159760D01*
X228899Y159677D01*
X229649Y159844D01*
X230232Y160177D01*
X230649Y160760D01*
X230732Y161427D01*
X230566Y162094D01*
X230149Y162510D01*
X229566Y162844D01*
X228982Y162927D01*
X228399Y162844D01*
X227649Y162510D01*
X227899Y164677D01*
X230149D01*
G01X234499Y159510D02*
X234332Y159594D01*
Y159760D01*
X234499Y159844D01*
X234666Y159760D01*
Y159594D01*
X234499Y159510D01*
G01X240099Y159677D02*
Y164677D01*
X239099Y163677D01*
G01Y159677D02*
X241099D01*
G01X246116Y158010D02*
X246949Y158844D01*
X247366Y159677D01*
Y163010D01*
X246949Y163844D01*
X246116Y164677D01*
G01X215676Y175707D02*
X217759Y170707D01*
X219842Y175707D01*
G01X223359Y174040D02*
Y170707D01*
G01Y175374D02*
X223192Y175457D01*
Y175624D01*
X223359Y175707D01*
X223526Y175624D01*
Y175457D01*
X223359Y175374D01*
G01X230459Y170707D02*
Y174040D01*
G01Y173457D02*
X230126Y173790D01*
X229626Y173957D01*
X229042Y174040D01*
X228459Y173874D01*
X227959Y173540D01*
X227626Y173040D01*
X227459Y172374D01*
X227626Y171707D01*
X227959Y171207D01*
X228459Y170874D01*
X229042Y170707D01*
X229626Y170790D01*
X230126Y171040D01*
X230459Y171374D01*
G01X240159Y170707D02*
X239492Y170790D01*
X238909Y171124D01*
X238409Y171624D01*
X238076Y172207D01*
X237909Y172874D01*
Y173540D01*
X238076Y174207D01*
X238409Y174790D01*
X238909Y175290D01*
X239492Y175624D01*
X240159Y175707D01*
X240826Y175624D01*
X241409Y175290D01*
X241909Y174790D01*
X242242Y174207D01*
X242409Y173540D01*
Y172874D01*
X242242Y172207D01*
X241909Y171624D01*
X241409Y171124D01*
X240826Y170790D01*
X240159Y170707D01*
G01X244342D02*
Y174040D01*
G01Y173207D02*
X244676Y173624D01*
X245176Y173957D01*
X245842Y174040D01*
X246426Y173957D01*
X246926Y173624D01*
X247176Y173040D01*
Y170707D01*
G01X255292D02*
Y175707D01*
X257292D01*
X257959Y175457D01*
X258459Y174874D01*
X258626Y174207D01*
X258459Y173540D01*
X258042Y173040D01*
X257292Y172790D01*
X255292D01*
G01X264059Y170707D02*
Y174040D01*
G01Y173457D02*
X263726Y173790D01*
X263226Y173957D01*
X262642Y174040D01*
X262059Y173874D01*
X261559Y173540D01*
X261226Y173040D01*
X261059Y172374D01*
X261226Y171707D01*
X261559Y171207D01*
X262059Y170874D01*
X262642Y170707D01*
X263226Y170790D01*
X263726Y171040D01*
X264059Y171374D01*
G01X269659Y175707D02*
Y170707D01*
G01Y171457D02*
X269326Y171040D01*
X268826Y170790D01*
X268242Y170707D01*
X267576Y170874D01*
X267076Y171290D01*
X266742Y171790D01*
X266659Y172374D01*
X266742Y172957D01*
X267076Y173457D01*
X267576Y173874D01*
X268242Y174040D01*
X268826Y173957D01*
X269242Y173790D01*
X269659Y173457D01*
G01X273342Y169040D02*
X272509Y169874D01*
X272092Y170707D01*
Y174040D01*
X272509Y174874D01*
X273342Y175707D01*
G01X277276D02*
X279359Y170707D01*
X281442Y175707D01*
G01X284959Y170707D02*
X284292Y170790D01*
X283709Y171124D01*
X283209Y171624D01*
X282876Y172207D01*
X282709Y172874D01*
Y173540D01*
X282876Y174207D01*
X283209Y174790D01*
X283709Y175290D01*
X284292Y175624D01*
X284959Y175707D01*
X285626Y175624D01*
X286209Y175290D01*
X286709Y174790D01*
X287042Y174207D01*
X287209Y173540D01*
Y172874D01*
X287042Y172207D01*
X286709Y171624D01*
X286209Y171124D01*
X285626Y170790D01*
X284959Y170707D01*
G01X288892D02*
Y175707D01*
X290892D01*
X291559Y175457D01*
X292059Y174874D01*
X292226Y174207D01*
X292059Y173540D01*
X291642Y173040D01*
X290892Y172790D01*
X288892D01*
G01X296576Y169040D02*
X297409Y169874D01*
X297826Y170707D01*
Y174040D01*
X297409Y174874D01*
X296576Y175707D01*
G01X218426Y194374D02*
X218759Y194624D01*
X219009Y195040D01*
X219176Y195624D01*
X219009Y196124D01*
X218676Y196457D01*
X218092Y196707D01*
X215842D01*
Y191707D01*
X218592D01*
X219176Y192040D01*
X219509Y192540D01*
X219676Y193124D01*
X219509Y193707D01*
X219009Y194207D01*
X218426Y194374D01*
X215842D01*
G01X221942Y195040D02*
Y192707D01*
X222276Y192124D01*
X222776Y191790D01*
X223359Y191707D01*
X223942Y191790D01*
X224442Y192124D01*
X224776Y192707D01*
G01Y191707D02*
Y195040D01*
G01X227792Y191707D02*
Y195040D01*
G01Y194374D02*
X228209Y194707D01*
X228626Y194957D01*
X229209Y195040D01*
X229626Y194957D01*
X230126Y194707D01*
G01X234559Y195040D02*
Y191707D01*
G01Y196374D02*
X234392Y196457D01*
Y196624D01*
X234559Y196707D01*
X234726Y196624D01*
Y196457D01*
X234559Y196374D01*
G01X238909Y193957D02*
X241576D01*
X241326Y194540D01*
X240909Y194874D01*
X240326Y195040D01*
X239742Y194957D01*
X239242Y194707D01*
X238909Y194124D01*
X238742Y193624D01*
Y193124D01*
X238909Y192624D01*
X239326Y192124D01*
X239826Y191790D01*
X240409Y191707D01*
X240992Y191874D01*
X241576Y192374D01*
G01X247259Y196707D02*
Y191707D01*
G01Y192457D02*
X246926Y192040D01*
X246426Y191790D01*
X245842Y191707D01*
X245176Y191874D01*
X244676Y192290D01*
X244342Y192790D01*
X244259Y193374D01*
X244342Y193957D01*
X244676Y194457D01*
X245176Y194874D01*
X245842Y195040D01*
X246426Y194957D01*
X246842Y194790D01*
X247259Y194457D01*
G01X255542Y191707D02*
Y196707D01*
G01Y194290D02*
X255959Y194707D01*
X256376Y194957D01*
X257042Y195040D01*
X257542Y194957D01*
X258126Y194624D01*
X258376Y194124D01*
Y191707D01*
G01X262559D02*
X262059Y191790D01*
X261559Y192124D01*
X261226Y192707D01*
X261059Y193374D01*
X261226Y194040D01*
X261559Y194624D01*
X262059Y194957D01*
X262559Y195040D01*
X263059Y194957D01*
X263559Y194624D01*
X263892Y194040D01*
X263976Y193374D01*
X263892Y192707D01*
X263559Y192124D01*
X263059Y191790D01*
X262559Y191707D01*
G01X268159D02*
Y196707D01*
G01X272509Y193957D02*
X275176D01*
X274926Y194540D01*
X274509Y194874D01*
X273926Y195040D01*
X273342Y194957D01*
X272842Y194707D01*
X272509Y194124D01*
X272342Y193624D01*
Y193124D01*
X272509Y192624D01*
X272926Y192124D01*
X273426Y191790D01*
X274009Y191707D01*
X274592Y191874D01*
X275176Y192374D01*
G01X216176Y212707D02*
Y217707D01*
X219342D01*
G01X218176Y215290D02*
X216176D01*
G01X221942Y216040D02*
Y213707D01*
X222276Y213124D01*
X222776Y212790D01*
X223359Y212707D01*
X223942Y212790D01*
X224442Y213124D01*
X224776Y213707D01*
G01Y212707D02*
Y216040D01*
G01X228959Y212707D02*
Y217707D01*
G01X234559Y212707D02*
Y217707D01*
G01X244259Y211040D02*
Y216040D01*
G01Y215290D02*
X244676Y215707D01*
X245092Y215957D01*
X245759Y216040D01*
X246342Y215957D01*
X246926Y215540D01*
X247176Y214957D01*
X247259Y214374D01*
X247176Y213790D01*
X246926Y213207D01*
X246426Y212874D01*
X245759Y212707D01*
X245176Y212790D01*
X244592Y213040D01*
X244259Y213374D01*
G01X251359Y212707D02*
Y217707D01*
G01X255542Y216040D02*
Y213707D01*
X255876Y213124D01*
X256376Y212790D01*
X256959Y212707D01*
X257542Y212790D01*
X258042Y213124D01*
X258376Y213707D01*
G01Y212707D02*
Y216040D01*
G01X261392Y211457D02*
X261976Y211124D01*
X262642Y211040D01*
X263226Y211124D01*
X263726Y211540D01*
X264059Y212124D01*
Y216040D01*
G01Y215374D02*
X263726Y215707D01*
X263226Y215957D01*
X262642Y216040D01*
X261976Y215874D01*
X261559Y215540D01*
X261226Y214957D01*
X261059Y214374D01*
X261142Y213874D01*
X261476Y213290D01*
X261976Y212874D01*
X262642Y212707D01*
X263142Y212790D01*
X263726Y213124D01*
X264059Y213457D01*
G01X266992Y211457D02*
X267576Y211124D01*
X268242Y211040D01*
X268826Y211124D01*
X269326Y211540D01*
X269659Y212124D01*
Y216040D01*
G01Y215374D02*
X269326Y215707D01*
X268826Y215957D01*
X268242Y216040D01*
X267576Y215874D01*
X267159Y215540D01*
X266826Y214957D01*
X266659Y214374D01*
X266742Y213874D01*
X267076Y213290D01*
X267576Y212874D01*
X268242Y212707D01*
X268742Y212790D01*
X269326Y213124D01*
X269659Y213457D01*
G01X273759Y216040D02*
Y212707D01*
G01Y217374D02*
X273592Y217457D01*
Y217624D01*
X273759Y217707D01*
X273926Y217624D01*
Y217457D01*
X273759Y217374D01*
G01X277942Y212707D02*
Y216040D01*
G01Y215207D02*
X278276Y215624D01*
X278776Y215957D01*
X279442Y216040D01*
X280026Y215957D01*
X280526Y215624D01*
X280776Y215040D01*
Y212707D01*
G01X283792Y211457D02*
X284376Y211124D01*
X285042Y211040D01*
X285626Y211124D01*
X286126Y211540D01*
X286459Y212124D01*
Y216040D01*
G01Y215374D02*
X286126Y215707D01*
X285626Y215957D01*
X285042Y216040D01*
X284376Y215874D01*
X283959Y215540D01*
X283626Y214957D01*
X283459Y214374D01*
X283542Y213874D01*
X283876Y213290D01*
X284376Y212874D01*
X285042Y212707D01*
X285542Y212790D01*
X286126Y213124D01*
X286459Y213457D01*
G01X207759Y151707D02*
X837759D01*
G01X207759Y186707D02*
X837759D01*
G01X207759Y201707D02*
X837759D01*
G01X216009Y281207D02*
Y286207D01*
G01X219509D02*
Y281207D01*
G01Y283707D02*
X216009D01*
G01X224859Y281207D02*
Y284540D01*
G01Y283957D02*
X224526Y284290D01*
X224026Y284457D01*
X223442Y284540D01*
X222859Y284374D01*
X222359Y284040D01*
X222026Y283540D01*
X221859Y282874D01*
X222026Y282207D01*
X222359Y281707D01*
X222859Y281374D01*
X223442Y281207D01*
X224026Y281290D01*
X224526Y281540D01*
X224859Y281874D01*
G01X228959Y281207D02*
Y286207D01*
G01X234059Y281207D02*
Y285457D01*
X234226Y285874D01*
X234559Y286124D01*
X235059Y286207D01*
X235559Y286040D01*
X235809Y285624D01*
G01X234809Y284207D02*
X233142D01*
G01X244092Y281207D02*
Y286207D01*
X246092D01*
X246759Y285957D01*
X247259Y285374D01*
X247426Y284707D01*
X247259Y284040D01*
X246842Y283540D01*
X246092Y283290D01*
X244092D01*
G01X251359Y281207D02*
Y286207D01*
G01X255542Y284540D02*
Y282207D01*
X255876Y281624D01*
X256376Y281290D01*
X256959Y281207D01*
X257542Y281290D01*
X258042Y281624D01*
X258376Y282207D01*
G01Y281207D02*
Y284540D01*
G01X261392Y279957D02*
X261976Y279624D01*
X262642Y279540D01*
X263226Y279624D01*
X263726Y280040D01*
X264059Y280624D01*
Y284540D01*
G01Y283874D02*
X263726Y284207D01*
X263226Y284457D01*
X262642Y284540D01*
X261976Y284374D01*
X261559Y284040D01*
X261226Y283457D01*
X261059Y282874D01*
X261142Y282374D01*
X261476Y281790D01*
X261976Y281374D01*
X262642Y281207D01*
X263142Y281290D01*
X263726Y281624D01*
X264059Y281957D01*
G01X266992Y279957D02*
X267576Y279624D01*
X268242Y279540D01*
X268826Y279624D01*
X269326Y280040D01*
X269659Y280624D01*
Y284540D01*
G01Y283874D02*
X269326Y284207D01*
X268826Y284457D01*
X268242Y284540D01*
X267576Y284374D01*
X267159Y284040D01*
X266826Y283457D01*
X266659Y282874D01*
X266742Y282374D01*
X267076Y281790D01*
X267576Y281374D01*
X268242Y281207D01*
X268742Y281290D01*
X269326Y281624D01*
X269659Y281957D01*
G01X273759Y284540D02*
Y281207D01*
G01Y285874D02*
X273592Y285957D01*
Y286124D01*
X273759Y286207D01*
X273926Y286124D01*
Y285957D01*
X273759Y285874D01*
G01X277942Y281207D02*
Y284540D01*
G01Y283707D02*
X278276Y284124D01*
X278776Y284457D01*
X279442Y284540D01*
X280026Y284457D01*
X280526Y284124D01*
X280776Y283540D01*
Y281207D01*
G01X283792Y279957D02*
X284376Y279624D01*
X285042Y279540D01*
X285626Y279624D01*
X286126Y280040D01*
X286459Y280624D01*
Y284540D01*
G01Y283874D02*
X286126Y284207D01*
X285626Y284457D01*
X285042Y284540D01*
X284376Y284374D01*
X283959Y284040D01*
X283626Y283457D01*
X283459Y282874D01*
X283542Y282374D01*
X283876Y281790D01*
X284376Y281374D01*
X285042Y281207D01*
X285542Y281290D01*
X286126Y281624D01*
X286459Y281957D01*
G01X207759Y228707D02*
X837759D01*
G01X217592Y340207D02*
Y345207D01*
X219592D01*
X220259Y344957D01*
X220759Y344374D01*
X220926Y343707D01*
X220759Y343040D01*
X220342Y342540D01*
X219592Y342290D01*
X217592D01*
G01X224859Y340207D02*
Y345207D01*
G01X229042Y343540D02*
Y341207D01*
X229376Y340624D01*
X229876Y340290D01*
X230459Y340207D01*
X231042Y340290D01*
X231542Y340624D01*
X231876Y341207D01*
G01Y340207D02*
Y343540D01*
G01X234892Y338957D02*
X235476Y338624D01*
X236142Y338540D01*
X236726Y338624D01*
X237226Y339040D01*
X237559Y339624D01*
Y343540D01*
G01Y342874D02*
X237226Y343207D01*
X236726Y343457D01*
X236142Y343540D01*
X235476Y343374D01*
X235059Y343040D01*
X234726Y342457D01*
X234559Y341874D01*
X234642Y341374D01*
X234976Y340790D01*
X235476Y340374D01*
X236142Y340207D01*
X236642Y340290D01*
X237226Y340624D01*
X237559Y340957D01*
G01X240492Y338957D02*
X241076Y338624D01*
X241742Y338540D01*
X242326Y338624D01*
X242826Y339040D01*
X243159Y339624D01*
Y343540D01*
G01Y342874D02*
X242826Y343207D01*
X242326Y343457D01*
X241742Y343540D01*
X241076Y343374D01*
X240659Y343040D01*
X240326Y342457D01*
X240159Y341874D01*
X240242Y341374D01*
X240576Y340790D01*
X241076Y340374D01*
X241742Y340207D01*
X242242Y340290D01*
X242826Y340624D01*
X243159Y340957D01*
G01X247259Y343540D02*
Y340207D01*
G01Y344874D02*
X247092Y344957D01*
Y345124D01*
X247259Y345207D01*
X247426Y345124D01*
Y344957D01*
X247259Y344874D01*
G01X251442Y340207D02*
Y343540D01*
G01Y342707D02*
X251776Y343124D01*
X252276Y343457D01*
X252942Y343540D01*
X253526Y343457D01*
X254026Y343124D01*
X254276Y342540D01*
Y340207D01*
G01X257292Y338957D02*
X257876Y338624D01*
X258542Y338540D01*
X259126Y338624D01*
X259626Y339040D01*
X259959Y339624D01*
Y343540D01*
G01Y342874D02*
X259626Y343207D01*
X259126Y343457D01*
X258542Y343540D01*
X257876Y343374D01*
X257459Y343040D01*
X257126Y342457D01*
X256959Y341874D01*
X257042Y341374D01*
X257376Y340790D01*
X257876Y340374D01*
X258542Y340207D01*
X259042Y340290D01*
X259626Y340624D01*
X259959Y340957D01*
G01X271159Y345207D02*
Y340207D01*
G01Y340957D02*
X270826Y340540D01*
X270326Y340290D01*
X269742Y340207D01*
X269076Y340374D01*
X268576Y340790D01*
X268242Y341290D01*
X268159Y341874D01*
X268242Y342457D01*
X268576Y342957D01*
X269076Y343374D01*
X269742Y343540D01*
X270326Y343457D01*
X270742Y343290D01*
X271159Y342957D01*
G01X274009Y342457D02*
X276676D01*
X276426Y343040D01*
X276009Y343374D01*
X275426Y343540D01*
X274842Y343457D01*
X274342Y343207D01*
X274009Y342624D01*
X273842Y342124D01*
Y341624D01*
X274009Y341124D01*
X274426Y340624D01*
X274926Y340290D01*
X275509Y340207D01*
X276092Y340374D01*
X276676Y340874D01*
G01X280359Y340207D02*
Y344457D01*
X280526Y344874D01*
X280859Y345124D01*
X281359Y345207D01*
X281859Y345040D01*
X282109Y344624D01*
G01X281109Y343207D02*
X279442D01*
G01X286459Y343540D02*
Y340207D01*
G01Y344874D02*
X286292Y344957D01*
Y345124D01*
X286459Y345207D01*
X286626Y345124D01*
Y344957D01*
X286459Y344874D01*
G01X290642Y340207D02*
Y343540D01*
G01Y342707D02*
X290976Y343124D01*
X291476Y343457D01*
X292142Y343540D01*
X292726Y343457D01*
X293226Y343124D01*
X293476Y342540D01*
Y340207D01*
G01X296409Y342457D02*
X299076D01*
X298826Y343040D01*
X298409Y343374D01*
X297826Y343540D01*
X297242Y343457D01*
X296742Y343207D01*
X296409Y342624D01*
X296242Y342124D01*
Y341624D01*
X296409Y341124D01*
X296826Y340624D01*
X297326Y340290D01*
X297909Y340207D01*
X298492Y340374D01*
X299076Y340874D01*
G01X207759Y330707D02*
X837759D01*
G01X207759Y355707D02*
X837759D01*
G01X217426Y516207D02*
X217926Y515624D01*
X218592Y515290D01*
X219342Y515207D01*
X220009Y515290D01*
X220676Y515707D01*
X221092Y516207D01*
X221176Y516707D01*
X221009Y517290D01*
X220426Y517707D01*
X219842Y517874D01*
X219092D01*
G01X219842D02*
X220342Y518124D01*
X220759Y518540D01*
X220926Y519040D01*
X220759Y519540D01*
X220342Y519957D01*
X219592Y520207D01*
X218842Y520124D01*
X218092Y519790D01*
G01X224859Y515040D02*
X224692Y515124D01*
Y515290D01*
X224859Y515374D01*
X225026Y515290D01*
Y515124D01*
X224859Y515040D01*
G01X234392Y515207D02*
Y520207D01*
X236392D01*
X237059Y519957D01*
X237559Y519374D01*
X237726Y518707D01*
X237559Y518040D01*
X237142Y517540D01*
X236392Y517290D01*
X234392D01*
G01X241659Y515207D02*
Y520207D01*
G01X245842Y518540D02*
Y516207D01*
X246176Y515624D01*
X246676Y515290D01*
X247259Y515207D01*
X247842Y515290D01*
X248342Y515624D01*
X248676Y516207D01*
G01Y515207D02*
Y518540D01*
G01X251692Y513957D02*
X252276Y513624D01*
X252942Y513540D01*
X253526Y513624D01*
X254026Y514040D01*
X254359Y514624D01*
Y518540D01*
G01Y517874D02*
X254026Y518207D01*
X253526Y518457D01*
X252942Y518540D01*
X252276Y518374D01*
X251859Y518040D01*
X251526Y517457D01*
X251359Y516874D01*
X251442Y516374D01*
X251776Y515790D01*
X252276Y515374D01*
X252942Y515207D01*
X253442Y515290D01*
X254026Y515624D01*
X254359Y515957D01*
G01X262559Y518540D02*
X264059Y515207D01*
X265559Y518540D01*
G01X269659D02*
Y515207D01*
G01Y519874D02*
X269492Y519957D01*
Y520124D01*
X269659Y520207D01*
X269826Y520124D01*
Y519957D01*
X269659Y519874D01*
G01X276759Y515207D02*
Y518540D01*
G01Y517957D02*
X276426Y518290D01*
X275926Y518457D01*
X275342Y518540D01*
X274759Y518374D01*
X274259Y518040D01*
X273926Y517540D01*
X273759Y516874D01*
X273926Y516207D01*
X274259Y515707D01*
X274759Y515374D01*
X275342Y515207D01*
X275926Y515290D01*
X276426Y515540D01*
X276759Y515874D01*
G01X284959Y515040D02*
X287959Y520207D01*
G01X289976D02*
X292059Y515207D01*
X294142Y520207D01*
G01X297659Y515207D02*
X296992Y515290D01*
X296409Y515624D01*
X295909Y516124D01*
X295576Y516707D01*
X295409Y517374D01*
Y518040D01*
X295576Y518707D01*
X295909Y519290D01*
X296409Y519790D01*
X296992Y520124D01*
X297659Y520207D01*
X298326Y520124D01*
X298909Y519790D01*
X299409Y519290D01*
X299742Y518707D01*
X299909Y518040D01*
Y517374D01*
X299742Y516707D01*
X299409Y516124D01*
X298909Y515624D01*
X298326Y515290D01*
X297659Y515207D01*
G01X301592D02*
Y520207D01*
X303592D01*
X304259Y519957D01*
X304759Y519374D01*
X304926Y518707D01*
X304759Y518040D01*
X304342Y517540D01*
X303592Y517290D01*
X301592D01*
G01X307359Y515040D02*
X310359Y520207D01*
G01X312376D02*
X314459Y515207D01*
X316542Y520207D01*
G01X319059D02*
X321059D01*
G01X320059D02*
Y515207D01*
G01X319059D02*
X321059D01*
G01X323992D02*
Y520207D01*
X325992D01*
X326659Y519957D01*
X327159Y519374D01*
X327326Y518707D01*
X327159Y518040D01*
X326742Y517540D01*
X325992Y517290D01*
X323992D01*
G01X331259Y515040D02*
X331092Y515124D01*
Y515290D01*
X331259Y515374D01*
X331426Y515290D01*
Y515124D01*
X331259Y515040D01*
G01Y517290D02*
X331092Y517374D01*
Y517540D01*
X331259Y517624D01*
X331426Y517540D01*
Y517374D01*
X331259Y517290D01*
G01X207759Y503207D02*
X839259D01*
G01X219572Y564207D02*
Y569207D01*
X221656D01*
X222322Y568957D01*
X222739Y568624D01*
X222906Y567957D01*
X222739Y567290D01*
X222239Y566874D01*
X221656Y566624D01*
X219572D01*
G01X221656D02*
X222906Y564207D01*
G01X226839D02*
X226339Y564290D01*
X225839Y564624D01*
X225506Y565207D01*
X225339Y565874D01*
X225506Y566540D01*
X225839Y567124D01*
X226339Y567457D01*
X226839Y567540D01*
X227339Y567457D01*
X227839Y567124D01*
X228172Y566540D01*
X228256Y565874D01*
X228172Y565207D01*
X227839Y564624D01*
X227339Y564290D01*
X226839Y564207D01*
G01X231022Y567540D02*
Y565207D01*
X231356Y564624D01*
X231856Y564290D01*
X232439Y564207D01*
X233022Y564290D01*
X233522Y564624D01*
X233856Y565207D01*
G01Y564207D02*
Y567540D01*
G01X238039Y569207D02*
Y564207D01*
G01X236872Y567540D02*
X239206D01*
G01X243639D02*
Y564207D01*
G01Y568874D02*
X243472Y568957D01*
Y569124D01*
X243639Y569207D01*
X243806Y569124D01*
Y568957D01*
X243639Y568874D01*
G01X247822Y564207D02*
Y567540D01*
G01Y566707D02*
X248156Y567124D01*
X248656Y567457D01*
X249322Y567540D01*
X249906Y567457D01*
X250406Y567124D01*
X250656Y566540D01*
Y564207D01*
G01X253672Y562957D02*
X254256Y562624D01*
X254922Y562540D01*
X255506Y562624D01*
X256006Y563040D01*
X256339Y563624D01*
Y567540D01*
G01Y566874D02*
X256006Y567207D01*
X255506Y567457D01*
X254922Y567540D01*
X254256Y567374D01*
X253839Y567040D01*
X253506Y566457D01*
X253339Y565874D01*
X253422Y565374D01*
X253756Y564790D01*
X254256Y564374D01*
X254922Y564207D01*
X255422Y564290D01*
X256006Y564624D01*
X256339Y564957D01*
G01X207739Y601707D02*
X837759D01*
G01X231696Y-314113D02*
X232196Y-314530D01*
X232779Y-314780D01*
X233529Y-314863D01*
X234279Y-314696D01*
X234862Y-314363D01*
X235279Y-313780D01*
X235362Y-313113D01*
X235196Y-312446D01*
X234779Y-312030D01*
X234196Y-311696D01*
X233612Y-311613D01*
X233029Y-311696D01*
X232279Y-312030D01*
X232529Y-309863D01*
X234779D01*
G01X239129Y-315030D02*
X238962Y-314946D01*
Y-314780D01*
X239129Y-314696D01*
X239296Y-314780D01*
Y-314946D01*
X239129Y-315030D01*
G01X244729Y-314863D02*
Y-309863D01*
X243729Y-310863D01*
G01Y-314863D02*
X245729D01*
G01X254929Y-309863D02*
X256929D01*
G01X255929D02*
Y-314863D01*
G01X254929D02*
X256929D01*
G01X261029D02*
Y-310613D01*
X261196Y-310196D01*
X261529Y-309946D01*
X262029Y-309863D01*
X262529Y-310030D01*
X262779Y-310446D01*
G01X261779Y-311863D02*
X260112D01*
G01X273229Y-312363D02*
X274896D01*
Y-313863D01*
X274396Y-314363D01*
X273812Y-314696D01*
X272979Y-314863D01*
X272146Y-314696D01*
X271562Y-314363D01*
X271062Y-313863D01*
X270729Y-313280D01*
X270562Y-312613D01*
Y-312030D01*
X270729Y-311530D01*
X271062Y-310946D01*
X271562Y-310446D01*
X272062Y-310113D01*
X272729Y-309863D01*
X273312D01*
X273979Y-310030D01*
X274479Y-310363D01*
G01X277079Y-312613D02*
X279746D01*
X279496Y-312030D01*
X279079Y-311696D01*
X278496Y-311530D01*
X277912Y-311613D01*
X277412Y-311863D01*
X277079Y-312446D01*
X276912Y-312946D01*
Y-313446D01*
X277079Y-313946D01*
X277496Y-314446D01*
X277996Y-314780D01*
X278579Y-314863D01*
X279162Y-314696D01*
X279746Y-314196D01*
G01X282762Y-314863D02*
Y-311530D01*
G01Y-312196D02*
X283179Y-311863D01*
X283596Y-311613D01*
X284179Y-311530D01*
X284596Y-311613D01*
X285096Y-311863D01*
G01X288029Y-314863D02*
Y-309863D01*
G01Y-312363D02*
X288446Y-311863D01*
X288946Y-311613D01*
X289446Y-311530D01*
X290196Y-311696D01*
X290696Y-312030D01*
X291029Y-312613D01*
Y-313280D01*
X290862Y-313946D01*
X290529Y-314446D01*
X289946Y-314780D01*
X289446Y-314863D01*
X288946Y-314780D01*
X288446Y-314530D01*
X288029Y-314113D01*
G01X293879Y-312613D02*
X296546D01*
X296296Y-312030D01*
X295879Y-311696D01*
X295296Y-311530D01*
X294712Y-311613D01*
X294212Y-311863D01*
X293879Y-312446D01*
X293712Y-312946D01*
Y-313446D01*
X293879Y-313946D01*
X294296Y-314446D01*
X294796Y-314780D01*
X295379Y-314863D01*
X295962Y-314696D01*
X296546Y-314196D01*
G01X299562Y-314863D02*
Y-311530D01*
G01Y-312196D02*
X299979Y-311863D01*
X300396Y-311613D01*
X300979Y-311530D01*
X301396Y-311613D01*
X301896Y-311863D01*
G01X310512Y-314863D02*
Y-309863D01*
G01Y-312280D02*
X310929Y-311863D01*
X311346Y-311613D01*
X312012Y-311530D01*
X312512Y-311613D01*
X313096Y-311946D01*
X313346Y-312446D01*
Y-314863D01*
G01X319029D02*
Y-311530D01*
G01Y-312113D02*
X318696Y-311780D01*
X318196Y-311613D01*
X317612Y-311530D01*
X317029Y-311696D01*
X316529Y-312030D01*
X316196Y-312530D01*
X316029Y-313196D01*
X316196Y-313863D01*
X316529Y-314363D01*
X317029Y-314696D01*
X317612Y-314863D01*
X318196Y-314780D01*
X318696Y-314530D01*
X319029Y-314196D01*
G01X321879Y-314280D02*
X322296Y-314613D01*
X322879Y-314863D01*
X323379D01*
X323879Y-314696D01*
X324212Y-314446D01*
X324379Y-314113D01*
X324296Y-313613D01*
X323962Y-313363D01*
X322462Y-312863D01*
X322129Y-312280D01*
X322296Y-311863D01*
X322629Y-311613D01*
X323129Y-311530D01*
X323629Y-311613D01*
X324129Y-311863D01*
G01X334329Y-309863D02*
Y-314863D01*
G01X333162Y-311530D02*
X335496D01*
G01X338512Y-314863D02*
Y-309863D01*
G01Y-312280D02*
X338929Y-311863D01*
X339346Y-311613D01*
X340012Y-311530D01*
X340512Y-311613D01*
X341096Y-311946D01*
X341346Y-312446D01*
Y-314863D01*
G01X345529Y-311530D02*
Y-314863D01*
G01Y-310196D02*
X345362Y-310113D01*
Y-309946D01*
X345529Y-309863D01*
X345696Y-309946D01*
Y-310113D01*
X345529Y-310196D01*
G01X349879Y-314280D02*
X350296Y-314613D01*
X350879Y-314863D01*
X351379D01*
X351879Y-314696D01*
X352212Y-314446D01*
X352379Y-314113D01*
X352296Y-313613D01*
X351962Y-313363D01*
X350462Y-312863D01*
X350129Y-312280D01*
X350296Y-311863D01*
X350629Y-311613D01*
X351129Y-311530D01*
X351629Y-311613D01*
X352129Y-311863D01*
G01X360912Y-314863D02*
Y-309863D01*
G01X363579Y-311530D02*
X360912Y-313446D01*
G01X361996Y-312696D02*
X363746Y-314863D01*
G01X367929Y-311530D02*
Y-314863D01*
G01Y-310196D02*
X367762Y-310113D01*
Y-309946D01*
X367929Y-309863D01*
X368096Y-309946D01*
Y-310113D01*
X367929Y-310196D01*
G01X372112Y-314863D02*
Y-311530D01*
G01Y-312363D02*
X372446Y-311946D01*
X372946Y-311613D01*
X373612Y-311530D01*
X374196Y-311613D01*
X374696Y-311946D01*
X374946Y-312530D01*
Y-314863D01*
G01X380629Y-309863D02*
Y-314863D01*
G01Y-314113D02*
X380296Y-314530D01*
X379796Y-314780D01*
X379212Y-314863D01*
X378546Y-314696D01*
X378046Y-314280D01*
X377712Y-313780D01*
X377629Y-313196D01*
X377712Y-312613D01*
X378046Y-312113D01*
X378546Y-311696D01*
X379212Y-311530D01*
X379796Y-311613D01*
X380212Y-311780D01*
X380629Y-312113D01*
G01X390329Y-314863D02*
X389829Y-314780D01*
X389329Y-314446D01*
X388996Y-313863D01*
X388829Y-313196D01*
X388996Y-312530D01*
X389329Y-311946D01*
X389829Y-311613D01*
X390329Y-311530D01*
X390829Y-311613D01*
X391329Y-311946D01*
X391662Y-312530D01*
X391746Y-313196D01*
X391662Y-313863D01*
X391329Y-314446D01*
X390829Y-314780D01*
X390329Y-314863D01*
G01X395429D02*
Y-310613D01*
X395596Y-310196D01*
X395929Y-309946D01*
X396429Y-309863D01*
X396929Y-310030D01*
X397179Y-310446D01*
G01X396179Y-311863D02*
X394512D01*
G01X408629Y-309863D02*
Y-314863D01*
G01Y-314113D02*
X408296Y-314530D01*
X407796Y-314780D01*
X407212Y-314863D01*
X406546Y-314696D01*
X406046Y-314280D01*
X405712Y-313780D01*
X405629Y-313196D01*
X405712Y-312613D01*
X406046Y-312113D01*
X406546Y-311696D01*
X407212Y-311530D01*
X407796Y-311613D01*
X408212Y-311780D01*
X408629Y-312113D01*
G01X411479Y-312613D02*
X414146D01*
X413896Y-312030D01*
X413479Y-311696D01*
X412896Y-311530D01*
X412312Y-311613D01*
X411812Y-311863D01*
X411479Y-312446D01*
X411312Y-312946D01*
Y-313446D01*
X411479Y-313946D01*
X411896Y-314446D01*
X412396Y-314780D01*
X412979Y-314863D01*
X413562Y-314696D01*
X414146Y-314196D01*
G01X417079Y-314280D02*
X417496Y-314613D01*
X418079Y-314863D01*
X418579D01*
X419079Y-314696D01*
X419412Y-314446D01*
X419579Y-314113D01*
X419496Y-313613D01*
X419162Y-313363D01*
X417662Y-312863D01*
X417329Y-312280D01*
X417496Y-311863D01*
X417829Y-311613D01*
X418329Y-311530D01*
X418829Y-311613D01*
X419329Y-311863D01*
G01X423929Y-311530D02*
Y-314863D01*
G01Y-310196D02*
X423762Y-310113D01*
Y-309946D01*
X423929Y-309863D01*
X424096Y-309946D01*
Y-310113D01*
X423929Y-310196D01*
G01X428362Y-316113D02*
X428946Y-316446D01*
X429612Y-316530D01*
X430196Y-316446D01*
X430696Y-316030D01*
X431029Y-315446D01*
Y-311530D01*
G01Y-312196D02*
X430696Y-311863D01*
X430196Y-311613D01*
X429612Y-311530D01*
X428946Y-311696D01*
X428529Y-312030D01*
X428196Y-312613D01*
X428029Y-313196D01*
X428112Y-313696D01*
X428446Y-314280D01*
X428946Y-314696D01*
X429612Y-314863D01*
X430112Y-314780D01*
X430696Y-314446D01*
X431029Y-314113D01*
G01X433712Y-314863D02*
Y-311530D01*
G01Y-312363D02*
X434046Y-311946D01*
X434546Y-311613D01*
X435212Y-311530D01*
X435796Y-311613D01*
X436296Y-311946D01*
X436546Y-312530D01*
Y-314863D01*
G01X440562Y-315780D02*
X440896Y-314696D01*
G01X450429Y-316530D02*
Y-311530D01*
G01Y-312280D02*
X450846Y-311863D01*
X451262Y-311613D01*
X451929Y-311530D01*
X452512Y-311613D01*
X453096Y-312030D01*
X453346Y-312613D01*
X453429Y-313196D01*
X453346Y-313780D01*
X453096Y-314363D01*
X452596Y-314696D01*
X451929Y-314863D01*
X451346Y-314780D01*
X450762Y-314530D01*
X450429Y-314196D01*
G01X457529Y-314863D02*
Y-309863D01*
G01X461879Y-312613D02*
X464546D01*
X464296Y-312030D01*
X463879Y-311696D01*
X463296Y-311530D01*
X462712Y-311613D01*
X462212Y-311863D01*
X461879Y-312446D01*
X461712Y-312946D01*
Y-313446D01*
X461879Y-313946D01*
X462296Y-314446D01*
X462796Y-314780D01*
X463379Y-314863D01*
X463962Y-314696D01*
X464546Y-314196D01*
G01X470229Y-314863D02*
Y-311530D01*
G01Y-312113D02*
X469896Y-311780D01*
X469396Y-311613D01*
X468812Y-311530D01*
X468229Y-311696D01*
X467729Y-312030D01*
X467396Y-312530D01*
X467229Y-313196D01*
X467396Y-313863D01*
X467729Y-314363D01*
X468229Y-314696D01*
X468812Y-314863D01*
X469396Y-314780D01*
X469896Y-314530D01*
X470229Y-314196D01*
G01X473079Y-314280D02*
X473496Y-314613D01*
X474079Y-314863D01*
X474579D01*
X475079Y-314696D01*
X475412Y-314446D01*
X475579Y-314113D01*
X475496Y-313613D01*
X475162Y-313363D01*
X473662Y-312863D01*
X473329Y-312280D01*
X473496Y-311863D01*
X473829Y-311613D01*
X474329Y-311530D01*
X474829Y-311613D01*
X475329Y-311863D01*
G01X478679Y-312613D02*
X481346D01*
X481096Y-312030D01*
X480679Y-311696D01*
X480096Y-311530D01*
X479512Y-311613D01*
X479012Y-311863D01*
X478679Y-312446D01*
X478512Y-312946D01*
Y-313446D01*
X478679Y-313946D01*
X479096Y-314446D01*
X479596Y-314780D01*
X480179Y-314863D01*
X480762Y-314696D01*
X481346Y-314196D01*
G01X490629Y-314863D02*
Y-310613D01*
X490796Y-310196D01*
X491129Y-309946D01*
X491629Y-309863D01*
X492129Y-310030D01*
X492379Y-310446D01*
G01X491379Y-311863D02*
X489712D01*
G01X496729Y-314863D02*
X496229Y-314780D01*
X495729Y-314446D01*
X495396Y-313863D01*
X495229Y-313196D01*
X495396Y-312530D01*
X495729Y-311946D01*
X496229Y-311613D01*
X496729Y-311530D01*
X497229Y-311613D01*
X497729Y-311946D01*
X498062Y-312530D01*
X498146Y-313196D01*
X498062Y-313863D01*
X497729Y-314446D01*
X497229Y-314780D01*
X496729Y-314863D01*
G01X502329D02*
Y-309863D01*
G01X507929Y-314863D02*
Y-309863D01*
G01X513529Y-314863D02*
X513029Y-314780D01*
X512529Y-314446D01*
X512196Y-313863D01*
X512029Y-313196D01*
X512196Y-312530D01*
X512529Y-311946D01*
X513029Y-311613D01*
X513529Y-311530D01*
X514029Y-311613D01*
X514529Y-311946D01*
X514862Y-312530D01*
X514946Y-313196D01*
X514862Y-313863D01*
X514529Y-314446D01*
X514029Y-314780D01*
X513529Y-314863D01*
G01X517046Y-311530D02*
X518046Y-314863D01*
X519129Y-311530D01*
X520212Y-314863D01*
X521212Y-311530D01*
G01X524729Y-315030D02*
X524562Y-314946D01*
Y-314780D01*
X524729Y-314696D01*
X524896Y-314780D01*
Y-314946D01*
X524729Y-315030D01*
G01X534929Y-309863D02*
X536929D01*
G01X535929D02*
Y-314863D01*
G01X534929D02*
X536929D01*
G01X541029D02*
Y-310613D01*
X541196Y-310196D01*
X541529Y-309946D01*
X542029Y-309863D01*
X542529Y-310030D01*
X542779Y-310446D01*
G01X541779Y-311863D02*
X540112D01*
G01X551312Y-314863D02*
Y-311530D01*
G01Y-312363D02*
X551646Y-311946D01*
X552146Y-311613D01*
X552812Y-311530D01*
X553396Y-311613D01*
X553896Y-311946D01*
X554146Y-312530D01*
Y-314863D01*
G01X558329D02*
X557829Y-314780D01*
X557329Y-314446D01*
X556996Y-313863D01*
X556829Y-313196D01*
X556996Y-312530D01*
X557329Y-311946D01*
X557829Y-311613D01*
X558329Y-311530D01*
X558829Y-311613D01*
X559329Y-311946D01*
X559662Y-312530D01*
X559746Y-313196D01*
X559662Y-313863D01*
X559329Y-314446D01*
X558829Y-314780D01*
X558329Y-314863D01*
G01X563929Y-309863D02*
Y-314863D01*
G01X562762Y-311530D02*
X565096D01*
G01X569362Y-315780D02*
X569696Y-314696D01*
G01X579229Y-316530D02*
Y-311530D01*
G01Y-312280D02*
X579646Y-311863D01*
X580062Y-311613D01*
X580729Y-311530D01*
X581312Y-311613D01*
X581896Y-312030D01*
X582146Y-312613D01*
X582229Y-313196D01*
X582146Y-313780D01*
X581896Y-314363D01*
X581396Y-314696D01*
X580729Y-314863D01*
X580146Y-314780D01*
X579562Y-314530D01*
X579229Y-314196D01*
G01X586329Y-314863D02*
Y-309863D01*
G01X590679Y-312613D02*
X593346D01*
X593096Y-312030D01*
X592679Y-311696D01*
X592096Y-311530D01*
X591512Y-311613D01*
X591012Y-311863D01*
X590679Y-312446D01*
X590512Y-312946D01*
Y-313446D01*
X590679Y-313946D01*
X591096Y-314446D01*
X591596Y-314780D01*
X592179Y-314863D01*
X592762Y-314696D01*
X593346Y-314196D01*
G01X599029Y-314863D02*
Y-311530D01*
G01Y-312113D02*
X598696Y-311780D01*
X598196Y-311613D01*
X597612Y-311530D01*
X597029Y-311696D01*
X596529Y-312030D01*
X596196Y-312530D01*
X596029Y-313196D01*
X596196Y-313863D01*
X596529Y-314363D01*
X597029Y-314696D01*
X597612Y-314863D01*
X598196Y-314780D01*
X598696Y-314530D01*
X599029Y-314196D01*
G01X601879Y-314280D02*
X602296Y-314613D01*
X602879Y-314863D01*
X603379D01*
X603879Y-314696D01*
X604212Y-314446D01*
X604379Y-314113D01*
X604296Y-313613D01*
X603962Y-313363D01*
X602462Y-312863D01*
X602129Y-312280D01*
X602296Y-311863D01*
X602629Y-311613D01*
X603129Y-311530D01*
X603629Y-311613D01*
X604129Y-311863D01*
G01X607479Y-312613D02*
X610146D01*
X609896Y-312030D01*
X609479Y-311696D01*
X608896Y-311530D01*
X608312Y-311613D01*
X607812Y-311863D01*
X607479Y-312446D01*
X607312Y-312946D01*
Y-313446D01*
X607479Y-313946D01*
X607896Y-314446D01*
X608396Y-314780D01*
X608979Y-314863D01*
X609562Y-314696D01*
X610146Y-314196D01*
G01X619929Y-311530D02*
Y-314863D01*
G01Y-310196D02*
X619762Y-310113D01*
Y-309946D01*
X619929Y-309863D01*
X620096Y-309946D01*
Y-310113D01*
X619929Y-310196D01*
G01X627029Y-316530D02*
Y-311530D01*
G01Y-312280D02*
X626612Y-311863D01*
X626112Y-311613D01*
X625529Y-311530D01*
X625029Y-311613D01*
X624446Y-312030D01*
X624112Y-312613D01*
X624029Y-313196D01*
X624112Y-313780D01*
X624446Y-314363D01*
X625029Y-314780D01*
X625529Y-314863D01*
X626112Y-314780D01*
X626612Y-314530D01*
X627029Y-314113D01*
G01X629712Y-314863D02*
Y-311530D01*
G01Y-312363D02*
X630046Y-311946D01*
X630546Y-311613D01*
X631212Y-311530D01*
X631796Y-311613D01*
X632296Y-311946D01*
X632546Y-312530D01*
Y-314863D01*
G01X636729D02*
X636229Y-314780D01*
X635729Y-314446D01*
X635396Y-313863D01*
X635229Y-313196D01*
X635396Y-312530D01*
X635729Y-311946D01*
X636229Y-311613D01*
X636729Y-311530D01*
X637229Y-311613D01*
X637729Y-311946D01*
X638062Y-312530D01*
X638146Y-313196D01*
X638062Y-313863D01*
X637729Y-314446D01*
X637229Y-314780D01*
X636729Y-314863D01*
G01X641162D02*
Y-311530D01*
G01Y-312196D02*
X641579Y-311863D01*
X641996Y-311613D01*
X642579Y-311530D01*
X642996Y-311613D01*
X643496Y-311863D01*
G01X646679Y-312613D02*
X649346D01*
X649096Y-312030D01*
X648679Y-311696D01*
X648096Y-311530D01*
X647512Y-311613D01*
X647012Y-311863D01*
X646679Y-312446D01*
X646512Y-312946D01*
Y-313446D01*
X646679Y-313946D01*
X647096Y-314446D01*
X647596Y-314780D01*
X648179Y-314863D01*
X648762Y-314696D01*
X649346Y-314196D01*
G01X659129Y-309863D02*
Y-314863D01*
G01X657962Y-311530D02*
X660296D01*
G01X663312Y-314863D02*
Y-309863D01*
G01Y-312280D02*
X663729Y-311863D01*
X664146Y-311613D01*
X664812Y-311530D01*
X665312Y-311613D01*
X665896Y-311946D01*
X666146Y-312446D01*
Y-314863D01*
G01X670329Y-311530D02*
Y-314863D01*
G01Y-310196D02*
X670162Y-310113D01*
Y-309946D01*
X670329Y-309863D01*
X670496Y-309946D01*
Y-310113D01*
X670329Y-310196D01*
G01X674679Y-314280D02*
X675096Y-314613D01*
X675679Y-314863D01*
X676179D01*
X676679Y-314696D01*
X677012Y-314446D01*
X677179Y-314113D01*
X677096Y-313613D01*
X676762Y-313363D01*
X675262Y-312863D01*
X674929Y-312280D01*
X675096Y-311863D01*
X675429Y-311613D01*
X675929Y-311530D01*
X676429Y-311613D01*
X676929Y-311863D01*
G01X685962Y-314863D02*
Y-311530D01*
G01Y-312196D02*
X686379Y-311863D01*
X686796Y-311613D01*
X687379Y-311530D01*
X687796Y-311613D01*
X688296Y-311863D01*
G01X691479Y-312613D02*
X694146D01*
X693896Y-312030D01*
X693479Y-311696D01*
X692896Y-311530D01*
X692312Y-311613D01*
X691812Y-311863D01*
X691479Y-312446D01*
X691312Y-312946D01*
Y-313446D01*
X691479Y-313946D01*
X691896Y-314446D01*
X692396Y-314780D01*
X692979Y-314863D01*
X693562Y-314696D01*
X694146Y-314196D01*
G01X699829Y-316530D02*
Y-311530D01*
G01Y-312280D02*
X699412Y-311863D01*
X698912Y-311613D01*
X698329Y-311530D01*
X697829Y-311613D01*
X697246Y-312030D01*
X696912Y-312613D01*
X696829Y-313196D01*
X696912Y-313780D01*
X697246Y-314363D01*
X697829Y-314780D01*
X698329Y-314863D01*
X698912Y-314780D01*
X699412Y-314530D01*
X699829Y-314113D01*
G01X702512Y-311530D02*
Y-313863D01*
X702846Y-314446D01*
X703346Y-314780D01*
X703929Y-314863D01*
X704512Y-314780D01*
X705012Y-314446D01*
X705346Y-313863D01*
G01Y-314863D02*
Y-311530D01*
G01X708279Y-312613D02*
X710946D01*
X710696Y-312030D01*
X710279Y-311696D01*
X709696Y-311530D01*
X709112Y-311613D01*
X708612Y-311863D01*
X708279Y-312446D01*
X708112Y-312946D01*
Y-313446D01*
X708279Y-313946D01*
X708696Y-314446D01*
X709196Y-314780D01*
X709779Y-314863D01*
X710362Y-314696D01*
X710946Y-314196D01*
G01X713879Y-314280D02*
X714296Y-314613D01*
X714879Y-314863D01*
X715379D01*
X715879Y-314696D01*
X716212Y-314446D01*
X716379Y-314113D01*
X716296Y-313613D01*
X715962Y-313363D01*
X714462Y-312863D01*
X714129Y-312280D01*
X714296Y-311863D01*
X714629Y-311613D01*
X715129Y-311530D01*
X715629Y-311613D01*
X716129Y-311863D01*
G01X720729Y-309863D02*
Y-314863D01*
G01X719562Y-311530D02*
X721896D01*
G01X726329Y-315030D02*
X726162Y-314946D01*
Y-314780D01*
X726329Y-314696D01*
X726496Y-314780D01*
Y-314946D01*
X726329Y-315030D01*
G01X296926Y-264293D02*
Y-259293D01*
X298592D01*
X299259Y-259543D01*
X299759Y-259876D01*
X300176Y-260376D01*
X300509Y-260960D01*
X300592Y-261793D01*
X300509Y-262626D01*
X300176Y-263210D01*
X299759Y-263710D01*
X299259Y-264043D01*
X298592Y-264293D01*
X296926D01*
G01X304359D02*
Y-259293D01*
X303359Y-260293D01*
G01Y-264293D02*
X305359D01*
G01X308376Y-262210D02*
X308959Y-261626D01*
X309459Y-261293D01*
X310126Y-261126D01*
X310709Y-261293D01*
X311126Y-261626D01*
X311459Y-262126D01*
X311542Y-262710D01*
X311459Y-263210D01*
X311126Y-263710D01*
X310626Y-264126D01*
X310042Y-264293D01*
X309376Y-264126D01*
X308792Y-263626D01*
X308459Y-262876D01*
X308376Y-262043D01*
X308542Y-260960D01*
X308792Y-260376D01*
X309209Y-259793D01*
X309792Y-259376D01*
X310376Y-259293D01*
X310959Y-259460D01*
X311376Y-259876D01*
G01X271926Y-125793D02*
Y-120793D01*
X273592D01*
X274259Y-121043D01*
X274759Y-121376D01*
X275176Y-121876D01*
X275509Y-122460D01*
X275592Y-123293D01*
X275509Y-124126D01*
X275176Y-124710D01*
X274759Y-125210D01*
X274259Y-125543D01*
X273592Y-125793D01*
X271926D01*
G01X278192D02*
Y-122460D01*
G01Y-123126D02*
X278609Y-122793D01*
X279026Y-122543D01*
X279609Y-122460D01*
X280026Y-122543D01*
X280526Y-122793D01*
G01X284959Y-122460D02*
Y-125793D01*
G01Y-121126D02*
X284792Y-121043D01*
Y-120876D01*
X284959Y-120793D01*
X285126Y-120876D01*
Y-121043D01*
X284959Y-121126D01*
G01X290559Y-125793D02*
Y-120793D01*
G01X296159Y-125793D02*
Y-120793D01*
G01X305776Y-125793D02*
Y-120793D01*
X308942D01*
G01X307776Y-123210D02*
X305776D01*
G01X311792Y-125793D02*
Y-122460D01*
G01Y-123126D02*
X312209Y-122793D01*
X312626Y-122543D01*
X313209Y-122460D01*
X313626Y-122543D01*
X314126Y-122793D01*
G01X318559Y-125793D02*
X318059Y-125710D01*
X317559Y-125376D01*
X317226Y-124793D01*
X317059Y-124126D01*
X317226Y-123460D01*
X317559Y-122876D01*
X318059Y-122543D01*
X318559Y-122460D01*
X319059Y-122543D01*
X319559Y-122876D01*
X319892Y-123460D01*
X319976Y-124126D01*
X319892Y-124793D01*
X319559Y-125376D01*
X319059Y-125710D01*
X318559Y-125793D01*
G01X321659D02*
Y-122460D01*
G01Y-123376D02*
X321909Y-122960D01*
X322326Y-122626D01*
X322909Y-122460D01*
X323492Y-122626D01*
X323909Y-122960D01*
X324159Y-123376D01*
Y-125793D01*
G01Y-123376D02*
X324409Y-122960D01*
X324826Y-122626D01*
X325409Y-122460D01*
X325992Y-122626D01*
X326409Y-122960D01*
X326659Y-123460D01*
Y-125793D01*
G01X333692Y-120793D02*
Y-125793D01*
X337026D01*
G01X340959D02*
Y-120793D01*
X339959Y-121793D01*
G01Y-125793D02*
X341959D01*
G01X351742Y-127460D02*
X350909Y-126626D01*
X350492Y-125793D01*
Y-122460D01*
X350909Y-121626D01*
X351742Y-120793D01*
G01X357759D02*
Y-125793D01*
G01X355842Y-120793D02*
X359676D01*
G01X363359Y-125793D02*
X362692Y-125710D01*
X362109Y-125376D01*
X361609Y-124876D01*
X361276Y-124293D01*
X361109Y-123626D01*
Y-122960D01*
X361276Y-122293D01*
X361609Y-121710D01*
X362109Y-121210D01*
X362692Y-120876D01*
X363359Y-120793D01*
X364026Y-120876D01*
X364609Y-121210D01*
X365109Y-121710D01*
X365442Y-122293D01*
X365609Y-122960D01*
Y-123626D01*
X365442Y-124293D01*
X365109Y-124876D01*
X364609Y-125376D01*
X364026Y-125710D01*
X363359Y-125793D01*
G01X367292D02*
Y-120793D01*
X369292D01*
X369959Y-121043D01*
X370459Y-121626D01*
X370626Y-122293D01*
X370459Y-122960D01*
X370042Y-123460D01*
X369292Y-123710D01*
X367292D01*
G01X374976Y-127460D02*
X375809Y-126626D01*
X376226Y-125793D01*
Y-122460D01*
X375809Y-121626D01*
X374976Y-120793D01*
G01X385759D02*
Y-125793D01*
G01X384592Y-122460D02*
X386926D01*
G01X391359Y-125793D02*
X390859Y-125710D01*
X390359Y-125376D01*
X390026Y-124793D01*
X389859Y-124126D01*
X390026Y-123460D01*
X390359Y-122876D01*
X390859Y-122543D01*
X391359Y-122460D01*
X391859Y-122543D01*
X392359Y-122876D01*
X392692Y-123460D01*
X392776Y-124126D01*
X392692Y-124793D01*
X392359Y-125376D01*
X391859Y-125710D01*
X391359Y-125793D01*
G01X400892Y-120793D02*
Y-125793D01*
X404226D01*
G01X406909Y-122460D02*
X409409Y-125793D01*
G01Y-122460D02*
X406909Y-125793D01*
G01X272342Y-144093D02*
Y-149093D01*
X275676D01*
G01X278359Y-145760D02*
X280859Y-149093D01*
G01Y-145760D02*
X278359Y-149093D01*
G01X285209Y-149260D02*
X285042Y-149176D01*
Y-149010D01*
X285209Y-148926D01*
X285376Y-149010D01*
Y-149176D01*
X285209Y-149260D01*
G01Y-147010D02*
X285042Y-146926D01*
Y-146760D01*
X285209Y-146676D01*
X285376Y-146760D01*
Y-146926D01*
X285209Y-147010D01*
G01X293909Y-149093D02*
Y-145760D01*
G01Y-146676D02*
X294159Y-146260D01*
X294576Y-145926D01*
X295159Y-145760D01*
X295742Y-145926D01*
X296159Y-146260D01*
X296409Y-146676D01*
Y-149093D01*
G01Y-146676D02*
X296659Y-146260D01*
X297076Y-145926D01*
X297659Y-145760D01*
X298242Y-145926D01*
X298659Y-146260D01*
X298909Y-146760D01*
Y-149093D01*
G01X300592Y-145760D02*
Y-148093D01*
X300926Y-148676D01*
X301426Y-149010D01*
X302009Y-149093D01*
X302592Y-149010D01*
X303092Y-148676D01*
X303426Y-148093D01*
G01Y-149093D02*
Y-145760D01*
G01X306359Y-148510D02*
X306776Y-148843D01*
X307359Y-149093D01*
X307859D01*
X308359Y-148926D01*
X308692Y-148676D01*
X308859Y-148343D01*
X308776Y-147843D01*
X308442Y-147593D01*
X306942Y-147093D01*
X306609Y-146510D01*
X306776Y-146093D01*
X307109Y-145843D01*
X307609Y-145760D01*
X308109Y-145843D01*
X308609Y-146093D01*
G01X313209Y-144093D02*
Y-149093D01*
G01X312042Y-145760D02*
X314376D01*
G01X322909Y-149093D02*
Y-144093D01*
G01Y-146593D02*
X323326Y-146093D01*
X323826Y-145843D01*
X324326Y-145760D01*
X325076Y-145926D01*
X325576Y-146260D01*
X325909Y-146843D01*
Y-147510D01*
X325742Y-148176D01*
X325409Y-148676D01*
X324826Y-149010D01*
X324326Y-149093D01*
X323826Y-149010D01*
X323326Y-148760D01*
X322909Y-148343D01*
G01X328759Y-146843D02*
X331426D01*
X331176Y-146260D01*
X330759Y-145926D01*
X330176Y-145760D01*
X329592Y-145843D01*
X329092Y-146093D01*
X328759Y-146676D01*
X328592Y-147176D01*
Y-147676D01*
X328759Y-148176D01*
X329176Y-148676D01*
X329676Y-149010D01*
X330259Y-149093D01*
X330842Y-148926D01*
X331426Y-148426D01*
G01X339709Y-149093D02*
Y-144093D01*
G01Y-146593D02*
X340126Y-146093D01*
X340626Y-145843D01*
X341126Y-145760D01*
X341876Y-145926D01*
X342376Y-146260D01*
X342709Y-146843D01*
Y-147510D01*
X342542Y-148176D01*
X342209Y-148676D01*
X341626Y-149010D01*
X341126Y-149093D01*
X340626Y-149010D01*
X340126Y-148760D01*
X339709Y-148343D01*
G01X345642Y-149093D02*
Y-145760D01*
G01Y-146426D02*
X346059Y-146093D01*
X346476Y-145843D01*
X347059Y-145760D01*
X347476Y-145843D01*
X347976Y-146093D01*
G01X352409Y-149093D02*
X351909Y-149010D01*
X351409Y-148676D01*
X351076Y-148093D01*
X350909Y-147426D01*
X351076Y-146760D01*
X351409Y-146176D01*
X351909Y-145843D01*
X352409Y-145760D01*
X352909Y-145843D01*
X353409Y-146176D01*
X353742Y-146760D01*
X353826Y-147426D01*
X353742Y-148093D01*
X353409Y-148676D01*
X352909Y-149010D01*
X352409Y-149093D01*
G01X356592D02*
Y-144093D01*
G01X359259Y-145760D02*
X356592Y-147676D01*
G01X357676Y-146926D02*
X359426Y-149093D01*
G01X362359Y-146843D02*
X365026D01*
X364776Y-146260D01*
X364359Y-145926D01*
X363776Y-145760D01*
X363192Y-145843D01*
X362692Y-146093D01*
X362359Y-146676D01*
X362192Y-147176D01*
Y-147676D01*
X362359Y-148176D01*
X362776Y-148676D01*
X363276Y-149010D01*
X363859Y-149093D01*
X364442Y-148926D01*
X365026Y-148426D01*
G01X367792Y-149093D02*
Y-145760D01*
G01Y-146593D02*
X368126Y-146176D01*
X368626Y-145843D01*
X369292Y-145760D01*
X369876Y-145843D01*
X370376Y-146176D01*
X370626Y-146760D01*
Y-149093D01*
G01X380409D02*
Y-144093D01*
G01X387509Y-149093D02*
Y-145760D01*
G01Y-146343D02*
X387176Y-146010D01*
X386676Y-145843D01*
X386092Y-145760D01*
X385509Y-145926D01*
X385009Y-146260D01*
X384676Y-146760D01*
X384509Y-147426D01*
X384676Y-148093D01*
X385009Y-148593D01*
X385509Y-148926D01*
X386092Y-149093D01*
X386676Y-149010D01*
X387176Y-148760D01*
X387509Y-148426D01*
G01X389859Y-150593D02*
X390359Y-150760D01*
X391026Y-150593D01*
X391442Y-150260D01*
X391776Y-149843D01*
X392276Y-148510D01*
X393359Y-145760D01*
G01X390692D02*
X392276Y-148510D01*
G01X395959Y-146843D02*
X398626D01*
X398376Y-146260D01*
X397959Y-145926D01*
X397376Y-145760D01*
X396792Y-145843D01*
X396292Y-146093D01*
X395959Y-146676D01*
X395792Y-147176D01*
Y-147676D01*
X395959Y-148176D01*
X396376Y-148676D01*
X396876Y-149010D01*
X397459Y-149093D01*
X398042Y-148926D01*
X398626Y-148426D01*
G01X401642Y-149093D02*
Y-145760D01*
G01Y-146426D02*
X402059Y-146093D01*
X402476Y-145843D01*
X403059Y-145760D01*
X403476Y-145843D01*
X403976Y-146093D01*
G01X271742Y-132483D02*
Y-137483D01*
X275076D01*
G01X277592D02*
Y-134150D01*
G01Y-134983D02*
X277926Y-134566D01*
X278426Y-134233D01*
X279092Y-134150D01*
X279676Y-134233D01*
X280176Y-134566D01*
X280426Y-135150D01*
Y-137483D01*
G01X284609Y-137650D02*
X284442Y-137566D01*
Y-137400D01*
X284609Y-137316D01*
X284776Y-137400D01*
Y-137566D01*
X284609Y-137650D01*
G01Y-135400D02*
X284442Y-135316D01*
Y-135150D01*
X284609Y-135066D01*
X284776Y-135150D01*
Y-135316D01*
X284609Y-135400D01*
G01X297142Y-134566D02*
X296559Y-134233D01*
X296059Y-134150D01*
X295392Y-134316D01*
X294892Y-134650D01*
X294559Y-135233D01*
X294476Y-135816D01*
X294559Y-136400D01*
X294892Y-136900D01*
X295392Y-137316D01*
X296059Y-137483D01*
X296642Y-137316D01*
X297142Y-136983D01*
G01X302909Y-137483D02*
Y-134150D01*
G01Y-134733D02*
X302576Y-134400D01*
X302076Y-134233D01*
X301492Y-134150D01*
X300909Y-134316D01*
X300409Y-134650D01*
X300076Y-135150D01*
X299909Y-135816D01*
X300076Y-136483D01*
X300409Y-136983D01*
X300909Y-137316D01*
X301492Y-137483D01*
X302076Y-137400D01*
X302576Y-137150D01*
X302909Y-136816D01*
G01X305592Y-137483D02*
Y-134150D01*
G01Y-134983D02*
X305926Y-134566D01*
X306426Y-134233D01*
X307092Y-134150D01*
X307676Y-134233D01*
X308176Y-134566D01*
X308426Y-135150D01*
Y-137483D01*
G01X312609Y-134150D02*
X313442Y-133108D01*
Y-132483D01*
X312817D01*
Y-133108D01*
X313442D01*
G01X318209Y-132483D02*
Y-137483D01*
G01X317042Y-134150D02*
X319376D01*
G01X327909Y-137483D02*
Y-132483D01*
G01Y-134983D02*
X328326Y-134483D01*
X328826Y-134233D01*
X329326Y-134150D01*
X330076Y-134316D01*
X330576Y-134650D01*
X330909Y-135233D01*
Y-135900D01*
X330742Y-136566D01*
X330409Y-137066D01*
X329826Y-137400D01*
X329326Y-137483D01*
X328826Y-137400D01*
X328326Y-137150D01*
X327909Y-136733D01*
G01X333759Y-135233D02*
X336426D01*
X336176Y-134650D01*
X335759Y-134316D01*
X335176Y-134150D01*
X334592Y-134233D01*
X334092Y-134483D01*
X333759Y-135066D01*
X333592Y-135566D01*
Y-136066D01*
X333759Y-136566D01*
X334176Y-137066D01*
X334676Y-137400D01*
X335259Y-137483D01*
X335842Y-137316D01*
X336426Y-136816D01*
G01X344709Y-137483D02*
Y-132483D01*
G01Y-134983D02*
X345126Y-134483D01*
X345626Y-134233D01*
X346126Y-134150D01*
X346876Y-134316D01*
X347376Y-134650D01*
X347709Y-135233D01*
Y-135900D01*
X347542Y-136566D01*
X347209Y-137066D01*
X346626Y-137400D01*
X346126Y-137483D01*
X345626Y-137400D01*
X345126Y-137150D01*
X344709Y-136733D01*
G01X350642Y-137483D02*
Y-134150D01*
G01Y-134816D02*
X351059Y-134483D01*
X351476Y-134233D01*
X352059Y-134150D01*
X352476Y-134233D01*
X352976Y-134483D01*
G01X357409Y-137483D02*
X356909Y-137400D01*
X356409Y-137066D01*
X356076Y-136483D01*
X355909Y-135816D01*
X356076Y-135150D01*
X356409Y-134566D01*
X356909Y-134233D01*
X357409Y-134150D01*
X357909Y-134233D01*
X358409Y-134566D01*
X358742Y-135150D01*
X358826Y-135816D01*
X358742Y-136483D01*
X358409Y-137066D01*
X357909Y-137400D01*
X357409Y-137483D01*
G01X361592D02*
Y-132483D01*
G01X364259Y-134150D02*
X361592Y-136066D01*
G01X362676Y-135316D02*
X364426Y-137483D01*
G01X367359Y-135233D02*
X370026D01*
X369776Y-134650D01*
X369359Y-134316D01*
X368776Y-134150D01*
X368192Y-134233D01*
X367692Y-134483D01*
X367359Y-135066D01*
X367192Y-135566D01*
Y-136066D01*
X367359Y-136566D01*
X367776Y-137066D01*
X368276Y-137400D01*
X368859Y-137483D01*
X369442Y-137316D01*
X370026Y-136816D01*
G01X372792Y-137483D02*
Y-134150D01*
G01Y-134983D02*
X373126Y-134566D01*
X373626Y-134233D01*
X374292Y-134150D01*
X374876Y-134233D01*
X375376Y-134566D01*
X375626Y-135150D01*
Y-137483D01*
G01X385409D02*
Y-132483D01*
G01X392509Y-137483D02*
Y-134150D01*
G01Y-134733D02*
X392176Y-134400D01*
X391676Y-134233D01*
X391092Y-134150D01*
X390509Y-134316D01*
X390009Y-134650D01*
X389676Y-135150D01*
X389509Y-135816D01*
X389676Y-136483D01*
X390009Y-136983D01*
X390509Y-137316D01*
X391092Y-137483D01*
X391676Y-137400D01*
X392176Y-137150D01*
X392509Y-136816D01*
G01X394859Y-138983D02*
X395359Y-139150D01*
X396026Y-138983D01*
X396442Y-138650D01*
X396776Y-138233D01*
X397276Y-136900D01*
X398359Y-134150D01*
G01X395692D02*
X397276Y-136900D01*
G01X400959Y-135233D02*
X403626D01*
X403376Y-134650D01*
X402959Y-134316D01*
X402376Y-134150D01*
X401792Y-134233D01*
X401292Y-134483D01*
X400959Y-135066D01*
X400792Y-135566D01*
Y-136066D01*
X400959Y-136566D01*
X401376Y-137066D01*
X401876Y-137400D01*
X402459Y-137483D01*
X403042Y-137316D01*
X403626Y-136816D01*
G01X406642Y-137483D02*
Y-134150D01*
G01Y-134816D02*
X407059Y-134483D01*
X407476Y-134233D01*
X408059Y-134150D01*
X408476Y-134233D01*
X408976Y-134483D01*
G01X289259Y425707D02*
Y420707D01*
G01X288092Y424040D02*
X290426D01*
G01X293442Y420707D02*
Y425707D01*
G01Y423290D02*
X293859Y423707D01*
X294276Y423957D01*
X294942Y424040D01*
X295442Y423957D01*
X296026Y423624D01*
X296276Y423124D01*
Y420707D01*
G01X300459Y424040D02*
Y420707D01*
G01Y425374D02*
X300292Y425457D01*
Y425624D01*
X300459Y425707D01*
X300626Y425624D01*
Y425457D01*
X300459Y425374D01*
G01X307392Y423624D02*
X306809Y423957D01*
X306309Y424040D01*
X305642Y423874D01*
X305142Y423540D01*
X304809Y422957D01*
X304726Y422374D01*
X304809Y421790D01*
X305142Y421290D01*
X305642Y420874D01*
X306309Y420707D01*
X306892Y420874D01*
X307392Y421207D01*
G01X310242Y420707D02*
Y425707D01*
G01X312909Y424040D02*
X310242Y422124D01*
G01X311326Y422874D02*
X313076Y420707D01*
G01X315842D02*
Y424040D01*
G01Y423207D02*
X316176Y423624D01*
X316676Y423957D01*
X317342Y424040D01*
X317926Y423957D01*
X318426Y423624D01*
X318676Y423040D01*
Y420707D01*
G01X321609Y422957D02*
X324276D01*
X324026Y423540D01*
X323609Y423874D01*
X323026Y424040D01*
X322442Y423957D01*
X321942Y423707D01*
X321609Y423124D01*
X321442Y422624D01*
Y422124D01*
X321609Y421624D01*
X322026Y421124D01*
X322526Y420790D01*
X323109Y420707D01*
X323692Y420874D01*
X324276Y421374D01*
G01X327209Y421290D02*
X327626Y420957D01*
X328209Y420707D01*
X328709D01*
X329209Y420874D01*
X329542Y421124D01*
X329709Y421457D01*
X329626Y421957D01*
X329292Y422207D01*
X327792Y422707D01*
X327459Y423290D01*
X327626Y423707D01*
X327959Y423957D01*
X328459Y424040D01*
X328959Y423957D01*
X329459Y423707D01*
G01X332809Y421290D02*
X333226Y420957D01*
X333809Y420707D01*
X334309D01*
X334809Y420874D01*
X335142Y421124D01*
X335309Y421457D01*
X335226Y421957D01*
X334892Y422207D01*
X333392Y422707D01*
X333059Y423290D01*
X333226Y423707D01*
X333559Y423957D01*
X334059Y424040D01*
X334559Y423957D01*
X335059Y423707D01*
G01X293259Y546707D02*
Y541707D01*
G01X291342Y546707D02*
X295176D01*
G01X296776Y545040D02*
X297776Y541707D01*
X298859Y545040D01*
X299942Y541707D01*
X300942Y545040D01*
G01X304459D02*
Y541707D01*
G01Y546374D02*
X304292Y546457D01*
Y546624D01*
X304459Y546707D01*
X304626Y546624D01*
Y546457D01*
X304459Y546374D01*
G01X308809Y542290D02*
X309226Y541957D01*
X309809Y541707D01*
X310309D01*
X310809Y541874D01*
X311142Y542124D01*
X311309Y542457D01*
X311226Y542957D01*
X310892Y543207D01*
X309392Y543707D01*
X309059Y544290D01*
X309226Y544707D01*
X309559Y544957D01*
X310059Y545040D01*
X310559Y544957D01*
X311059Y544707D01*
G01X315659Y546707D02*
Y541707D01*
G01X314492Y545040D02*
X316826D01*
G01X328359Y541707D02*
Y545040D01*
G01Y544457D02*
X328026Y544790D01*
X327526Y544957D01*
X326942Y545040D01*
X326359Y544874D01*
X325859Y544540D01*
X325526Y544040D01*
X325359Y543374D01*
X325526Y542707D01*
X325859Y542207D01*
X326359Y541874D01*
X326942Y541707D01*
X327526Y541790D01*
X328026Y542040D01*
X328359Y542374D01*
G01X331042Y541707D02*
Y545040D01*
G01Y544207D02*
X331376Y544624D01*
X331876Y544957D01*
X332542Y545040D01*
X333126Y544957D01*
X333626Y544624D01*
X333876Y544040D01*
Y541707D01*
G01X339559Y546707D02*
Y541707D01*
G01Y542457D02*
X339226Y542040D01*
X338726Y541790D01*
X338142Y541707D01*
X337476Y541874D01*
X336976Y542290D01*
X336642Y542790D01*
X336559Y543374D01*
X336642Y543957D01*
X336976Y544457D01*
X337476Y544874D01*
X338142Y545040D01*
X338726Y544957D01*
X339142Y544790D01*
X339559Y544457D01*
G01X347759Y541707D02*
Y546707D01*
G01Y544207D02*
X348176Y544707D01*
X348676Y544957D01*
X349176Y545040D01*
X349926Y544874D01*
X350426Y544540D01*
X350759Y543957D01*
Y543290D01*
X350592Y542624D01*
X350259Y542124D01*
X349676Y541790D01*
X349176Y541707D01*
X348676Y541790D01*
X348176Y542040D01*
X347759Y542457D01*
G01X354859Y541707D02*
X354359Y541790D01*
X353859Y542124D01*
X353526Y542707D01*
X353359Y543374D01*
X353526Y544040D01*
X353859Y544624D01*
X354359Y544957D01*
X354859Y545040D01*
X355359Y544957D01*
X355859Y544624D01*
X356192Y544040D01*
X356276Y543374D01*
X356192Y542707D01*
X355859Y542124D01*
X355359Y541790D01*
X354859Y541707D01*
G01X358376Y545040D02*
X359376Y541707D01*
X360459Y545040D01*
X361542Y541707D01*
X362542Y545040D01*
G01X291592Y577707D02*
Y582707D01*
X293676D01*
X294342Y582457D01*
X294759Y582124D01*
X294926Y581457D01*
X294759Y580790D01*
X294259Y580374D01*
X293676Y580124D01*
X291592D01*
G01X293676D02*
X294926Y577707D01*
G01X298859D02*
X298359Y577790D01*
X297859Y578124D01*
X297526Y578707D01*
X297359Y579374D01*
X297526Y580040D01*
X297859Y580624D01*
X298359Y580957D01*
X298859Y581040D01*
X299359Y580957D01*
X299859Y580624D01*
X300192Y580040D01*
X300276Y579374D01*
X300192Y578707D01*
X299859Y578124D01*
X299359Y577790D01*
X298859Y577707D01*
G01X303042Y581040D02*
Y578707D01*
X303376Y578124D01*
X303876Y577790D01*
X304459Y577707D01*
X305042Y577790D01*
X305542Y578124D01*
X305876Y578707D01*
G01Y577707D02*
Y581040D01*
G01X310059Y582707D02*
Y577707D01*
G01X308892Y581040D02*
X311226D01*
G01X315659D02*
Y577707D01*
G01Y582374D02*
X315492Y582457D01*
Y582624D01*
X315659Y582707D01*
X315826Y582624D01*
Y582457D01*
X315659Y582374D01*
G01X319842Y577707D02*
Y581040D01*
G01Y580207D02*
X320176Y580624D01*
X320676Y580957D01*
X321342Y581040D01*
X321926Y580957D01*
X322426Y580624D01*
X322676Y580040D01*
Y577707D01*
G01X325692Y576457D02*
X326276Y576124D01*
X326942Y576040D01*
X327526Y576124D01*
X328026Y576540D01*
X328359Y577124D01*
Y581040D01*
G01Y580374D02*
X328026Y580707D01*
X327526Y580957D01*
X326942Y581040D01*
X326276Y580874D01*
X325859Y580540D01*
X325526Y579957D01*
X325359Y579374D01*
X325442Y578874D01*
X325776Y578290D01*
X326276Y577874D01*
X326942Y577707D01*
X327442Y577790D01*
X328026Y578124D01*
X328359Y578457D01*
G01X338059Y582707D02*
Y577707D01*
G01X336892Y581040D02*
X339226D01*
G01X343659Y577707D02*
X343159Y577790D01*
X342659Y578124D01*
X342326Y578707D01*
X342159Y579374D01*
X342326Y580040D01*
X342659Y580624D01*
X343159Y580957D01*
X343659Y581040D01*
X344159Y580957D01*
X344659Y580624D01*
X344992Y580040D01*
X345076Y579374D01*
X344992Y578707D01*
X344659Y578124D01*
X344159Y577790D01*
X343659Y577707D01*
G01X349259D02*
Y582707D01*
G01X353609Y579957D02*
X356276D01*
X356026Y580540D01*
X355609Y580874D01*
X355026Y581040D01*
X354442Y580957D01*
X353942Y580707D01*
X353609Y580124D01*
X353442Y579624D01*
Y579124D01*
X353609Y578624D01*
X354026Y578124D01*
X354526Y577790D01*
X355109Y577707D01*
X355692Y577874D01*
X356276Y578374D01*
G01X359292Y577707D02*
Y581040D01*
G01Y580374D02*
X359709Y580707D01*
X360126Y580957D01*
X360709Y581040D01*
X361126Y580957D01*
X361626Y580707D01*
G01X367559Y577707D02*
Y581040D01*
G01Y580457D02*
X367226Y580790D01*
X366726Y580957D01*
X366142Y581040D01*
X365559Y580874D01*
X365059Y580540D01*
X364726Y580040D01*
X364559Y579374D01*
X364726Y578707D01*
X365059Y578207D01*
X365559Y577874D01*
X366142Y577707D01*
X366726Y577790D01*
X367226Y578040D01*
X367559Y578374D01*
G01X370242Y577707D02*
Y581040D01*
G01Y580207D02*
X370576Y580624D01*
X371076Y580957D01*
X371742Y581040D01*
X372326Y580957D01*
X372826Y580624D01*
X373076Y580040D01*
Y577707D01*
G01X378592Y580624D02*
X378009Y580957D01*
X377509Y581040D01*
X376842Y580874D01*
X376342Y580540D01*
X376009Y579957D01*
X375926Y579374D01*
X376009Y578790D01*
X376342Y578290D01*
X376842Y577874D01*
X377509Y577707D01*
X378092Y577874D01*
X378592Y578207D01*
G01X381609Y579957D02*
X384276D01*
X384026Y580540D01*
X383609Y580874D01*
X383026Y581040D01*
X382442Y580957D01*
X381942Y580707D01*
X381609Y580124D01*
X381442Y579624D01*
Y579124D01*
X381609Y578624D01*
X382026Y578124D01*
X382526Y577790D01*
X383109Y577707D01*
X383692Y577874D01*
X384276Y578374D01*
G01X282759Y601817D02*
Y533317D01*
G01Y556707D02*
X837759D01*
G01X363009Y-96793D02*
Y-91793D01*
G01X366509D02*
Y-96793D01*
G01Y-94293D02*
X363009D01*
G01X370359Y-96793D02*
X369692Y-96710D01*
X369109Y-96376D01*
X368609Y-95876D01*
X368276Y-95293D01*
X368109Y-94626D01*
Y-93960D01*
X368276Y-93293D01*
X368609Y-92710D01*
X369109Y-92210D01*
X369692Y-91876D01*
X370359Y-91793D01*
X371026Y-91876D01*
X371609Y-92210D01*
X372109Y-92710D01*
X372442Y-93293D01*
X372609Y-93960D01*
Y-94626D01*
X372442Y-95293D01*
X372109Y-95876D01*
X371609Y-96376D01*
X371026Y-96710D01*
X370359Y-96793D01*
G01X374292Y-91793D02*
Y-96793D01*
X377626D01*
G01X383226D02*
X379892D01*
Y-91793D01*
X383226D01*
G01X381892Y-94210D02*
X379892D01*
G01X407059Y-96793D02*
Y-93460D01*
G01Y-94376D02*
X407309Y-93960D01*
X407726Y-93626D01*
X408309Y-93460D01*
X408892Y-93626D01*
X409309Y-93960D01*
X409559Y-94376D01*
Y-96793D01*
G01Y-94376D02*
X409809Y-93960D01*
X410226Y-93626D01*
X410809Y-93460D01*
X411392Y-93626D01*
X411809Y-93960D01*
X412059Y-94460D01*
Y-96793D01*
G01X415159Y-93460D02*
Y-96793D01*
G01Y-92126D02*
X414992Y-92043D01*
Y-91876D01*
X415159Y-91793D01*
X415326Y-91876D01*
Y-92043D01*
X415159Y-92126D01*
G01X420759Y-96793D02*
Y-91793D01*
G01X425109Y-96210D02*
X425526Y-96543D01*
X426109Y-96793D01*
X426609D01*
X427109Y-96626D01*
X427442Y-96376D01*
X427609Y-96043D01*
X427526Y-95543D01*
X427192Y-95293D01*
X425692Y-94793D01*
X425359Y-94210D01*
X425526Y-93793D01*
X425859Y-93543D01*
X426359Y-93460D01*
X426859Y-93543D01*
X427359Y-93793D01*
G01X431542Y-98460D02*
X430709Y-97626D01*
X430292Y-96793D01*
Y-93460D01*
X430709Y-92626D01*
X431542Y-91793D01*
G01X435892Y-96793D02*
Y-91793D01*
X437892D01*
X438559Y-92043D01*
X439059Y-92626D01*
X439226Y-93293D01*
X439059Y-93960D01*
X438642Y-94460D01*
X437892Y-94710D01*
X435892D01*
G01X443159Y-91793D02*
Y-96793D01*
G01X441242Y-91793D02*
X445076D01*
G01X447009Y-96793D02*
Y-91793D01*
G01X450509D02*
Y-96793D01*
G01Y-94293D02*
X447009D01*
G01X454776Y-98460D02*
X455609Y-97626D01*
X456026Y-96793D01*
Y-93460D01*
X455609Y-92626D01*
X454776Y-91793D01*
G01X322426Y-98293D02*
Y-93293D01*
X324092D01*
X324759Y-93543D01*
X325259Y-93876D01*
X325676Y-94376D01*
X326009Y-94960D01*
X326092Y-95793D01*
X326009Y-96626D01*
X325676Y-97210D01*
X325259Y-97710D01*
X324759Y-98043D01*
X324092Y-98293D01*
X322426D01*
G01X329859D02*
Y-93293D01*
X328859Y-94293D01*
G01Y-98293D02*
X330859D01*
G01X362926Y59374D02*
X363259Y59624D01*
X363509Y60040D01*
X363676Y60624D01*
X363509Y61124D01*
X363176Y61457D01*
X362592Y61707D01*
X360342D01*
Y56707D01*
X363092D01*
X363676Y57040D01*
X364009Y57540D01*
X364176Y58124D01*
X364009Y58707D01*
X363509Y59207D01*
X362926Y59374D01*
X360342D01*
G01X365776Y56707D02*
X367859Y61707D01*
X369942Y56707D01*
G01X369192Y58457D02*
X366526D01*
G01X375292Y61290D02*
X374792Y61540D01*
X374209Y61707D01*
X373542D01*
X372792Y61457D01*
X372209Y61040D01*
X371792Y60540D01*
X371459Y59707D01*
X371376Y58957D01*
X371542Y58207D01*
X371792Y57707D01*
X372292Y57207D01*
X372876Y56874D01*
X373459Y56707D01*
X374042D01*
X374626Y56874D01*
X375126Y57124D01*
X375542Y57457D01*
G01X377226Y56707D02*
Y61707D01*
G01X380392D02*
X377226Y58624D01*
G01X380892Y56707D02*
X378642Y60040D01*
G01X388426Y56707D02*
Y61707D01*
X390092D01*
X390759Y61457D01*
X391259Y61124D01*
X391676Y60624D01*
X392009Y60040D01*
X392092Y59207D01*
X392009Y58374D01*
X391676Y57790D01*
X391259Y57290D01*
X390759Y56957D01*
X390092Y56707D01*
X388426D01*
G01X394192D02*
Y61707D01*
X396276D01*
X396942Y61457D01*
X397359Y61124D01*
X397526Y60457D01*
X397359Y59790D01*
X396859Y59374D01*
X396276Y59124D01*
X394192D01*
G01X396276D02*
X397526Y56707D01*
G01X400459Y61707D02*
X402459D01*
G01X401459D02*
Y56707D01*
G01X400459D02*
X402459D01*
G01X405392Y61707D02*
Y56707D01*
X408726D01*
G01X410992Y61707D02*
Y56707D01*
X414326D01*
G01X438159D02*
Y60040D01*
G01Y59124D02*
X438409Y59540D01*
X438826Y59874D01*
X439409Y60040D01*
X439992Y59874D01*
X440409Y59540D01*
X440659Y59124D01*
Y56707D01*
G01Y59124D02*
X440909Y59540D01*
X441326Y59874D01*
X441909Y60040D01*
X442492Y59874D01*
X442909Y59540D01*
X443159Y59040D01*
Y56707D01*
G01X446259Y60040D02*
Y56707D01*
G01Y61374D02*
X446092Y61457D01*
Y61624D01*
X446259Y61707D01*
X446426Y61624D01*
Y61457D01*
X446259Y61374D01*
G01X451859Y56707D02*
Y61707D01*
G01X456209Y57290D02*
X456626Y56957D01*
X457209Y56707D01*
X457709D01*
X458209Y56874D01*
X458542Y57124D01*
X458709Y57457D01*
X458626Y57957D01*
X458292Y58207D01*
X456792Y58707D01*
X456459Y59290D01*
X456626Y59707D01*
X456959Y59957D01*
X457459Y60040D01*
X457959Y59957D01*
X458459Y59707D01*
G01X462642Y55040D02*
X461809Y55874D01*
X461392Y56707D01*
Y60040D01*
X461809Y60874D01*
X462642Y61707D01*
G01X466742Y56707D02*
Y61707D01*
X470576Y56707D01*
Y61707D01*
G01X472592Y56707D02*
Y61707D01*
X474592D01*
X475259Y61457D01*
X475759Y60874D01*
X475926Y60207D01*
X475759Y59540D01*
X475342Y59040D01*
X474592Y58790D01*
X472592D01*
G01X479859Y61707D02*
Y56707D01*
G01X477942Y61707D02*
X481776D01*
G01X483709Y56707D02*
Y61707D01*
G01X487209D02*
Y56707D01*
G01Y59207D02*
X483709D01*
G01X491476Y55040D02*
X492309Y55874D01*
X492726Y56707D01*
Y60040D01*
X492309Y60874D01*
X491476Y61707D01*
G01X320426Y65707D02*
Y70707D01*
X322092D01*
X322759Y70457D01*
X323259Y70124D01*
X323676Y69624D01*
X324009Y69040D01*
X324092Y68207D01*
X324009Y67374D01*
X323676Y66790D01*
X323259Y66290D01*
X322759Y65957D01*
X322092Y65707D01*
X320426D01*
G01X326276Y69874D02*
X326776Y70374D01*
X327359Y70624D01*
X328026Y70707D01*
X328859Y70540D01*
X329442Y70124D01*
X329609Y69624D01*
X329526Y69124D01*
X329192Y68707D01*
X327526Y67874D01*
X326776Y67290D01*
X326276Y66457D01*
X326109Y65707D01*
X329609D01*
G01X316349Y127657D02*
Y130990D01*
G01Y130407D02*
X316016Y130740D01*
X315516Y130907D01*
X314932Y130990D01*
X314349Y130824D01*
X313849Y130490D01*
X313516Y129990D01*
X313349Y129324D01*
X313516Y128657D01*
X313849Y128157D01*
X314349Y127824D01*
X314932Y127657D01*
X315516Y127740D01*
X316016Y127990D01*
X316349Y128324D01*
G01X319032Y127657D02*
Y130990D01*
G01Y130157D02*
X319366Y130574D01*
X319866Y130907D01*
X320532Y130990D01*
X321116Y130907D01*
X321616Y130574D01*
X321866Y129990D01*
Y127657D01*
G01X327549Y132657D02*
Y127657D01*
G01Y128407D02*
X327216Y127990D01*
X326716Y127740D01*
X326132Y127657D01*
X325466Y127824D01*
X324966Y128240D01*
X324632Y128740D01*
X324549Y129324D01*
X324632Y129907D01*
X324966Y130407D01*
X325466Y130824D01*
X326132Y130990D01*
X326716Y130907D01*
X327132Y130740D01*
X327549Y130407D01*
G01X338582Y130574D02*
X337999Y130907D01*
X337499Y130990D01*
X336832Y130824D01*
X336332Y130490D01*
X335999Y129907D01*
X335916Y129324D01*
X335999Y128740D01*
X336332Y128240D01*
X336832Y127824D01*
X337499Y127657D01*
X338082Y127824D01*
X338582Y128157D01*
G01X342849Y127657D02*
X342349Y127740D01*
X341849Y128074D01*
X341516Y128657D01*
X341349Y129324D01*
X341516Y129990D01*
X341849Y130574D01*
X342349Y130907D01*
X342849Y130990D01*
X343349Y130907D01*
X343849Y130574D01*
X344182Y129990D01*
X344266Y129324D01*
X344182Y128657D01*
X343849Y128074D01*
X343349Y127740D01*
X342849Y127657D01*
G01X346949Y130990D02*
X348449Y127657D01*
X349949Y130990D01*
G01X352799Y129907D02*
X355466D01*
X355216Y130490D01*
X354799Y130824D01*
X354216Y130990D01*
X353632Y130907D01*
X353132Y130657D01*
X352799Y130074D01*
X352632Y129574D01*
Y129074D01*
X352799Y128574D01*
X353216Y128074D01*
X353716Y127740D01*
X354299Y127657D01*
X354882Y127824D01*
X355466Y128324D01*
G01X358482Y127657D02*
Y130990D01*
G01Y130324D02*
X358899Y130657D01*
X359316Y130907D01*
X359899Y130990D01*
X360316Y130907D01*
X360816Y130657D01*
G01X363999Y129907D02*
X366666D01*
X366416Y130490D01*
X365999Y130824D01*
X365416Y130990D01*
X364832Y130907D01*
X364332Y130657D01*
X363999Y130074D01*
X363832Y129574D01*
Y129074D01*
X363999Y128574D01*
X364416Y128074D01*
X364916Y127740D01*
X365499Y127657D01*
X366082Y127824D01*
X366666Y128324D01*
G01X372349Y132657D02*
Y127657D01*
G01Y128407D02*
X372016Y127990D01*
X371516Y127740D01*
X370932Y127657D01*
X370266Y127824D01*
X369766Y128240D01*
X369432Y128740D01*
X369349Y129324D01*
X369432Y129907D01*
X369766Y130407D01*
X370266Y130824D01*
X370932Y130990D01*
X371516Y130907D01*
X371932Y130740D01*
X372349Y130407D01*
G01X379966Y130990D02*
X380966Y127657D01*
X382049Y130990D01*
X383132Y127657D01*
X384132Y130990D01*
G01X387649D02*
Y127657D01*
G01Y132324D02*
X387482Y132407D01*
Y132574D01*
X387649Y132657D01*
X387816Y132574D01*
Y132407D01*
X387649Y132324D01*
G01X393249Y132657D02*
Y127657D01*
G01X392082Y130990D02*
X394416D01*
G01X397432Y127657D02*
Y132657D01*
G01Y130240D02*
X397849Y130657D01*
X398266Y130907D01*
X398932Y130990D01*
X399432Y130907D01*
X400016Y130574D01*
X400266Y130074D01*
Y127657D01*
G01X411382Y130574D02*
X410799Y130907D01*
X410299Y130990D01*
X409632Y130824D01*
X409132Y130490D01*
X408799Y129907D01*
X408716Y129324D01*
X408799Y128740D01*
X409132Y128240D01*
X409632Y127824D01*
X410299Y127657D01*
X410882Y127824D01*
X411382Y128157D01*
G01X415649Y127657D02*
X415149Y127740D01*
X414649Y128074D01*
X414316Y128657D01*
X414149Y129324D01*
X414316Y129990D01*
X414649Y130574D01*
X415149Y130907D01*
X415649Y130990D01*
X416149Y130907D01*
X416649Y130574D01*
X416982Y129990D01*
X417066Y129324D01*
X416982Y128657D01*
X416649Y128074D01*
X416149Y127740D01*
X415649Y127657D01*
G01X419749Y125990D02*
Y130990D01*
G01Y130240D02*
X420166Y130657D01*
X420582Y130907D01*
X421249Y130990D01*
X421832Y130907D01*
X422416Y130490D01*
X422666Y129907D01*
X422749Y129324D01*
X422666Y128740D01*
X422416Y128157D01*
X421916Y127824D01*
X421249Y127657D01*
X420666Y127740D01*
X420082Y127990D01*
X419749Y128324D01*
G01X425349Y125990D02*
Y130990D01*
G01Y130240D02*
X425766Y130657D01*
X426182Y130907D01*
X426849Y130990D01*
X427432Y130907D01*
X428016Y130490D01*
X428266Y129907D01*
X428349Y129324D01*
X428266Y128740D01*
X428016Y128157D01*
X427516Y127824D01*
X426849Y127657D01*
X426266Y127740D01*
X425682Y127990D01*
X425349Y128324D01*
G01X431199Y129907D02*
X433866D01*
X433616Y130490D01*
X433199Y130824D01*
X432616Y130990D01*
X432032Y130907D01*
X431532Y130657D01*
X431199Y130074D01*
X431032Y129574D01*
Y129074D01*
X431199Y128574D01*
X431616Y128074D01*
X432116Y127740D01*
X432699Y127657D01*
X433282Y127824D01*
X433866Y128324D01*
G01X436882Y127657D02*
Y130990D01*
G01Y130324D02*
X437299Y130657D01*
X437716Y130907D01*
X438299Y130990D01*
X438716Y130907D01*
X439216Y130657D01*
G01X314349Y141017D02*
Y145267D01*
X314516Y145684D01*
X314849Y145934D01*
X315349Y146017D01*
X315849Y145850D01*
X316099Y145434D01*
G01X315099Y144017D02*
X313432D01*
G01X320449Y141017D02*
X319949Y141100D01*
X319449Y141434D01*
X319116Y142017D01*
X318949Y142684D01*
X319116Y143350D01*
X319449Y143934D01*
X319949Y144267D01*
X320449Y144350D01*
X320949Y144267D01*
X321449Y143934D01*
X321782Y143350D01*
X321866Y142684D01*
X321782Y142017D01*
X321449Y141434D01*
X320949Y141100D01*
X320449Y141017D01*
G01X326049D02*
Y146017D01*
G01X331649Y141017D02*
Y146017D01*
G01X337249Y141017D02*
X336749Y141100D01*
X336249Y141434D01*
X335916Y142017D01*
X335749Y142684D01*
X335916Y143350D01*
X336249Y143934D01*
X336749Y144267D01*
X337249Y144350D01*
X337749Y144267D01*
X338249Y143934D01*
X338582Y143350D01*
X338666Y142684D01*
X338582Y142017D01*
X338249Y141434D01*
X337749Y141100D01*
X337249Y141017D01*
G01X340766Y144350D02*
X341766Y141017D01*
X342849Y144350D01*
X343932Y141017D01*
X344932Y144350D01*
G01X354549Y143517D02*
X356216D01*
Y142017D01*
X355716Y141517D01*
X355132Y141184D01*
X354299Y141017D01*
X353466Y141184D01*
X352882Y141517D01*
X352382Y142017D01*
X352049Y142600D01*
X351882Y143267D01*
Y143850D01*
X352049Y144350D01*
X352382Y144934D01*
X352882Y145434D01*
X353382Y145767D01*
X354049Y146017D01*
X354632D01*
X355299Y145850D01*
X355799Y145517D01*
G01X358399Y143267D02*
X361066D01*
X360816Y143850D01*
X360399Y144184D01*
X359816Y144350D01*
X359232Y144267D01*
X358732Y144017D01*
X358399Y143434D01*
X358232Y142934D01*
Y142434D01*
X358399Y141934D01*
X358816Y141434D01*
X359316Y141100D01*
X359899Y141017D01*
X360482Y141184D01*
X361066Y141684D01*
G01X364082Y141017D02*
Y144350D01*
G01Y143684D02*
X364499Y144017D01*
X364916Y144267D01*
X365499Y144350D01*
X365916Y144267D01*
X366416Y144017D01*
G01X369349Y141017D02*
Y146017D01*
G01Y143517D02*
X369766Y144017D01*
X370266Y144267D01*
X370766Y144350D01*
X371516Y144184D01*
X372016Y143850D01*
X372349Y143267D01*
Y142600D01*
X372182Y141934D01*
X371849Y141434D01*
X371266Y141100D01*
X370766Y141017D01*
X370266Y141100D01*
X369766Y141350D01*
X369349Y141767D01*
G01X375199Y143267D02*
X377866D01*
X377616Y143850D01*
X377199Y144184D01*
X376616Y144350D01*
X376032Y144267D01*
X375532Y144017D01*
X375199Y143434D01*
X375032Y142934D01*
Y142434D01*
X375199Y141934D01*
X375616Y141434D01*
X376116Y141100D01*
X376699Y141017D01*
X377282Y141184D01*
X377866Y141684D01*
G01X380882Y141017D02*
Y144350D01*
G01Y143684D02*
X381299Y144017D01*
X381716Y144267D01*
X382299Y144350D01*
X382716Y144267D01*
X383216Y144017D01*
G01X394749Y141017D02*
Y144350D01*
G01Y143767D02*
X394416Y144100D01*
X393916Y144267D01*
X393332Y144350D01*
X392749Y144184D01*
X392249Y143850D01*
X391916Y143350D01*
X391749Y142684D01*
X391916Y142017D01*
X392249Y141517D01*
X392749Y141184D01*
X393332Y141017D01*
X393916Y141100D01*
X394416Y141350D01*
X394749Y141684D01*
G01X397432Y141017D02*
Y144350D01*
G01Y143517D02*
X397766Y143934D01*
X398266Y144267D01*
X398932Y144350D01*
X399516Y144267D01*
X400016Y143934D01*
X400266Y143350D01*
Y141017D01*
G01X405949Y146017D02*
Y141017D01*
G01Y141767D02*
X405616Y141350D01*
X405116Y141100D01*
X404532Y141017D01*
X403866Y141184D01*
X403366Y141600D01*
X403032Y142100D01*
X402949Y142684D01*
X403032Y143267D01*
X403366Y143767D01*
X403866Y144184D01*
X404532Y144350D01*
X405116Y144267D01*
X405532Y144100D01*
X405949Y143767D01*
G01X414149Y139350D02*
Y144350D01*
G01Y143600D02*
X414566Y144017D01*
X414982Y144267D01*
X415649Y144350D01*
X416232Y144267D01*
X416816Y143850D01*
X417066Y143267D01*
X417149Y142684D01*
X417066Y142100D01*
X416816Y141517D01*
X416316Y141184D01*
X415649Y141017D01*
X415066Y141100D01*
X414482Y141350D01*
X414149Y141684D01*
G01X421249Y141017D02*
Y146017D01*
G01X425432Y144350D02*
Y142017D01*
X425766Y141434D01*
X426266Y141100D01*
X426849Y141017D01*
X427432Y141100D01*
X427932Y141434D01*
X428266Y142017D01*
G01Y141017D02*
Y144350D01*
G01X431282Y139767D02*
X431866Y139434D01*
X432532Y139350D01*
X433116Y139434D01*
X433616Y139850D01*
X433949Y140434D01*
Y144350D01*
G01Y143684D02*
X433616Y144017D01*
X433116Y144267D01*
X432532Y144350D01*
X431866Y144184D01*
X431449Y143850D01*
X431116Y143267D01*
X430949Y142684D01*
X431032Y142184D01*
X431366Y141600D01*
X431866Y141184D01*
X432532Y141017D01*
X433032Y141100D01*
X433616Y141434D01*
X433949Y141767D01*
G01X441566Y144350D02*
X442566Y141017D01*
X443649Y144350D01*
X444732Y141017D01*
X445732Y144350D01*
G01X449249D02*
Y141017D01*
G01Y145684D02*
X449082Y145767D01*
Y145934D01*
X449249Y146017D01*
X449416Y145934D01*
Y145767D01*
X449249Y145684D01*
G01X454849Y146017D02*
Y141017D01*
G01X453682Y144350D02*
X456016D01*
G01X459032Y141017D02*
Y146017D01*
G01Y143600D02*
X459449Y144017D01*
X459866Y144267D01*
X460532Y144350D01*
X461032Y144267D01*
X461616Y143934D01*
X461866Y143434D01*
Y141017D01*
G01X470482D02*
Y144350D01*
G01Y143684D02*
X470899Y144017D01*
X471316Y144267D01*
X471899Y144350D01*
X472316Y144267D01*
X472816Y144017D01*
G01X475999Y143267D02*
X478666D01*
X478416Y143850D01*
X477999Y144184D01*
X477416Y144350D01*
X476832Y144267D01*
X476332Y144017D01*
X475999Y143434D01*
X475832Y142934D01*
Y142434D01*
X475999Y141934D01*
X476416Y141434D01*
X476916Y141100D01*
X477499Y141017D01*
X478082Y141184D01*
X478666Y141684D01*
G01X481599Y141600D02*
X482016Y141267D01*
X482599Y141017D01*
X483099D01*
X483599Y141184D01*
X483932Y141434D01*
X484099Y141767D01*
X484016Y142267D01*
X483682Y142517D01*
X482182Y143017D01*
X481849Y143600D01*
X482016Y144017D01*
X482349Y144267D01*
X482849Y144350D01*
X483349Y144267D01*
X483849Y144017D01*
G01X488449Y144350D02*
Y141017D01*
G01Y145684D02*
X488282Y145767D01*
Y145934D01*
X488449Y146017D01*
X488616Y145934D01*
Y145767D01*
X488449Y145684D01*
G01X492632Y141017D02*
Y144350D01*
G01Y143517D02*
X492966Y143934D01*
X493466Y144267D01*
X494132Y144350D01*
X494716Y144267D01*
X495216Y143934D01*
X495466Y143350D01*
Y141017D01*
G01X306759Y355707D02*
Y117207D01*
G01X318259Y206707D02*
Y210040D01*
G01Y209457D02*
X317926Y209790D01*
X317426Y209957D01*
X316842Y210040D01*
X316259Y209874D01*
X315759Y209540D01*
X315426Y209040D01*
X315259Y208374D01*
X315426Y207707D01*
X315759Y207207D01*
X316259Y206874D01*
X316842Y206707D01*
X317426Y206790D01*
X317926Y207040D01*
X318259Y207374D01*
G01X320942Y206707D02*
Y210040D01*
G01Y209207D02*
X321276Y209624D01*
X321776Y209957D01*
X322442Y210040D01*
X323026Y209957D01*
X323526Y209624D01*
X323776Y209040D01*
Y206707D01*
G01X329459Y211707D02*
Y206707D01*
G01Y207457D02*
X329126Y207040D01*
X328626Y206790D01*
X328042Y206707D01*
X327376Y206874D01*
X326876Y207290D01*
X326542Y207790D01*
X326459Y208374D01*
X326542Y208957D01*
X326876Y209457D01*
X327376Y209874D01*
X328042Y210040D01*
X328626Y209957D01*
X329042Y209790D01*
X329459Y209457D01*
G01X337659Y206707D02*
Y211707D01*
G01Y209207D02*
X338076Y209707D01*
X338576Y209957D01*
X339076Y210040D01*
X339826Y209874D01*
X340326Y209540D01*
X340659Y208957D01*
Y208290D01*
X340492Y207624D01*
X340159Y207124D01*
X339576Y206790D01*
X339076Y206707D01*
X338576Y206790D01*
X338076Y207040D01*
X337659Y207457D01*
G01X344759Y206707D02*
X344259Y206790D01*
X343759Y207124D01*
X343426Y207707D01*
X343259Y208374D01*
X343426Y209040D01*
X343759Y209624D01*
X344259Y209957D01*
X344759Y210040D01*
X345259Y209957D01*
X345759Y209624D01*
X346092Y209040D01*
X346176Y208374D01*
X346092Y207707D01*
X345759Y207124D01*
X345259Y206790D01*
X344759Y206707D01*
G01X350359Y211707D02*
Y206707D01*
G01X349192Y210040D02*
X351526D01*
G01X355959Y211707D02*
Y206707D01*
G01X354792Y210040D02*
X357126D01*
G01X361559Y206707D02*
X361059Y206790D01*
X360559Y207124D01*
X360226Y207707D01*
X360059Y208374D01*
X360226Y209040D01*
X360559Y209624D01*
X361059Y209957D01*
X361559Y210040D01*
X362059Y209957D01*
X362559Y209624D01*
X362892Y209040D01*
X362976Y208374D01*
X362892Y207707D01*
X362559Y207124D01*
X362059Y206790D01*
X361559Y206707D01*
G01X364659D02*
Y210040D01*
G01Y209124D02*
X364909Y209540D01*
X365326Y209874D01*
X365909Y210040D01*
X366492Y209874D01*
X366909Y209540D01*
X367159Y209124D01*
Y206707D01*
G01Y209124D02*
X367409Y209540D01*
X367826Y209874D01*
X368409Y210040D01*
X368992Y209874D01*
X369409Y209540D01*
X369659Y209040D01*
Y206707D01*
G01X377109Y207290D02*
X377526Y206957D01*
X378109Y206707D01*
X378609D01*
X379109Y206874D01*
X379442Y207124D01*
X379609Y207457D01*
X379526Y207957D01*
X379192Y208207D01*
X377692Y208707D01*
X377359Y209290D01*
X377526Y209707D01*
X377859Y209957D01*
X378359Y210040D01*
X378859Y209957D01*
X379359Y209707D01*
G01X383959Y210040D02*
Y206707D01*
G01Y211374D02*
X383792Y211457D01*
Y211624D01*
X383959Y211707D01*
X384126Y211624D01*
Y211457D01*
X383959Y211374D01*
G01X391059Y211707D02*
Y206707D01*
G01Y207457D02*
X390726Y207040D01*
X390226Y206790D01*
X389642Y206707D01*
X388976Y206874D01*
X388476Y207290D01*
X388142Y207790D01*
X388059Y208374D01*
X388142Y208957D01*
X388476Y209457D01*
X388976Y209874D01*
X389642Y210040D01*
X390226Y209957D01*
X390642Y209790D01*
X391059Y209457D01*
G01X393909Y208957D02*
X396576D01*
X396326Y209540D01*
X395909Y209874D01*
X395326Y210040D01*
X394742Y209957D01*
X394242Y209707D01*
X393909Y209124D01*
X393742Y208624D01*
Y208124D01*
X393909Y207624D01*
X394326Y207124D01*
X394826Y206790D01*
X395409Y206707D01*
X395992Y206874D01*
X396576Y207374D01*
G01X314676Y222040D02*
X315676Y218707D01*
X316759Y222040D01*
X317842Y218707D01*
X318842Y222040D01*
G01X322359D02*
Y218707D01*
G01Y223374D02*
X322192Y223457D01*
Y223624D01*
X322359Y223707D01*
X322526Y223624D01*
Y223457D01*
X322359Y223374D01*
G01X327959Y223707D02*
Y218707D01*
G01X326792Y222040D02*
X329126D01*
G01X332142Y218707D02*
Y223707D01*
G01Y221290D02*
X332559Y221707D01*
X332976Y221957D01*
X333642Y222040D01*
X334142Y221957D01*
X334726Y221624D01*
X334976Y221124D01*
Y218707D01*
G01X339159D02*
X338659Y218790D01*
X338159Y219124D01*
X337826Y219707D01*
X337659Y220374D01*
X337826Y221040D01*
X338159Y221624D01*
X338659Y221957D01*
X339159Y222040D01*
X339659Y221957D01*
X340159Y221624D01*
X340492Y221040D01*
X340576Y220374D01*
X340492Y219707D01*
X340159Y219124D01*
X339659Y218790D01*
X339159Y218707D01*
G01X343342Y222040D02*
Y219707D01*
X343676Y219124D01*
X344176Y218790D01*
X344759Y218707D01*
X345342Y218790D01*
X345842Y219124D01*
X346176Y219707D01*
G01Y218707D02*
Y222040D01*
G01X350359Y223707D02*
Y218707D01*
G01X349192Y222040D02*
X351526D01*
G01X360309Y219290D02*
X360726Y218957D01*
X361309Y218707D01*
X361809D01*
X362309Y218874D01*
X362642Y219124D01*
X362809Y219457D01*
X362726Y219957D01*
X362392Y220207D01*
X360892Y220707D01*
X360559Y221290D01*
X360726Y221707D01*
X361059Y221957D01*
X361559Y222040D01*
X362059Y221957D01*
X362559Y221707D01*
G01X367159Y218707D02*
X366659Y218790D01*
X366159Y219124D01*
X365826Y219707D01*
X365659Y220374D01*
X365826Y221040D01*
X366159Y221624D01*
X366659Y221957D01*
X367159Y222040D01*
X367659Y221957D01*
X368159Y221624D01*
X368492Y221040D01*
X368576Y220374D01*
X368492Y219707D01*
X368159Y219124D01*
X367659Y218790D01*
X367159Y218707D01*
G01X372759D02*
Y223707D01*
G01X379859D02*
Y218707D01*
G01Y219457D02*
X379526Y219040D01*
X379026Y218790D01*
X378442Y218707D01*
X377776Y218874D01*
X377276Y219290D01*
X376942Y219790D01*
X376859Y220374D01*
X376942Y220957D01*
X377276Y221457D01*
X377776Y221874D01*
X378442Y222040D01*
X379026Y221957D01*
X379442Y221790D01*
X379859Y221457D01*
G01X382709Y220957D02*
X385376D01*
X385126Y221540D01*
X384709Y221874D01*
X384126Y222040D01*
X383542Y221957D01*
X383042Y221707D01*
X382709Y221124D01*
X382542Y220624D01*
Y220124D01*
X382709Y219624D01*
X383126Y219124D01*
X383626Y218790D01*
X384209Y218707D01*
X384792Y218874D01*
X385376Y219374D01*
G01X388392Y218707D02*
Y222040D01*
G01Y221374D02*
X388809Y221707D01*
X389226Y221957D01*
X389809Y222040D01*
X390226Y221957D01*
X390726Y221707D01*
G01X398259Y218707D02*
Y222040D01*
G01Y221124D02*
X398509Y221540D01*
X398926Y221874D01*
X399509Y222040D01*
X400092Y221874D01*
X400509Y221540D01*
X400759Y221124D01*
Y218707D01*
G01Y221124D02*
X401009Y221540D01*
X401426Y221874D01*
X402009Y222040D01*
X402592Y221874D01*
X403009Y221540D01*
X403259Y221040D01*
Y218707D01*
G01X407859D02*
Y222040D01*
G01Y221457D02*
X407526Y221790D01*
X407026Y221957D01*
X406442Y222040D01*
X405859Y221874D01*
X405359Y221540D01*
X405026Y221040D01*
X404859Y220374D01*
X405026Y219707D01*
X405359Y219207D01*
X405859Y218874D01*
X406442Y218707D01*
X407026Y218790D01*
X407526Y219040D01*
X407859Y219374D01*
G01X410709Y219290D02*
X411126Y218957D01*
X411709Y218707D01*
X412209D01*
X412709Y218874D01*
X413042Y219124D01*
X413209Y219457D01*
X413126Y219957D01*
X412792Y220207D01*
X411292Y220707D01*
X410959Y221290D01*
X411126Y221707D01*
X411459Y221957D01*
X411959Y222040D01*
X412459Y221957D01*
X412959Y221707D01*
G01X416142Y218707D02*
Y223707D01*
G01X418809Y222040D02*
X416142Y220124D01*
G01X417226Y220874D02*
X418976Y218707D01*
G01X427259Y217040D02*
Y222040D01*
G01Y221290D02*
X427676Y221707D01*
X428092Y221957D01*
X428759Y222040D01*
X429342Y221957D01*
X429926Y221540D01*
X430176Y220957D01*
X430259Y220374D01*
X430176Y219790D01*
X429926Y219207D01*
X429426Y218874D01*
X428759Y218707D01*
X428176Y218790D01*
X427592Y219040D01*
X427259Y219374D01*
G01X435859Y218707D02*
Y222040D01*
G01Y221457D02*
X435526Y221790D01*
X435026Y221957D01*
X434442Y222040D01*
X433859Y221874D01*
X433359Y221540D01*
X433026Y221040D01*
X432859Y220374D01*
X433026Y219707D01*
X433359Y219207D01*
X433859Y218874D01*
X434442Y218707D01*
X435026Y218790D01*
X435526Y219040D01*
X435859Y219374D01*
G01X441459Y223707D02*
Y218707D01*
G01Y219457D02*
X441126Y219040D01*
X440626Y218790D01*
X440042Y218707D01*
X439376Y218874D01*
X438876Y219290D01*
X438542Y219790D01*
X438459Y220374D01*
X438542Y220957D01*
X438876Y221457D01*
X439376Y221874D01*
X440042Y222040D01*
X440626Y221957D01*
X441042Y221790D01*
X441459Y221457D01*
G01X451159Y218707D02*
X450659Y218790D01*
X450159Y219124D01*
X449826Y219707D01*
X449659Y220374D01*
X449826Y221040D01*
X450159Y221624D01*
X450659Y221957D01*
X451159Y222040D01*
X451659Y221957D01*
X452159Y221624D01*
X452492Y221040D01*
X452576Y220374D01*
X452492Y219707D01*
X452159Y219124D01*
X451659Y218790D01*
X451159Y218707D01*
G01X455342D02*
Y222040D01*
G01Y221207D02*
X455676Y221624D01*
X456176Y221957D01*
X456842Y222040D01*
X457426Y221957D01*
X457926Y221624D01*
X458176Y221040D01*
Y218707D01*
G01X467959Y223707D02*
Y218707D01*
G01X466792Y222040D02*
X469126D01*
G01X473559Y218707D02*
X473059Y218790D01*
X472559Y219124D01*
X472226Y219707D01*
X472059Y220374D01*
X472226Y221040D01*
X472559Y221624D01*
X473059Y221957D01*
X473559Y222040D01*
X474059Y221957D01*
X474559Y221624D01*
X474892Y221040D01*
X474976Y220374D01*
X474892Y219707D01*
X474559Y219124D01*
X474059Y218790D01*
X473559Y218707D01*
G01X477659Y217040D02*
Y222040D01*
G01Y221290D02*
X478076Y221707D01*
X478492Y221957D01*
X479159Y222040D01*
X479742Y221957D01*
X480326Y221540D01*
X480576Y220957D01*
X480659Y220374D01*
X480576Y219790D01*
X480326Y219207D01*
X479826Y218874D01*
X479159Y218707D01*
X478576Y218790D01*
X477992Y219040D01*
X477659Y219374D01*
G01X316259Y191707D02*
Y195957D01*
X316426Y196374D01*
X316759Y196624D01*
X317259Y196707D01*
X317759Y196540D01*
X318009Y196124D01*
G01X317009Y194707D02*
X315342D01*
G01X322359Y191707D02*
X321859Y191790D01*
X321359Y192124D01*
X321026Y192707D01*
X320859Y193374D01*
X321026Y194040D01*
X321359Y194624D01*
X321859Y194957D01*
X322359Y195040D01*
X322859Y194957D01*
X323359Y194624D01*
X323692Y194040D01*
X323776Y193374D01*
X323692Y192707D01*
X323359Y192124D01*
X322859Y191790D01*
X322359Y191707D01*
G01X327959D02*
Y196707D01*
G01X333559Y191707D02*
Y196707D01*
G01X339159Y191707D02*
X338659Y191790D01*
X338159Y192124D01*
X337826Y192707D01*
X337659Y193374D01*
X337826Y194040D01*
X338159Y194624D01*
X338659Y194957D01*
X339159Y195040D01*
X339659Y194957D01*
X340159Y194624D01*
X340492Y194040D01*
X340576Y193374D01*
X340492Y192707D01*
X340159Y192124D01*
X339659Y191790D01*
X339159Y191707D01*
G01X342676Y195040D02*
X343676Y191707D01*
X344759Y195040D01*
X345842Y191707D01*
X346842Y195040D01*
G01X356459Y194207D02*
X358126D01*
Y192707D01*
X357626Y192207D01*
X357042Y191874D01*
X356209Y191707D01*
X355376Y191874D01*
X354792Y192207D01*
X354292Y192707D01*
X353959Y193290D01*
X353792Y193957D01*
Y194540D01*
X353959Y195040D01*
X354292Y195624D01*
X354792Y196124D01*
X355292Y196457D01*
X355959Y196707D01*
X356542D01*
X357209Y196540D01*
X357709Y196207D01*
G01X360309Y193957D02*
X362976D01*
X362726Y194540D01*
X362309Y194874D01*
X361726Y195040D01*
X361142Y194957D01*
X360642Y194707D01*
X360309Y194124D01*
X360142Y193624D01*
Y193124D01*
X360309Y192624D01*
X360726Y192124D01*
X361226Y191790D01*
X361809Y191707D01*
X362392Y191874D01*
X362976Y192374D01*
G01X365992Y191707D02*
Y195040D01*
G01Y194374D02*
X366409Y194707D01*
X366826Y194957D01*
X367409Y195040D01*
X367826Y194957D01*
X368326Y194707D01*
G01X371259Y191707D02*
Y196707D01*
G01Y194207D02*
X371676Y194707D01*
X372176Y194957D01*
X372676Y195040D01*
X373426Y194874D01*
X373926Y194540D01*
X374259Y193957D01*
Y193290D01*
X374092Y192624D01*
X373759Y192124D01*
X373176Y191790D01*
X372676Y191707D01*
X372176Y191790D01*
X371676Y192040D01*
X371259Y192457D01*
G01X377109Y193957D02*
X379776D01*
X379526Y194540D01*
X379109Y194874D01*
X378526Y195040D01*
X377942Y194957D01*
X377442Y194707D01*
X377109Y194124D01*
X376942Y193624D01*
Y193124D01*
X377109Y192624D01*
X377526Y192124D01*
X378026Y191790D01*
X378609Y191707D01*
X379192Y191874D01*
X379776Y192374D01*
G01X382792Y191707D02*
Y195040D01*
G01Y194374D02*
X383209Y194707D01*
X383626Y194957D01*
X384209Y195040D01*
X384626Y194957D01*
X385126Y194707D01*
G01X316259Y170707D02*
Y174957D01*
X316426Y175374D01*
X316759Y175624D01*
X317259Y175707D01*
X317759Y175540D01*
X318009Y175124D01*
G01X317009Y173707D02*
X315342D01*
G01X322359Y170707D02*
X321859Y170790D01*
X321359Y171124D01*
X321026Y171707D01*
X320859Y172374D01*
X321026Y173040D01*
X321359Y173624D01*
X321859Y173957D01*
X322359Y174040D01*
X322859Y173957D01*
X323359Y173624D01*
X323692Y173040D01*
X323776Y172374D01*
X323692Y171707D01*
X323359Y171124D01*
X322859Y170790D01*
X322359Y170707D01*
G01X327959D02*
Y175707D01*
G01X333559Y170707D02*
Y175707D01*
G01X339159Y170707D02*
X338659Y170790D01*
X338159Y171124D01*
X337826Y171707D01*
X337659Y172374D01*
X337826Y173040D01*
X338159Y173624D01*
X338659Y173957D01*
X339159Y174040D01*
X339659Y173957D01*
X340159Y173624D01*
X340492Y173040D01*
X340576Y172374D01*
X340492Y171707D01*
X340159Y171124D01*
X339659Y170790D01*
X339159Y170707D01*
G01X342676Y174040D02*
X343676Y170707D01*
X344759Y174040D01*
X345842Y170707D01*
X346842Y174040D01*
G01X356459Y173207D02*
X358126D01*
Y171707D01*
X357626Y171207D01*
X357042Y170874D01*
X356209Y170707D01*
X355376Y170874D01*
X354792Y171207D01*
X354292Y171707D01*
X353959Y172290D01*
X353792Y172957D01*
Y173540D01*
X353959Y174040D01*
X354292Y174624D01*
X354792Y175124D01*
X355292Y175457D01*
X355959Y175707D01*
X356542D01*
X357209Y175540D01*
X357709Y175207D01*
G01X360309Y172957D02*
X362976D01*
X362726Y173540D01*
X362309Y173874D01*
X361726Y174040D01*
X361142Y173957D01*
X360642Y173707D01*
X360309Y173124D01*
X360142Y172624D01*
Y172124D01*
X360309Y171624D01*
X360726Y171124D01*
X361226Y170790D01*
X361809Y170707D01*
X362392Y170874D01*
X362976Y171374D01*
G01X365992Y170707D02*
Y174040D01*
G01Y173374D02*
X366409Y173707D01*
X366826Y173957D01*
X367409Y174040D01*
X367826Y173957D01*
X368326Y173707D01*
G01X371259Y170707D02*
Y175707D01*
G01Y173207D02*
X371676Y173707D01*
X372176Y173957D01*
X372676Y174040D01*
X373426Y173874D01*
X373926Y173540D01*
X374259Y172957D01*
Y172290D01*
X374092Y171624D01*
X373759Y171124D01*
X373176Y170790D01*
X372676Y170707D01*
X372176Y170790D01*
X371676Y171040D01*
X371259Y171457D01*
G01X377109Y172957D02*
X379776D01*
X379526Y173540D01*
X379109Y173874D01*
X378526Y174040D01*
X377942Y173957D01*
X377442Y173707D01*
X377109Y173124D01*
X376942Y172624D01*
Y172124D01*
X377109Y171624D01*
X377526Y171124D01*
X378026Y170790D01*
X378609Y170707D01*
X379192Y170874D01*
X379776Y171374D01*
G01X382792Y170707D02*
Y174040D01*
G01Y173374D02*
X383209Y173707D01*
X383626Y173957D01*
X384209Y174040D01*
X384626Y173957D01*
X385126Y173707D01*
G01X396659Y170707D02*
Y174040D01*
G01Y173457D02*
X396326Y173790D01*
X395826Y173957D01*
X395242Y174040D01*
X394659Y173874D01*
X394159Y173540D01*
X393826Y173040D01*
X393659Y172374D01*
X393826Y171707D01*
X394159Y171207D01*
X394659Y170874D01*
X395242Y170707D01*
X395826Y170790D01*
X396326Y171040D01*
X396659Y171374D01*
G01X399342Y170707D02*
Y174040D01*
G01Y173207D02*
X399676Y173624D01*
X400176Y173957D01*
X400842Y174040D01*
X401426Y173957D01*
X401926Y173624D01*
X402176Y173040D01*
Y170707D01*
G01X407859Y175707D02*
Y170707D01*
G01Y171457D02*
X407526Y171040D01*
X407026Y170790D01*
X406442Y170707D01*
X405776Y170874D01*
X405276Y171290D01*
X404942Y171790D01*
X404859Y172374D01*
X404942Y172957D01*
X405276Y173457D01*
X405776Y173874D01*
X406442Y174040D01*
X407026Y173957D01*
X407442Y173790D01*
X407859Y173457D01*
G01X416059Y169040D02*
Y174040D01*
G01Y173290D02*
X416476Y173707D01*
X416892Y173957D01*
X417559Y174040D01*
X418142Y173957D01*
X418726Y173540D01*
X418976Y172957D01*
X419059Y172374D01*
X418976Y171790D01*
X418726Y171207D01*
X418226Y170874D01*
X417559Y170707D01*
X416976Y170790D01*
X416392Y171040D01*
X416059Y171374D01*
G01X423159Y170707D02*
Y175707D01*
G01X427342Y174040D02*
Y171707D01*
X427676Y171124D01*
X428176Y170790D01*
X428759Y170707D01*
X429342Y170790D01*
X429842Y171124D01*
X430176Y171707D01*
G01Y170707D02*
Y174040D01*
G01X433192Y169457D02*
X433776Y169124D01*
X434442Y169040D01*
X435026Y169124D01*
X435526Y169540D01*
X435859Y170124D01*
Y174040D01*
G01Y173374D02*
X435526Y173707D01*
X435026Y173957D01*
X434442Y174040D01*
X433776Y173874D01*
X433359Y173540D01*
X433026Y172957D01*
X432859Y172374D01*
X432942Y171874D01*
X433276Y171290D01*
X433776Y170874D01*
X434442Y170707D01*
X434942Y170790D01*
X435526Y171124D01*
X435859Y171457D01*
G01X443476Y174040D02*
X444476Y170707D01*
X445559Y174040D01*
X446642Y170707D01*
X447642Y174040D01*
G01X451159D02*
Y170707D01*
G01Y175374D02*
X450992Y175457D01*
Y175624D01*
X451159Y175707D01*
X451326Y175624D01*
Y175457D01*
X451159Y175374D01*
G01X456759Y175707D02*
Y170707D01*
G01X455592Y174040D02*
X457926D01*
G01X460942Y170707D02*
Y175707D01*
G01Y173290D02*
X461359Y173707D01*
X461776Y173957D01*
X462442Y174040D01*
X462942Y173957D01*
X463526Y173624D01*
X463776Y173124D01*
Y170707D01*
G01X472392D02*
Y174040D01*
G01Y173374D02*
X472809Y173707D01*
X473226Y173957D01*
X473809Y174040D01*
X474226Y173957D01*
X474726Y173707D01*
G01X477909Y172957D02*
X480576D01*
X480326Y173540D01*
X479909Y173874D01*
X479326Y174040D01*
X478742Y173957D01*
X478242Y173707D01*
X477909Y173124D01*
X477742Y172624D01*
Y172124D01*
X477909Y171624D01*
X478326Y171124D01*
X478826Y170790D01*
X479409Y170707D01*
X479992Y170874D01*
X480576Y171374D01*
G01X483509Y171290D02*
X483926Y170957D01*
X484509Y170707D01*
X485009D01*
X485509Y170874D01*
X485842Y171124D01*
X486009Y171457D01*
X485926Y171957D01*
X485592Y172207D01*
X484092Y172707D01*
X483759Y173290D01*
X483926Y173707D01*
X484259Y173957D01*
X484759Y174040D01*
X485259Y173957D01*
X485759Y173707D01*
G01X490359Y174040D02*
Y170707D01*
G01Y175374D02*
X490192Y175457D01*
Y175624D01*
X490359Y175707D01*
X490526Y175624D01*
Y175457D01*
X490359Y175374D01*
G01X494542Y170707D02*
Y174040D01*
G01Y173207D02*
X494876Y173624D01*
X495376Y173957D01*
X496042Y174040D01*
X496626Y173957D01*
X497126Y173624D01*
X497376Y173040D01*
Y170707D01*
G01X324509Y293790D02*
X324926Y293457D01*
X325509Y293207D01*
X326009D01*
X326509Y293374D01*
X326842Y293624D01*
X327009Y293957D01*
X326926Y294457D01*
X326592Y294707D01*
X325092Y295207D01*
X324759Y295790D01*
X324926Y296207D01*
X325259Y296457D01*
X325759Y296540D01*
X326259Y296457D01*
X326759Y296207D01*
G01X331359Y293207D02*
X330859Y293290D01*
X330359Y293624D01*
X330026Y294207D01*
X329859Y294874D01*
X330026Y295540D01*
X330359Y296124D01*
X330859Y296457D01*
X331359Y296540D01*
X331859Y296457D01*
X332359Y296124D01*
X332692Y295540D01*
X332776Y294874D01*
X332692Y294207D01*
X332359Y293624D01*
X331859Y293290D01*
X331359Y293207D01*
G01X336959D02*
Y298207D01*
G01X344059D02*
Y293207D01*
G01Y293957D02*
X343726Y293540D01*
X343226Y293290D01*
X342642Y293207D01*
X341976Y293374D01*
X341476Y293790D01*
X341142Y294290D01*
X341059Y294874D01*
X341142Y295457D01*
X341476Y295957D01*
X341976Y296374D01*
X342642Y296540D01*
X343226Y296457D01*
X343642Y296290D01*
X344059Y295957D01*
G01X346909Y295457D02*
X349576D01*
X349326Y296040D01*
X348909Y296374D01*
X348326Y296540D01*
X347742Y296457D01*
X347242Y296207D01*
X346909Y295624D01*
X346742Y295124D01*
Y294624D01*
X346909Y294124D01*
X347326Y293624D01*
X347826Y293290D01*
X348409Y293207D01*
X348992Y293374D01*
X349576Y293874D01*
G01X352592Y293207D02*
Y296540D01*
G01Y295874D02*
X353009Y296207D01*
X353426Y296457D01*
X354009Y296540D01*
X354426Y296457D01*
X354926Y296207D01*
G01X362459Y293207D02*
Y296540D01*
G01Y295624D02*
X362709Y296040D01*
X363126Y296374D01*
X363709Y296540D01*
X364292Y296374D01*
X364709Y296040D01*
X364959Y295624D01*
Y293207D01*
G01Y295624D02*
X365209Y296040D01*
X365626Y296374D01*
X366209Y296540D01*
X366792Y296374D01*
X367209Y296040D01*
X367459Y295540D01*
Y293207D01*
G01X372059D02*
Y296540D01*
G01Y295957D02*
X371726Y296290D01*
X371226Y296457D01*
X370642Y296540D01*
X370059Y296374D01*
X369559Y296040D01*
X369226Y295540D01*
X369059Y294874D01*
X369226Y294207D01*
X369559Y293707D01*
X370059Y293374D01*
X370642Y293207D01*
X371226Y293290D01*
X371726Y293540D01*
X372059Y293874D01*
G01X374909Y293790D02*
X375326Y293457D01*
X375909Y293207D01*
X376409D01*
X376909Y293374D01*
X377242Y293624D01*
X377409Y293957D01*
X377326Y294457D01*
X376992Y294707D01*
X375492Y295207D01*
X375159Y295790D01*
X375326Y296207D01*
X375659Y296457D01*
X376159Y296540D01*
X376659Y296457D01*
X377159Y296207D01*
G01X380342Y293207D02*
Y298207D01*
G01X383009Y296540D02*
X380342Y294624D01*
G01X381426Y295374D02*
X383176Y293207D01*
G01X391459Y291540D02*
Y296540D01*
G01Y295790D02*
X391876Y296207D01*
X392292Y296457D01*
X392959Y296540D01*
X393542Y296457D01*
X394126Y296040D01*
X394376Y295457D01*
X394459Y294874D01*
X394376Y294290D01*
X394126Y293707D01*
X393626Y293374D01*
X392959Y293207D01*
X392376Y293290D01*
X391792Y293540D01*
X391459Y293874D01*
G01X400059Y293207D02*
Y296540D01*
G01Y295957D02*
X399726Y296290D01*
X399226Y296457D01*
X398642Y296540D01*
X398059Y296374D01*
X397559Y296040D01*
X397226Y295540D01*
X397059Y294874D01*
X397226Y294207D01*
X397559Y293707D01*
X398059Y293374D01*
X398642Y293207D01*
X399226Y293290D01*
X399726Y293540D01*
X400059Y293874D01*
G01X405659Y298207D02*
Y293207D01*
G01Y293957D02*
X405326Y293540D01*
X404826Y293290D01*
X404242Y293207D01*
X403576Y293374D01*
X403076Y293790D01*
X402742Y294290D01*
X402659Y294874D01*
X402742Y295457D01*
X403076Y295957D01*
X403576Y296374D01*
X404242Y296540D01*
X404826Y296457D01*
X405242Y296290D01*
X405659Y295957D01*
G01X324676Y314540D02*
X325676Y311207D01*
X326759Y314540D01*
X327842Y311207D01*
X328842Y314540D01*
G01X330942Y311207D02*
Y316207D01*
G01Y313790D02*
X331359Y314207D01*
X331776Y314457D01*
X332442Y314540D01*
X332942Y314457D01*
X333526Y314124D01*
X333776Y313624D01*
Y311207D01*
G01X337959Y314540D02*
Y311207D01*
G01Y315874D02*
X337792Y315957D01*
Y316124D01*
X337959Y316207D01*
X338126Y316124D01*
Y315957D01*
X337959Y315874D01*
G01X344892Y314124D02*
X344309Y314457D01*
X343809Y314540D01*
X343142Y314374D01*
X342642Y314040D01*
X342309Y313457D01*
X342226Y312874D01*
X342309Y312290D01*
X342642Y311790D01*
X343142Y311374D01*
X343809Y311207D01*
X344392Y311374D01*
X344892Y311707D01*
G01X347742Y311207D02*
Y316207D01*
G01Y313790D02*
X348159Y314207D01*
X348576Y314457D01*
X349242Y314540D01*
X349742Y314457D01*
X350326Y314124D01*
X350576Y313624D01*
Y311207D01*
G01X359109Y311790D02*
X359526Y311457D01*
X360109Y311207D01*
X360609D01*
X361109Y311374D01*
X361442Y311624D01*
X361609Y311957D01*
X361526Y312457D01*
X361192Y312707D01*
X359692Y313207D01*
X359359Y313790D01*
X359526Y314207D01*
X359859Y314457D01*
X360359Y314540D01*
X360859Y314457D01*
X361359Y314207D01*
G01X365959Y314540D02*
Y311207D01*
G01Y315874D02*
X365792Y315957D01*
Y316124D01*
X365959Y316207D01*
X366126Y316124D01*
Y315957D01*
X365959Y315874D01*
G01X370309Y314540D02*
X372809D01*
X370309Y311207D01*
X372809D01*
G01X375909Y313457D02*
X378576D01*
X378326Y314040D01*
X377909Y314374D01*
X377326Y314540D01*
X376742Y314457D01*
X376242Y314207D01*
X375909Y313624D01*
X375742Y313124D01*
Y312624D01*
X375909Y312124D01*
X376326Y311624D01*
X376826Y311290D01*
X377409Y311207D01*
X377992Y311374D01*
X378576Y311874D01*
G01X388359Y314540D02*
Y311207D01*
G01Y315874D02*
X388192Y315957D01*
Y316124D01*
X388359Y316207D01*
X388526Y316124D01*
Y315957D01*
X388359Y315874D01*
G01X392709Y311790D02*
X393126Y311457D01*
X393709Y311207D01*
X394209D01*
X394709Y311374D01*
X395042Y311624D01*
X395209Y311957D01*
X395126Y312457D01*
X394792Y312707D01*
X393292Y313207D01*
X392959Y313790D01*
X393126Y314207D01*
X393459Y314457D01*
X393959Y314540D01*
X394459Y314457D01*
X394959Y314207D01*
G01X403659Y311207D02*
Y316207D01*
G01Y313707D02*
X404076Y314207D01*
X404576Y314457D01*
X405076Y314540D01*
X405826Y314374D01*
X406326Y314040D01*
X406659Y313457D01*
Y312790D01*
X406492Y312124D01*
X406159Y311624D01*
X405576Y311290D01*
X405076Y311207D01*
X404576Y311290D01*
X404076Y311540D01*
X403659Y311957D01*
G01X410759Y314540D02*
Y311207D01*
G01Y315874D02*
X410592Y315957D01*
Y316124D01*
X410759Y316207D01*
X410926Y316124D01*
Y315957D01*
X410759Y315874D01*
G01X415192Y309957D02*
X415776Y309624D01*
X416442Y309540D01*
X417026Y309624D01*
X417526Y310040D01*
X417859Y310624D01*
Y314540D01*
G01Y313874D02*
X417526Y314207D01*
X417026Y314457D01*
X416442Y314540D01*
X415776Y314374D01*
X415359Y314040D01*
X415026Y313457D01*
X414859Y312874D01*
X414942Y312374D01*
X415276Y311790D01*
X415776Y311374D01*
X416442Y311207D01*
X416942Y311290D01*
X417526Y311624D01*
X417859Y311957D01*
G01X420792Y309957D02*
X421376Y309624D01*
X422042Y309540D01*
X422626Y309624D01*
X423126Y310040D01*
X423459Y310624D01*
Y314540D01*
G01Y313874D02*
X423126Y314207D01*
X422626Y314457D01*
X422042Y314540D01*
X421376Y314374D01*
X420959Y314040D01*
X420626Y313457D01*
X420459Y312874D01*
X420542Y312374D01*
X420876Y311790D01*
X421376Y311374D01*
X422042Y311207D01*
X422542Y311290D01*
X423126Y311624D01*
X423459Y311957D01*
G01X426309Y313457D02*
X428976D01*
X428726Y314040D01*
X428309Y314374D01*
X427726Y314540D01*
X427142Y314457D01*
X426642Y314207D01*
X426309Y313624D01*
X426142Y313124D01*
Y312624D01*
X426309Y312124D01*
X426726Y311624D01*
X427226Y311290D01*
X427809Y311207D01*
X428392Y311374D01*
X428976Y311874D01*
G01X431992Y311207D02*
Y314540D01*
G01Y313874D02*
X432409Y314207D01*
X432826Y314457D01*
X433409Y314540D01*
X433826Y314457D01*
X434326Y314207D01*
G01X444359Y316207D02*
Y311207D01*
G01X443192Y314540D02*
X445526D01*
G01X448542Y311207D02*
Y316207D01*
G01Y313790D02*
X448959Y314207D01*
X449376Y314457D01*
X450042Y314540D01*
X450542Y314457D01*
X451126Y314124D01*
X451376Y313624D01*
Y311207D01*
G01X457059D02*
Y314540D01*
G01Y313957D02*
X456726Y314290D01*
X456226Y314457D01*
X455642Y314540D01*
X455059Y314374D01*
X454559Y314040D01*
X454226Y313540D01*
X454059Y312874D01*
X454226Y312207D01*
X454559Y311707D01*
X455059Y311374D01*
X455642Y311207D01*
X456226Y311290D01*
X456726Y311540D01*
X457059Y311874D01*
G01X459742Y311207D02*
Y314540D01*
G01Y313707D02*
X460076Y314124D01*
X460576Y314457D01*
X461242Y314540D01*
X461826Y314457D01*
X462326Y314124D01*
X462576Y313540D01*
Y311207D01*
G01X473859D02*
Y314540D01*
G01Y313957D02*
X473526Y314290D01*
X473026Y314457D01*
X472442Y314540D01*
X471859Y314374D01*
X471359Y314040D01*
X471026Y313540D01*
X470859Y312874D01*
X471026Y312207D01*
X471359Y311707D01*
X471859Y311374D01*
X472442Y311207D01*
X473026Y311290D01*
X473526Y311540D01*
X473859Y311874D01*
G01X476542Y311207D02*
Y314540D01*
G01Y313707D02*
X476876Y314124D01*
X477376Y314457D01*
X478042Y314540D01*
X478626Y314457D01*
X479126Y314124D01*
X479376Y313540D01*
Y311207D01*
G01X482142D02*
Y314540D01*
G01Y313707D02*
X482476Y314124D01*
X482976Y314457D01*
X483642Y314540D01*
X484226Y314457D01*
X484726Y314124D01*
X484976Y313540D01*
Y311207D01*
G01X487742Y314540D02*
Y312207D01*
X488076Y311624D01*
X488576Y311290D01*
X489159Y311207D01*
X489742Y311290D01*
X490242Y311624D01*
X490576Y312207D01*
G01Y311207D02*
Y314540D01*
G01X496259Y311207D02*
Y314540D01*
G01Y313957D02*
X495926Y314290D01*
X495426Y314457D01*
X494842Y314540D01*
X494259Y314374D01*
X493759Y314040D01*
X493426Y313540D01*
X493259Y312874D01*
X493426Y312207D01*
X493759Y311707D01*
X494259Y311374D01*
X494842Y311207D01*
X495426Y311290D01*
X495926Y311540D01*
X496259Y311874D01*
G01X500359Y311207D02*
Y316207D01*
G01X316759Y320207D02*
Y325207D01*
X315759Y324207D01*
G01Y320207D02*
X317759D01*
G01X322359Y320040D02*
X322192Y320124D01*
Y320290D01*
X322359Y320374D01*
X322526Y320290D01*
Y320124D01*
X322359Y320040D01*
G01X327959Y320207D02*
X327292Y320290D01*
X326709Y320624D01*
X326209Y321124D01*
X325876Y321707D01*
X325709Y322374D01*
Y323040D01*
X325876Y323707D01*
X326209Y324290D01*
X326709Y324790D01*
X327292Y325124D01*
X327959Y325207D01*
X328626Y325124D01*
X329209Y324790D01*
X329709Y324290D01*
X330042Y323707D01*
X330209Y323040D01*
Y322374D01*
X330042Y321707D01*
X329709Y321124D01*
X329209Y320624D01*
X328626Y320290D01*
X327959Y320207D01*
G01X332142D02*
Y323540D01*
G01Y322707D02*
X332476Y323124D01*
X332976Y323457D01*
X333642Y323540D01*
X334226Y323457D01*
X334726Y323124D01*
X334976Y322540D01*
Y320207D01*
G01X337909Y322457D02*
X340576D01*
X340326Y323040D01*
X339909Y323374D01*
X339326Y323540D01*
X338742Y323457D01*
X338242Y323207D01*
X337909Y322624D01*
X337742Y322124D01*
Y321624D01*
X337909Y321124D01*
X338326Y320624D01*
X338826Y320290D01*
X339409Y320207D01*
X339992Y320374D01*
X340576Y320874D01*
G01X349109Y320790D02*
X349526Y320457D01*
X350109Y320207D01*
X350609D01*
X351109Y320374D01*
X351442Y320624D01*
X351609Y320957D01*
X351526Y321457D01*
X351192Y321707D01*
X349692Y322207D01*
X349359Y322790D01*
X349526Y323207D01*
X349859Y323457D01*
X350359Y323540D01*
X350859Y323457D01*
X351359Y323207D01*
G01X355959Y323540D02*
Y320207D01*
G01Y324874D02*
X355792Y324957D01*
Y325124D01*
X355959Y325207D01*
X356126Y325124D01*
Y324957D01*
X355959Y324874D01*
G01X363059Y325207D02*
Y320207D01*
G01Y320957D02*
X362726Y320540D01*
X362226Y320290D01*
X361642Y320207D01*
X360976Y320374D01*
X360476Y320790D01*
X360142Y321290D01*
X360059Y321874D01*
X360142Y322457D01*
X360476Y322957D01*
X360976Y323374D01*
X361642Y323540D01*
X362226Y323457D01*
X362642Y323290D01*
X363059Y322957D01*
G01X365909Y322457D02*
X368576D01*
X368326Y323040D01*
X367909Y323374D01*
X367326Y323540D01*
X366742Y323457D01*
X366242Y323207D01*
X365909Y322624D01*
X365742Y322124D01*
Y321624D01*
X365909Y321124D01*
X366326Y320624D01*
X366826Y320290D01*
X367409Y320207D01*
X367992Y320374D01*
X368576Y320874D01*
G01X376276Y323540D02*
X377276Y320207D01*
X378359Y323540D01*
X379442Y320207D01*
X380442Y323540D01*
G01X383959D02*
Y320207D01*
G01Y324874D02*
X383792Y324957D01*
Y325124D01*
X383959Y325207D01*
X384126Y325124D01*
Y324957D01*
X383959Y324874D01*
G01X389559Y325207D02*
Y320207D01*
G01X388392Y323540D02*
X390726D01*
G01X393742Y320207D02*
Y325207D01*
G01Y322790D02*
X394159Y323207D01*
X394576Y323457D01*
X395242Y323540D01*
X395742Y323457D01*
X396326Y323124D01*
X396576Y322624D01*
Y320207D01*
G01X405109Y320790D02*
X405526Y320457D01*
X406109Y320207D01*
X406609D01*
X407109Y320374D01*
X407442Y320624D01*
X407609Y320957D01*
X407526Y321457D01*
X407192Y321707D01*
X405692Y322207D01*
X405359Y322790D01*
X405526Y323207D01*
X405859Y323457D01*
X406359Y323540D01*
X406859Y323457D01*
X407359Y323207D01*
G01X411959Y320207D02*
X411459Y320290D01*
X410959Y320624D01*
X410626Y321207D01*
X410459Y321874D01*
X410626Y322540D01*
X410959Y323124D01*
X411459Y323457D01*
X411959Y323540D01*
X412459Y323457D01*
X412959Y323124D01*
X413292Y322540D01*
X413376Y321874D01*
X413292Y321207D01*
X412959Y320624D01*
X412459Y320290D01*
X411959Y320207D01*
G01X417559D02*
Y325207D01*
G01X424659D02*
Y320207D01*
G01Y320957D02*
X424326Y320540D01*
X423826Y320290D01*
X423242Y320207D01*
X422576Y320374D01*
X422076Y320790D01*
X421742Y321290D01*
X421659Y321874D01*
X421742Y322457D01*
X422076Y322957D01*
X422576Y323374D01*
X423242Y323540D01*
X423826Y323457D01*
X424242Y323290D01*
X424659Y322957D01*
G01X427509Y322457D02*
X430176D01*
X429926Y323040D01*
X429509Y323374D01*
X428926Y323540D01*
X428342Y323457D01*
X427842Y323207D01*
X427509Y322624D01*
X427342Y322124D01*
Y321624D01*
X427509Y321124D01*
X427926Y320624D01*
X428426Y320290D01*
X429009Y320207D01*
X429592Y320374D01*
X430176Y320874D01*
G01X433192Y320207D02*
Y323540D01*
G01Y322874D02*
X433609Y323207D01*
X434026Y323457D01*
X434609Y323540D01*
X435026Y323457D01*
X435526Y323207D01*
G01X443059Y320207D02*
Y323540D01*
G01Y322624D02*
X443309Y323040D01*
X443726Y323374D01*
X444309Y323540D01*
X444892Y323374D01*
X445309Y323040D01*
X445559Y322624D01*
Y320207D01*
G01Y322624D02*
X445809Y323040D01*
X446226Y323374D01*
X446809Y323540D01*
X447392Y323374D01*
X447809Y323040D01*
X448059Y322540D01*
Y320207D01*
G01X452659D02*
Y323540D01*
G01Y322957D02*
X452326Y323290D01*
X451826Y323457D01*
X451242Y323540D01*
X450659Y323374D01*
X450159Y323040D01*
X449826Y322540D01*
X449659Y321874D01*
X449826Y321207D01*
X450159Y320707D01*
X450659Y320374D01*
X451242Y320207D01*
X451826Y320290D01*
X452326Y320540D01*
X452659Y320874D01*
G01X455509Y320790D02*
X455926Y320457D01*
X456509Y320207D01*
X457009D01*
X457509Y320374D01*
X457842Y320624D01*
X458009Y320957D01*
X457926Y321457D01*
X457592Y321707D01*
X456092Y322207D01*
X455759Y322790D01*
X455926Y323207D01*
X456259Y323457D01*
X456759Y323540D01*
X457259Y323457D01*
X457759Y323207D01*
G01X460942Y320207D02*
Y325207D01*
G01X463609Y323540D02*
X460942Y321624D01*
G01X462026Y322374D02*
X463776Y320207D01*
G01X472059Y318540D02*
Y323540D01*
G01Y322790D02*
X472476Y323207D01*
X472892Y323457D01*
X473559Y323540D01*
X474142Y323457D01*
X474726Y323040D01*
X474976Y322457D01*
X475059Y321874D01*
X474976Y321290D01*
X474726Y320707D01*
X474226Y320374D01*
X473559Y320207D01*
X472976Y320290D01*
X472392Y320540D01*
X472059Y320874D01*
G01X480659Y320207D02*
Y323540D01*
G01Y322957D02*
X480326Y323290D01*
X479826Y323457D01*
X479242Y323540D01*
X478659Y323374D01*
X478159Y323040D01*
X477826Y322540D01*
X477659Y321874D01*
X477826Y321207D01*
X478159Y320707D01*
X478659Y320374D01*
X479242Y320207D01*
X479826Y320290D01*
X480326Y320540D01*
X480659Y320874D01*
G01X486259Y325207D02*
Y320207D01*
G01Y320957D02*
X485926Y320540D01*
X485426Y320290D01*
X484842Y320207D01*
X484176Y320374D01*
X483676Y320790D01*
X483342Y321290D01*
X483259Y321874D01*
X483342Y322457D01*
X483676Y322957D01*
X484176Y323374D01*
X484842Y323540D01*
X485426Y323457D01*
X485842Y323290D01*
X486259Y322957D01*
G01X326092Y302207D02*
Y305540D01*
G01Y304874D02*
X326509Y305207D01*
X326926Y305457D01*
X327509Y305540D01*
X327926Y305457D01*
X328426Y305207D01*
G01X332859Y305540D02*
Y302207D01*
G01Y306874D02*
X332692Y306957D01*
Y307124D01*
X332859Y307207D01*
X333026Y307124D01*
Y306957D01*
X332859Y306874D01*
G01X337042Y302207D02*
Y305540D01*
G01Y304707D02*
X337376Y305124D01*
X337876Y305457D01*
X338542Y305540D01*
X339126Y305457D01*
X339626Y305124D01*
X339876Y304540D01*
Y302207D01*
G01X342892Y300957D02*
X343476Y300624D01*
X344142Y300540D01*
X344726Y300624D01*
X345226Y301040D01*
X345559Y301624D01*
Y305540D01*
G01Y304874D02*
X345226Y305207D01*
X344726Y305457D01*
X344142Y305540D01*
X343476Y305374D01*
X343059Y305040D01*
X342726Y304457D01*
X342559Y303874D01*
X342642Y303374D01*
X342976Y302790D01*
X343476Y302374D01*
X344142Y302207D01*
X344642Y302290D01*
X345226Y302624D01*
X345559Y302957D01*
G01X354009Y302790D02*
X354426Y302457D01*
X355009Y302207D01*
X355509D01*
X356009Y302374D01*
X356342Y302624D01*
X356509Y302957D01*
X356426Y303457D01*
X356092Y303707D01*
X354592Y304207D01*
X354259Y304790D01*
X354426Y305207D01*
X354759Y305457D01*
X355259Y305540D01*
X355759Y305457D01*
X356259Y305207D01*
G01X360859Y305540D02*
Y302207D01*
G01Y306874D02*
X360692Y306957D01*
Y307124D01*
X360859Y307207D01*
X361026Y307124D01*
Y306957D01*
X360859Y306874D01*
G01X365209Y305540D02*
X367709D01*
X365209Y302207D01*
X367709D01*
G01X370809Y304457D02*
X373476D01*
X373226Y305040D01*
X372809Y305374D01*
X372226Y305540D01*
X371642Y305457D01*
X371142Y305207D01*
X370809Y304624D01*
X370642Y304124D01*
Y303624D01*
X370809Y303124D01*
X371226Y302624D01*
X371726Y302290D01*
X372309Y302207D01*
X372892Y302374D01*
X373476Y302874D01*
G01X383092Y301290D02*
X383426Y302374D01*
G01X372759Y342707D02*
X374426D01*
Y341207D01*
X373926Y340707D01*
X373342Y340374D01*
X372509Y340207D01*
X371676Y340374D01*
X371092Y340707D01*
X370592Y341207D01*
X370259Y341790D01*
X370092Y342457D01*
Y343040D01*
X370259Y343540D01*
X370592Y344124D01*
X371092Y344624D01*
X371592Y344957D01*
X372259Y345207D01*
X372842D01*
X373509Y345040D01*
X374009Y344707D01*
G01X376609Y342457D02*
X379276D01*
X379026Y343040D01*
X378609Y343374D01*
X378026Y343540D01*
X377442Y343457D01*
X376942Y343207D01*
X376609Y342624D01*
X376442Y342124D01*
Y341624D01*
X376609Y341124D01*
X377026Y340624D01*
X377526Y340290D01*
X378109Y340207D01*
X378692Y340374D01*
X379276Y340874D01*
G01X382292Y340207D02*
Y343540D01*
G01Y342874D02*
X382709Y343207D01*
X383126Y343457D01*
X383709Y343540D01*
X384126Y343457D01*
X384626Y343207D01*
G01X387559Y340207D02*
Y345207D01*
G01Y342707D02*
X387976Y343207D01*
X388476Y343457D01*
X388976Y343540D01*
X389726Y343374D01*
X390226Y343040D01*
X390559Y342457D01*
Y341790D01*
X390392Y341124D01*
X390059Y340624D01*
X389476Y340290D01*
X388976Y340207D01*
X388476Y340290D01*
X387976Y340540D01*
X387559Y340957D01*
G01X393409Y342457D02*
X396076D01*
X395826Y343040D01*
X395409Y343374D01*
X394826Y343540D01*
X394242Y343457D01*
X393742Y343207D01*
X393409Y342624D01*
X393242Y342124D01*
Y341624D01*
X393409Y341124D01*
X393826Y340624D01*
X394326Y340290D01*
X394909Y340207D01*
X395492Y340374D01*
X396076Y340874D01*
G01X399092Y340207D02*
Y343540D01*
G01Y342874D02*
X399509Y343207D01*
X399926Y343457D01*
X400509Y343540D01*
X400926Y343457D01*
X401426Y343207D01*
G01X412959Y345207D02*
Y340207D01*
G01Y340957D02*
X412626Y340540D01*
X412126Y340290D01*
X411542Y340207D01*
X410876Y340374D01*
X410376Y340790D01*
X410042Y341290D01*
X409959Y341874D01*
X410042Y342457D01*
X410376Y342957D01*
X410876Y343374D01*
X411542Y343540D01*
X412126Y343457D01*
X412542Y343290D01*
X412959Y342957D01*
G01X415809Y342457D02*
X418476D01*
X418226Y343040D01*
X417809Y343374D01*
X417226Y343540D01*
X416642Y343457D01*
X416142Y343207D01*
X415809Y342624D01*
X415642Y342124D01*
Y341624D01*
X415809Y341124D01*
X416226Y340624D01*
X416726Y340290D01*
X417309Y340207D01*
X417892Y340374D01*
X418476Y340874D01*
G01X421409Y340790D02*
X421826Y340457D01*
X422409Y340207D01*
X422909D01*
X423409Y340374D01*
X423742Y340624D01*
X423909Y340957D01*
X423826Y341457D01*
X423492Y341707D01*
X421992Y342207D01*
X421659Y342790D01*
X421826Y343207D01*
X422159Y343457D01*
X422659Y343540D01*
X423159Y343457D01*
X423659Y343207D01*
G01X428259Y343540D02*
Y340207D01*
G01Y344874D02*
X428092Y344957D01*
Y345124D01*
X428259Y345207D01*
X428426Y345124D01*
Y344957D01*
X428259Y344874D01*
G01X432692Y338957D02*
X433276Y338624D01*
X433942Y338540D01*
X434526Y338624D01*
X435026Y339040D01*
X435359Y339624D01*
Y343540D01*
G01Y342874D02*
X435026Y343207D01*
X434526Y343457D01*
X433942Y343540D01*
X433276Y343374D01*
X432859Y343040D01*
X432526Y342457D01*
X432359Y341874D01*
X432442Y341374D01*
X432776Y340790D01*
X433276Y340374D01*
X433942Y340207D01*
X434442Y340290D01*
X435026Y340624D01*
X435359Y340957D01*
G01X438042Y340207D02*
Y343540D01*
G01Y342707D02*
X438376Y343124D01*
X438876Y343457D01*
X439542Y343540D01*
X440126Y343457D01*
X440626Y343124D01*
X440876Y342540D01*
Y340207D01*
G01X303759Y437707D02*
Y442707D01*
G01Y440207D02*
X304176Y440707D01*
X304676Y440957D01*
X305176Y441040D01*
X305926Y440874D01*
X306426Y440540D01*
X306759Y439957D01*
Y439290D01*
X306592Y438624D01*
X306259Y438124D01*
X305676Y437790D01*
X305176Y437707D01*
X304676Y437790D01*
X304176Y438040D01*
X303759Y438457D01*
G01X310859Y437707D02*
X310359Y437790D01*
X309859Y438124D01*
X309526Y438707D01*
X309359Y439374D01*
X309526Y440040D01*
X309859Y440624D01*
X310359Y440957D01*
X310859Y441040D01*
X311359Y440957D01*
X311859Y440624D01*
X312192Y440040D01*
X312276Y439374D01*
X312192Y438707D01*
X311859Y438124D01*
X311359Y437790D01*
X310859Y437707D01*
G01X317959D02*
Y441040D01*
G01Y440457D02*
X317626Y440790D01*
X317126Y440957D01*
X316542Y441040D01*
X315959Y440874D01*
X315459Y440540D01*
X315126Y440040D01*
X314959Y439374D01*
X315126Y438707D01*
X315459Y438207D01*
X315959Y437874D01*
X316542Y437707D01*
X317126Y437790D01*
X317626Y438040D01*
X317959Y438374D01*
G01X320892Y437707D02*
Y441040D01*
G01Y440374D02*
X321309Y440707D01*
X321726Y440957D01*
X322309Y441040D01*
X322726Y440957D01*
X323226Y440707D01*
G01X329159Y442707D02*
Y437707D01*
G01Y438457D02*
X328826Y438040D01*
X328326Y437790D01*
X327742Y437707D01*
X327076Y437874D01*
X326576Y438290D01*
X326242Y438790D01*
X326159Y439374D01*
X326242Y439957D01*
X326576Y440457D01*
X327076Y440874D01*
X327742Y441040D01*
X328326Y440957D01*
X328742Y440790D01*
X329159Y440457D01*
G01X337842Y485707D02*
Y490707D01*
G01Y488290D02*
X338259Y488707D01*
X338676Y488957D01*
X339342Y489040D01*
X339842Y488957D01*
X340426Y488624D01*
X340676Y488124D01*
Y485707D01*
G01X346359D02*
Y489040D01*
G01Y488457D02*
X346026Y488790D01*
X345526Y488957D01*
X344942Y489040D01*
X344359Y488874D01*
X343859Y488540D01*
X343526Y488040D01*
X343359Y487374D01*
X343526Y486707D01*
X343859Y486207D01*
X344359Y485874D01*
X344942Y485707D01*
X345526Y485790D01*
X346026Y486040D01*
X346359Y486374D01*
G01X350459Y485707D02*
Y490707D01*
G01X355559Y485707D02*
Y489957D01*
X355726Y490374D01*
X356059Y490624D01*
X356559Y490707D01*
X357059Y490540D01*
X357309Y490124D01*
G01X356309Y488707D02*
X354642D01*
G01X365759Y484040D02*
Y489040D01*
G01Y488290D02*
X366176Y488707D01*
X366592Y488957D01*
X367259Y489040D01*
X367842Y488957D01*
X368426Y488540D01*
X368676Y487957D01*
X368759Y487374D01*
X368676Y486790D01*
X368426Y486207D01*
X367926Y485874D01*
X367259Y485707D01*
X366676Y485790D01*
X366092Y486040D01*
X365759Y486374D01*
G01X372859Y485707D02*
Y490707D01*
G01X377042Y489040D02*
Y486707D01*
X377376Y486124D01*
X377876Y485790D01*
X378459Y485707D01*
X379042Y485790D01*
X379542Y486124D01*
X379876Y486707D01*
G01Y485707D02*
Y489040D01*
G01X382892Y484457D02*
X383476Y484124D01*
X384142Y484040D01*
X384726Y484124D01*
X385226Y484540D01*
X385559Y485124D01*
Y489040D01*
G01Y488374D02*
X385226Y488707D01*
X384726Y488957D01*
X384142Y489040D01*
X383476Y488874D01*
X383059Y488540D01*
X382726Y487957D01*
X382559Y487374D01*
X382642Y486874D01*
X382976Y486290D01*
X383476Y485874D01*
X384142Y485707D01*
X384642Y485790D01*
X385226Y486124D01*
X385559Y486457D01*
G01X388492Y484457D02*
X389076Y484124D01*
X389742Y484040D01*
X390326Y484124D01*
X390826Y484540D01*
X391159Y485124D01*
Y489040D01*
G01Y488374D02*
X390826Y488707D01*
X390326Y488957D01*
X389742Y489040D01*
X389076Y488874D01*
X388659Y488540D01*
X388326Y487957D01*
X388159Y487374D01*
X388242Y486874D01*
X388576Y486290D01*
X389076Y485874D01*
X389742Y485707D01*
X390242Y485790D01*
X390826Y486124D01*
X391159Y486457D01*
G01X395259Y489040D02*
Y485707D01*
G01Y490374D02*
X395092Y490457D01*
Y490624D01*
X395259Y490707D01*
X395426Y490624D01*
Y490457D01*
X395259Y490374D01*
G01X399442Y485707D02*
Y489040D01*
G01Y488207D02*
X399776Y488624D01*
X400276Y488957D01*
X400942Y489040D01*
X401526Y488957D01*
X402026Y488624D01*
X402276Y488040D01*
Y485707D01*
G01X405292Y484457D02*
X405876Y484124D01*
X406542Y484040D01*
X407126Y484124D01*
X407626Y484540D01*
X407959Y485124D01*
Y489040D01*
G01Y488374D02*
X407626Y488707D01*
X407126Y488957D01*
X406542Y489040D01*
X405876Y488874D01*
X405459Y488540D01*
X405126Y487957D01*
X404959Y487374D01*
X405042Y486874D01*
X405376Y486290D01*
X405876Y485874D01*
X406542Y485707D01*
X407042Y485790D01*
X407626Y486124D01*
X407959Y486457D01*
G01X423342Y-225710D02*
X423926Y-226126D01*
X424592Y-226293D01*
X425259Y-226126D01*
X425842Y-225626D01*
X426259Y-224876D01*
X426426Y-224126D01*
Y-223210D01*
X426259Y-222460D01*
X425842Y-221793D01*
X425342Y-221460D01*
X424759Y-221293D01*
X424092Y-221460D01*
X423592Y-221793D01*
X423259Y-222293D01*
X423092Y-222960D01*
X423259Y-223543D01*
X423676Y-224126D01*
X424176Y-224460D01*
X424759Y-224543D01*
X425426Y-224376D01*
X425926Y-223960D01*
X426426Y-223210D01*
G01X428776Y-224210D02*
X429359Y-223626D01*
X429859Y-223293D01*
X430526Y-223126D01*
X431109Y-223293D01*
X431526Y-223626D01*
X431859Y-224126D01*
X431942Y-224710D01*
X431859Y-225210D01*
X431526Y-225710D01*
X431026Y-226126D01*
X430442Y-226293D01*
X429776Y-226126D01*
X429192Y-225626D01*
X428859Y-224876D01*
X428776Y-224043D01*
X428942Y-222960D01*
X429192Y-222376D01*
X429609Y-221793D01*
X430192Y-221376D01*
X430776Y-221293D01*
X431359Y-221460D01*
X431776Y-221876D01*
G01X403759Y-181293D02*
Y-176293D01*
X400676Y-179876D01*
X404842D01*
G01X406526Y-180543D02*
X407026Y-180960D01*
X407609Y-181210D01*
X408359Y-181293D01*
X409109Y-181126D01*
X409692Y-180793D01*
X410109Y-180210D01*
X410192Y-179543D01*
X410026Y-178876D01*
X409609Y-178460D01*
X409026Y-178126D01*
X408442Y-178043D01*
X407859Y-178126D01*
X407109Y-178460D01*
X407359Y-176293D01*
X409609D01*
G01X404009Y-64710D02*
X404426Y-65043D01*
X405009Y-65293D01*
X405509D01*
X406009Y-65126D01*
X406342Y-64876D01*
X406509Y-64543D01*
X406426Y-64043D01*
X406092Y-63793D01*
X404592Y-63293D01*
X404259Y-62710D01*
X404426Y-62293D01*
X404759Y-62043D01*
X405259Y-61960D01*
X405759Y-62043D01*
X406259Y-62293D01*
G01X410859Y-60293D02*
Y-65293D01*
G01X409692Y-61960D02*
X412026D01*
G01X415042D02*
Y-64293D01*
X415376Y-64876D01*
X415876Y-65210D01*
X416459Y-65293D01*
X417042Y-65210D01*
X417542Y-64876D01*
X417876Y-64293D01*
G01Y-65293D02*
Y-61960D01*
G01X420559Y-65293D02*
Y-60293D01*
G01Y-62793D02*
X420976Y-62293D01*
X421476Y-62043D01*
X421976Y-61960D01*
X422726Y-62126D01*
X423226Y-62460D01*
X423559Y-63043D01*
Y-63710D01*
X423392Y-64376D01*
X423059Y-64876D01*
X422476Y-65210D01*
X421976Y-65293D01*
X421476Y-65210D01*
X420976Y-64960D01*
X420559Y-64543D01*
G01X433259Y-65293D02*
Y-60293D01*
G01X437609Y-63043D02*
X440276D01*
X440026Y-62460D01*
X439609Y-62126D01*
X439026Y-61960D01*
X438442Y-62043D01*
X437942Y-62293D01*
X437609Y-62876D01*
X437442Y-63376D01*
Y-63876D01*
X437609Y-64376D01*
X438026Y-64876D01*
X438526Y-65210D01*
X439109Y-65293D01*
X439692Y-65126D01*
X440276Y-64626D01*
G01X443042Y-65293D02*
Y-61960D01*
G01Y-62793D02*
X443376Y-62376D01*
X443876Y-62043D01*
X444542Y-61960D01*
X445126Y-62043D01*
X445626Y-62376D01*
X445876Y-62960D01*
Y-65293D01*
G01X448892Y-66543D02*
X449476Y-66876D01*
X450142Y-66960D01*
X450726Y-66876D01*
X451226Y-66460D01*
X451559Y-65876D01*
Y-61960D01*
G01Y-62626D02*
X451226Y-62293D01*
X450726Y-62043D01*
X450142Y-61960D01*
X449476Y-62126D01*
X449059Y-62460D01*
X448726Y-63043D01*
X448559Y-63626D01*
X448642Y-64126D01*
X448976Y-64710D01*
X449476Y-65126D01*
X450142Y-65293D01*
X450642Y-65210D01*
X451226Y-64876D01*
X451559Y-64543D01*
G01X455659Y-60293D02*
Y-65293D01*
G01X454492Y-61960D02*
X456826D01*
G01X459842Y-65293D02*
Y-60293D01*
G01Y-62710D02*
X460259Y-62293D01*
X460676Y-62043D01*
X461342Y-61960D01*
X461842Y-62043D01*
X462426Y-62376D01*
X462676Y-62876D01*
Y-65293D01*
G01X465776Y-64376D02*
X467942D01*
G01Y-62876D02*
X465776D01*
G01X470876Y-63210D02*
X471459Y-62626D01*
X471959Y-62293D01*
X472626Y-62126D01*
X473209Y-62293D01*
X473626Y-62626D01*
X473959Y-63126D01*
X474042Y-63710D01*
X473959Y-64210D01*
X473626Y-64710D01*
X473126Y-65126D01*
X472542Y-65293D01*
X471876Y-65126D01*
X471292Y-64626D01*
X470959Y-63876D01*
X470876Y-63043D01*
X471042Y-61960D01*
X471292Y-61376D01*
X471709Y-60793D01*
X472292Y-60376D01*
X472876Y-60293D01*
X473459Y-60460D01*
X473876Y-60876D01*
G01X477142Y-63626D02*
X479142D01*
G01X478059Y-62543D02*
Y-64710D01*
G01X482159Y-65460D02*
X485159Y-60293D01*
G01X488176Y-63626D02*
X490342D01*
G01X493026Y-64543D02*
X493526Y-64960D01*
X494109Y-65210D01*
X494859Y-65293D01*
X495609Y-65126D01*
X496192Y-64793D01*
X496609Y-64210D01*
X496692Y-63543D01*
X496526Y-62876D01*
X496109Y-62460D01*
X495526Y-62126D01*
X494942Y-62043D01*
X494359Y-62126D01*
X493609Y-62460D01*
X493859Y-60293D01*
X496109D01*
G01X497959Y-65293D02*
Y-61960D01*
G01Y-62876D02*
X498209Y-62460D01*
X498626Y-62126D01*
X499209Y-61960D01*
X499792Y-62126D01*
X500209Y-62460D01*
X500459Y-62876D01*
Y-65293D01*
G01Y-62876D02*
X500709Y-62460D01*
X501126Y-62126D01*
X501709Y-61960D01*
X502292Y-62126D01*
X502709Y-62460D01*
X502959Y-62960D01*
Y-65293D01*
G01X506059Y-61960D02*
Y-65293D01*
G01Y-60626D02*
X505892Y-60543D01*
Y-60376D01*
X506059Y-60293D01*
X506226Y-60376D01*
Y-60543D01*
X506059Y-60626D01*
G01X511659Y-65293D02*
Y-60293D01*
G01X395592Y-34293D02*
Y-39293D01*
X398926D01*
G01X401442D02*
Y-35960D01*
G01Y-36793D02*
X401776Y-36376D01*
X402276Y-36043D01*
X402942Y-35960D01*
X403526Y-36043D01*
X404026Y-36376D01*
X404276Y-36960D01*
Y-39293D01*
G01X397592Y6707D02*
Y1707D01*
X400926D01*
G01X403609Y5040D02*
X406109Y1707D01*
G01Y5040D02*
X403609Y1707D01*
G01X384026Y100280D02*
X387692Y103947D01*
G01X385859Y104614D02*
Y99614D01*
G01X387692Y100280D02*
X384026Y103947D01*
G01X383359Y102114D02*
X388359D01*
G01X391042Y98780D02*
X390209Y99614D01*
X389792Y100447D01*
Y103780D01*
X390209Y104614D01*
X391042Y105447D01*
G01X395226Y101197D02*
X395726Y100780D01*
X396309Y100530D01*
X397059Y100447D01*
X397809Y100614D01*
X398392Y100947D01*
X398809Y101530D01*
X398892Y102197D01*
X398726Y102864D01*
X398309Y103280D01*
X397726Y103614D01*
X397142Y103697D01*
X396559Y103614D01*
X395809Y103280D01*
X396059Y105447D01*
X398309D01*
G01X402659Y100280D02*
X402492Y100364D01*
Y100530D01*
X402659Y100614D01*
X402826Y100530D01*
Y100364D01*
X402659Y100280D01*
G01X408259Y100447D02*
Y105447D01*
X407259Y104447D01*
G01Y100447D02*
X409259D01*
G01X414276Y98780D02*
X415109Y99614D01*
X415526Y100447D01*
Y103780D01*
X415109Y104614D01*
X414276Y105447D01*
G01X388759Y307207D02*
Y302207D01*
G01X387592Y305540D02*
X389926D01*
G01X392942Y302207D02*
Y307207D01*
G01Y304790D02*
X393359Y305207D01*
X393776Y305457D01*
X394442Y305540D01*
X394942Y305457D01*
X395526Y305124D01*
X395776Y304624D01*
Y302207D01*
G01X398709Y304457D02*
X401376D01*
X401126Y305040D01*
X400709Y305374D01*
X400126Y305540D01*
X399542Y305457D01*
X399042Y305207D01*
X398709Y304624D01*
X398542Y304124D01*
Y303624D01*
X398709Y303124D01*
X399126Y302624D01*
X399626Y302290D01*
X400209Y302207D01*
X400792Y302374D01*
X401376Y302874D01*
G01X411159Y302207D02*
X410659Y302290D01*
X410159Y302624D01*
X409826Y303207D01*
X409659Y303874D01*
X409826Y304540D01*
X410159Y305124D01*
X410659Y305457D01*
X411159Y305540D01*
X411659Y305457D01*
X412159Y305124D01*
X412492Y304540D01*
X412576Y303874D01*
X412492Y303207D01*
X412159Y302624D01*
X411659Y302290D01*
X411159Y302207D01*
G01X416759Y307207D02*
Y302207D01*
G01X415592Y305540D02*
X417926D01*
G01X420942Y302207D02*
Y307207D01*
G01Y304790D02*
X421359Y305207D01*
X421776Y305457D01*
X422442Y305540D01*
X422942Y305457D01*
X423526Y305124D01*
X423776Y304624D01*
Y302207D01*
G01X426709Y304457D02*
X429376D01*
X429126Y305040D01*
X428709Y305374D01*
X428126Y305540D01*
X427542Y305457D01*
X427042Y305207D01*
X426709Y304624D01*
X426542Y304124D01*
Y303624D01*
X426709Y303124D01*
X427126Y302624D01*
X427626Y302290D01*
X428209Y302207D01*
X428792Y302374D01*
X429376Y302874D01*
G01X432392Y302207D02*
Y305540D01*
G01Y304874D02*
X432809Y305207D01*
X433226Y305457D01*
X433809Y305540D01*
X434226Y305457D01*
X434726Y305207D01*
G01X443509Y302790D02*
X443926Y302457D01*
X444509Y302207D01*
X445009D01*
X445509Y302374D01*
X445842Y302624D01*
X446009Y302957D01*
X445926Y303457D01*
X445592Y303707D01*
X444092Y304207D01*
X443759Y304790D01*
X443926Y305207D01*
X444259Y305457D01*
X444759Y305540D01*
X445259Y305457D01*
X445759Y305207D01*
G01X450359Y305540D02*
Y302207D01*
G01Y306874D02*
X450192Y306957D01*
Y307124D01*
X450359Y307207D01*
X450526Y307124D01*
Y306957D01*
X450359Y306874D01*
G01X457459Y307207D02*
Y302207D01*
G01Y302957D02*
X457126Y302540D01*
X456626Y302290D01*
X456042Y302207D01*
X455376Y302374D01*
X454876Y302790D01*
X454542Y303290D01*
X454459Y303874D01*
X454542Y304457D01*
X454876Y304957D01*
X455376Y305374D01*
X456042Y305540D01*
X456626Y305457D01*
X457042Y305290D01*
X457459Y304957D01*
G01X460309Y304457D02*
X462976D01*
X462726Y305040D01*
X462309Y305374D01*
X461726Y305540D01*
X461142Y305457D01*
X460642Y305207D01*
X460309Y304624D01*
X460142Y304124D01*
Y303624D01*
X460309Y303124D01*
X460726Y302624D01*
X461226Y302290D01*
X461809Y302207D01*
X462392Y302374D01*
X462976Y302874D01*
G01X470676Y305540D02*
X471676Y302207D01*
X472759Y305540D01*
X473842Y302207D01*
X474842Y305540D01*
G01X478359D02*
Y302207D01*
G01Y306874D02*
X478192Y306957D01*
Y307124D01*
X478359Y307207D01*
X478526Y307124D01*
Y306957D01*
X478359Y306874D01*
G01X483959Y307207D02*
Y302207D01*
G01X482792Y305540D02*
X485126D01*
G01X488142Y302207D02*
Y307207D01*
G01Y304790D02*
X488559Y305207D01*
X488976Y305457D01*
X489642Y305540D01*
X490142Y305457D01*
X490726Y305124D01*
X490976Y304624D01*
Y302207D01*
G01X495159D02*
X494659Y302290D01*
X494159Y302624D01*
X493826Y303207D01*
X493659Y303874D01*
X493826Y304540D01*
X494159Y305124D01*
X494659Y305457D01*
X495159Y305540D01*
X495659Y305457D01*
X496159Y305124D01*
X496492Y304540D01*
X496576Y303874D01*
X496492Y303207D01*
X496159Y302624D01*
X495659Y302290D01*
X495159Y302207D01*
G01X499342Y305540D02*
Y303207D01*
X499676Y302624D01*
X500176Y302290D01*
X500759Y302207D01*
X501342Y302290D01*
X501842Y302624D01*
X502176Y303207D01*
G01Y302207D02*
Y305540D01*
G01X506359Y307207D02*
Y302207D01*
G01X505192Y305540D02*
X507526D01*
G01X423759Y485707D02*
Y489957D01*
X423926Y490374D01*
X424259Y490624D01*
X424759Y490707D01*
X425259Y490540D01*
X425509Y490124D01*
G01X424509Y488707D02*
X422842D01*
G01X428442Y489040D02*
Y486707D01*
X428776Y486124D01*
X429276Y485790D01*
X429859Y485707D01*
X430442Y485790D01*
X430942Y486124D01*
X431276Y486707D01*
G01Y485707D02*
Y489040D01*
G01X435459Y485707D02*
Y490707D01*
G01X441059Y485707D02*
Y490707D01*
G01X450759Y484040D02*
Y489040D01*
G01Y488290D02*
X451176Y488707D01*
X451592Y488957D01*
X452259Y489040D01*
X452842Y488957D01*
X453426Y488540D01*
X453676Y487957D01*
X453759Y487374D01*
X453676Y486790D01*
X453426Y486207D01*
X452926Y485874D01*
X452259Y485707D01*
X451676Y485790D01*
X451092Y486040D01*
X450759Y486374D01*
G01X457859Y485707D02*
Y490707D01*
G01X462042Y489040D02*
Y486707D01*
X462376Y486124D01*
X462876Y485790D01*
X463459Y485707D01*
X464042Y485790D01*
X464542Y486124D01*
X464876Y486707D01*
G01Y485707D02*
Y489040D01*
G01X467892Y484457D02*
X468476Y484124D01*
X469142Y484040D01*
X469726Y484124D01*
X470226Y484540D01*
X470559Y485124D01*
Y489040D01*
G01Y488374D02*
X470226Y488707D01*
X469726Y488957D01*
X469142Y489040D01*
X468476Y488874D01*
X468059Y488540D01*
X467726Y487957D01*
X467559Y487374D01*
X467642Y486874D01*
X467976Y486290D01*
X468476Y485874D01*
X469142Y485707D01*
X469642Y485790D01*
X470226Y486124D01*
X470559Y486457D01*
G01X473492Y484457D02*
X474076Y484124D01*
X474742Y484040D01*
X475326Y484124D01*
X475826Y484540D01*
X476159Y485124D01*
Y489040D01*
G01Y488374D02*
X475826Y488707D01*
X475326Y488957D01*
X474742Y489040D01*
X474076Y488874D01*
X473659Y488540D01*
X473326Y487957D01*
X473159Y487374D01*
X473242Y486874D01*
X473576Y486290D01*
X474076Y485874D01*
X474742Y485707D01*
X475242Y485790D01*
X475826Y486124D01*
X476159Y486457D01*
G01X480259Y489040D02*
Y485707D01*
G01Y490374D02*
X480092Y490457D01*
Y490624D01*
X480259Y490707D01*
X480426Y490624D01*
Y490457D01*
X480259Y490374D01*
G01X484442Y485707D02*
Y489040D01*
G01Y488207D02*
X484776Y488624D01*
X485276Y488957D01*
X485942Y489040D01*
X486526Y488957D01*
X487026Y488624D01*
X487276Y488040D01*
Y485707D01*
G01X490292Y484457D02*
X490876Y484124D01*
X491542Y484040D01*
X492126Y484124D01*
X492626Y484540D01*
X492959Y485124D01*
Y489040D01*
G01Y488374D02*
X492626Y488707D01*
X492126Y488957D01*
X491542Y489040D01*
X490876Y488874D01*
X490459Y488540D01*
X490126Y487957D01*
X489959Y487374D01*
X490042Y486874D01*
X490376Y486290D01*
X490876Y485874D01*
X491542Y485707D01*
X492042Y485790D01*
X492626Y486124D01*
X492959Y486457D01*
G01X452259Y562707D02*
X453926D01*
Y561207D01*
X453426Y560707D01*
X452842Y560374D01*
X452009Y560207D01*
X451176Y560374D01*
X450592Y560707D01*
X450092Y561207D01*
X449759Y561790D01*
X449592Y562457D01*
Y563040D01*
X449759Y563540D01*
X450092Y564124D01*
X450592Y564624D01*
X451092Y564957D01*
X451759Y565207D01*
X452342D01*
X453009Y565040D01*
X453509Y564707D01*
G01X455859Y560040D02*
X458859Y565207D01*
G01X461376Y560207D02*
Y565207D01*
X464542D01*
G01X463376Y562790D02*
X461376D01*
G01X472409Y560874D02*
X473076Y560457D01*
X473826Y560207D01*
X474492D01*
X475159Y560457D01*
X475659Y560874D01*
X475909Y561457D01*
X475742Y562040D01*
X475326Y562540D01*
X474576Y562874D01*
X473576Y563040D01*
X472992Y563374D01*
X472742Y563957D01*
X472909Y564540D01*
X473326Y564957D01*
X473909Y565207D01*
X474492D01*
X475076Y565040D01*
X475576Y564624D01*
G01X479759Y560207D02*
Y565207D01*
G01X485359Y560207D02*
X484859Y560290D01*
X484359Y560624D01*
X484026Y561207D01*
X483859Y561874D01*
X484026Y562540D01*
X484359Y563124D01*
X484859Y563457D01*
X485359Y563540D01*
X485859Y563457D01*
X486359Y563124D01*
X486692Y562540D01*
X486776Y561874D01*
X486692Y561207D01*
X486359Y560624D01*
X485859Y560290D01*
X485359Y560207D01*
G01X490959Y565207D02*
Y560207D01*
G01X489792Y563540D02*
X492126D01*
G01X450509Y577457D02*
X453176D01*
X452926Y578040D01*
X452509Y578374D01*
X451926Y578540D01*
X451342Y578457D01*
X450842Y578207D01*
X450509Y577624D01*
X450342Y577124D01*
Y576624D01*
X450509Y576124D01*
X450926Y575624D01*
X451426Y575290D01*
X452009Y575207D01*
X452592Y575374D01*
X453176Y575874D01*
G01X458859Y580207D02*
Y575207D01*
G01Y575957D02*
X458526Y575540D01*
X458026Y575290D01*
X457442Y575207D01*
X456776Y575374D01*
X456276Y575790D01*
X455942Y576290D01*
X455859Y576874D01*
X455942Y577457D01*
X456276Y577957D01*
X456776Y578374D01*
X457442Y578540D01*
X458026Y578457D01*
X458442Y578290D01*
X458859Y577957D01*
G01X461792Y573957D02*
X462376Y573624D01*
X463042Y573540D01*
X463626Y573624D01*
X464126Y574040D01*
X464459Y574624D01*
Y578540D01*
G01Y577874D02*
X464126Y578207D01*
X463626Y578457D01*
X463042Y578540D01*
X462376Y578374D01*
X461959Y578040D01*
X461626Y577457D01*
X461459Y576874D01*
X461542Y576374D01*
X461876Y575790D01*
X462376Y575374D01*
X463042Y575207D01*
X463542Y575290D01*
X464126Y575624D01*
X464459Y575957D01*
G01X467309Y577457D02*
X469976D01*
X469726Y578040D01*
X469309Y578374D01*
X468726Y578540D01*
X468142Y578457D01*
X467642Y578207D01*
X467309Y577624D01*
X467142Y577124D01*
Y576624D01*
X467309Y576124D01*
X467726Y575624D01*
X468226Y575290D01*
X468809Y575207D01*
X469392Y575374D01*
X469976Y575874D01*
G01X479759Y580207D02*
Y575207D01*
G01X478592Y578540D02*
X480926D01*
G01X485359Y575207D02*
X484859Y575290D01*
X484359Y575624D01*
X484026Y576207D01*
X483859Y576874D01*
X484026Y577540D01*
X484359Y578124D01*
X484859Y578457D01*
X485359Y578540D01*
X485859Y578457D01*
X486359Y578124D01*
X486692Y577540D01*
X486776Y576874D01*
X486692Y576207D01*
X486359Y575624D01*
X485859Y575290D01*
X485359Y575207D01*
G01X495142D02*
Y580207D01*
G01Y577790D02*
X495559Y578207D01*
X495976Y578457D01*
X496642Y578540D01*
X497142Y578457D01*
X497726Y578124D01*
X497976Y577624D01*
Y575207D01*
G01X502159D02*
X501659Y575290D01*
X501159Y575624D01*
X500826Y576207D01*
X500659Y576874D01*
X500826Y577540D01*
X501159Y578124D01*
X501659Y578457D01*
X502159Y578540D01*
X502659Y578457D01*
X503159Y578124D01*
X503492Y577540D01*
X503576Y576874D01*
X503492Y576207D01*
X503159Y575624D01*
X502659Y575290D01*
X502159Y575207D01*
G01X507759D02*
Y580207D01*
G01X512109Y577457D02*
X514776D01*
X514526Y578040D01*
X514109Y578374D01*
X513526Y578540D01*
X512942Y578457D01*
X512442Y578207D01*
X512109Y577624D01*
X511942Y577124D01*
Y576624D01*
X512109Y576124D01*
X512526Y575624D01*
X513026Y575290D01*
X513609Y575207D01*
X514192Y575374D01*
X514776Y575874D01*
G01X450509Y593957D02*
X453176D01*
X452926Y594540D01*
X452509Y594874D01*
X451926Y595040D01*
X451342Y594957D01*
X450842Y594707D01*
X450509Y594124D01*
X450342Y593624D01*
Y593124D01*
X450509Y592624D01*
X450926Y592124D01*
X451426Y591790D01*
X452009Y591707D01*
X452592Y591874D01*
X453176Y592374D01*
G01X458859Y596707D02*
Y591707D01*
G01Y592457D02*
X458526Y592040D01*
X458026Y591790D01*
X457442Y591707D01*
X456776Y591874D01*
X456276Y592290D01*
X455942Y592790D01*
X455859Y593374D01*
X455942Y593957D01*
X456276Y594457D01*
X456776Y594874D01*
X457442Y595040D01*
X458026Y594957D01*
X458442Y594790D01*
X458859Y594457D01*
G01X461792Y590457D02*
X462376Y590124D01*
X463042Y590040D01*
X463626Y590124D01*
X464126Y590540D01*
X464459Y591124D01*
Y595040D01*
G01Y594374D02*
X464126Y594707D01*
X463626Y594957D01*
X463042Y595040D01*
X462376Y594874D01*
X461959Y594540D01*
X461626Y593957D01*
X461459Y593374D01*
X461542Y592874D01*
X461876Y592290D01*
X462376Y591874D01*
X463042Y591707D01*
X463542Y591790D01*
X464126Y592124D01*
X464459Y592457D01*
G01X467309Y593957D02*
X469976D01*
X469726Y594540D01*
X469309Y594874D01*
X468726Y595040D01*
X468142Y594957D01*
X467642Y594707D01*
X467309Y594124D01*
X467142Y593624D01*
Y593124D01*
X467309Y592624D01*
X467726Y592124D01*
X468226Y591790D01*
X468809Y591707D01*
X469392Y591874D01*
X469976Y592374D01*
G01X479759Y596707D02*
Y591707D01*
G01X478592Y595040D02*
X480926D01*
G01X485359Y591707D02*
X484859Y591790D01*
X484359Y592124D01*
X484026Y592707D01*
X483859Y593374D01*
X484026Y594040D01*
X484359Y594624D01*
X484859Y594957D01*
X485359Y595040D01*
X485859Y594957D01*
X486359Y594624D01*
X486692Y594040D01*
X486776Y593374D01*
X486692Y592707D01*
X486359Y592124D01*
X485859Y591790D01*
X485359Y591707D01*
G01X495309Y593957D02*
X497976D01*
X497726Y594540D01*
X497309Y594874D01*
X496726Y595040D01*
X496142Y594957D01*
X495642Y594707D01*
X495309Y594124D01*
X495142Y593624D01*
Y593124D01*
X495309Y592624D01*
X495726Y592124D01*
X496226Y591790D01*
X496809Y591707D01*
X497392Y591874D01*
X497976Y592374D01*
G01X503659Y596707D02*
Y591707D01*
G01Y592457D02*
X503326Y592040D01*
X502826Y591790D01*
X502242Y591707D01*
X501576Y591874D01*
X501076Y592290D01*
X500742Y592790D01*
X500659Y593374D01*
X500742Y593957D01*
X501076Y594457D01*
X501576Y594874D01*
X502242Y595040D01*
X502826Y594957D01*
X503242Y594790D01*
X503659Y594457D01*
G01X506592Y590457D02*
X507176Y590124D01*
X507842Y590040D01*
X508426Y590124D01*
X508926Y590540D01*
X509259Y591124D01*
Y595040D01*
G01Y594374D02*
X508926Y594707D01*
X508426Y594957D01*
X507842Y595040D01*
X507176Y594874D01*
X506759Y594540D01*
X506426Y593957D01*
X506259Y593374D01*
X506342Y592874D01*
X506676Y592290D01*
X507176Y591874D01*
X507842Y591707D01*
X508342Y591790D01*
X508926Y592124D01*
X509259Y592457D01*
G01X512109Y593957D02*
X514776D01*
X514526Y594540D01*
X514109Y594874D01*
X513526Y595040D01*
X512942Y594957D01*
X512442Y594707D01*
X512109Y594124D01*
X511942Y593624D01*
Y593124D01*
X512109Y592624D01*
X512526Y592124D01*
X513026Y591790D01*
X513609Y591707D01*
X514192Y591874D01*
X514776Y592374D01*
G01X450759Y547187D02*
Y542187D01*
G01X448842Y547187D02*
X452676D01*
G01X454276Y545520D02*
X455276Y542187D01*
X456359Y545520D01*
X457442Y542187D01*
X458442Y545520D01*
G01X461959D02*
Y542187D01*
G01Y546854D02*
X461792Y546937D01*
Y547104D01*
X461959Y547187D01*
X462126Y547104D01*
Y546937D01*
X461959Y546854D01*
G01X466309Y542770D02*
X466726Y542437D01*
X467309Y542187D01*
X467809D01*
X468309Y542354D01*
X468642Y542604D01*
X468809Y542937D01*
X468726Y543437D01*
X468392Y543687D01*
X466892Y544187D01*
X466559Y544770D01*
X466726Y545187D01*
X467059Y545437D01*
X467559Y545520D01*
X468059Y545437D01*
X468559Y545187D01*
G01X473159Y547187D02*
Y542187D01*
G01X471992Y545520D02*
X474326D01*
G01X485859Y542187D02*
Y545520D01*
G01Y544937D02*
X485526Y545270D01*
X485026Y545437D01*
X484442Y545520D01*
X483859Y545354D01*
X483359Y545020D01*
X483026Y544520D01*
X482859Y543854D01*
X483026Y543187D01*
X483359Y542687D01*
X483859Y542354D01*
X484442Y542187D01*
X485026Y542270D01*
X485526Y542520D01*
X485859Y542854D01*
G01X488542Y542187D02*
Y545520D01*
G01Y544687D02*
X488876Y545104D01*
X489376Y545437D01*
X490042Y545520D01*
X490626Y545437D01*
X491126Y545104D01*
X491376Y544520D01*
Y542187D01*
G01X497059Y547187D02*
Y542187D01*
G01Y542937D02*
X496726Y542520D01*
X496226Y542270D01*
X495642Y542187D01*
X494976Y542354D01*
X494476Y542770D01*
X494142Y543270D01*
X494059Y543854D01*
X494142Y544437D01*
X494476Y544937D01*
X494976Y545354D01*
X495642Y545520D01*
X496226Y545437D01*
X496642Y545270D01*
X497059Y544937D01*
G01X505259Y542187D02*
Y547187D01*
G01Y544687D02*
X505676Y545187D01*
X506176Y545437D01*
X506676Y545520D01*
X507426Y545354D01*
X507926Y545020D01*
X508259Y544437D01*
Y543770D01*
X508092Y543104D01*
X507759Y542604D01*
X507176Y542270D01*
X506676Y542187D01*
X506176Y542270D01*
X505676Y542520D01*
X505259Y542937D01*
G01X512359Y542187D02*
X511859Y542270D01*
X511359Y542604D01*
X511026Y543187D01*
X510859Y543854D01*
X511026Y544520D01*
X511359Y545104D01*
X511859Y545437D01*
X512359Y545520D01*
X512859Y545437D01*
X513359Y545104D01*
X513692Y544520D01*
X513776Y543854D01*
X513692Y543187D01*
X513359Y542604D01*
X512859Y542270D01*
X512359Y542187D01*
G01X515876Y545520D02*
X516876Y542187D01*
X517959Y545520D01*
X519042Y542187D01*
X520042Y545520D01*
G01X442759Y601817D02*
Y533317D01*
G01X443259Y570707D02*
X837759D01*
G01X443259Y585707D02*
X837759D01*
G01X490426Y-243293D02*
Y-238293D01*
X492092D01*
X492759Y-238543D01*
X493259Y-238876D01*
X493676Y-239376D01*
X494009Y-239960D01*
X494092Y-240793D01*
X494009Y-241626D01*
X493676Y-242210D01*
X493259Y-242710D01*
X492759Y-243043D01*
X492092Y-243293D01*
X490426D01*
G01X497859D02*
Y-238293D01*
X496859Y-239293D01*
G01Y-243293D02*
X498859D01*
G01X501876Y-241210D02*
X502459Y-240626D01*
X502959Y-240293D01*
X503626Y-240126D01*
X504209Y-240293D01*
X504626Y-240626D01*
X504959Y-241126D01*
X505042Y-241710D01*
X504959Y-242210D01*
X504626Y-242710D01*
X504126Y-243126D01*
X503542Y-243293D01*
X502876Y-243126D01*
X502292Y-242626D01*
X501959Y-241876D01*
X501876Y-241043D01*
X502042Y-239960D01*
X502292Y-239376D01*
X502709Y-238793D01*
X503292Y-238376D01*
X503876Y-238293D01*
X504459Y-238460D01*
X504876Y-238876D01*
G01X509059Y-243460D02*
X508892Y-243376D01*
Y-243210D01*
X509059Y-243126D01*
X509226Y-243210D01*
Y-243376D01*
X509059Y-243460D01*
G01Y-241210D02*
X508892Y-241126D01*
Y-240960D01*
X509059Y-240876D01*
X509226Y-240960D01*
Y-241126D01*
X509059Y-241210D01*
G01X512826Y-243293D02*
Y-238293D01*
X514492D01*
X515159Y-238543D01*
X515659Y-238876D01*
X516076Y-239376D01*
X516409Y-239960D01*
X516492Y-240793D01*
X516409Y-241626D01*
X516076Y-242210D01*
X515659Y-242710D01*
X515159Y-243043D01*
X514492Y-243293D01*
X512826D01*
G01X520259Y-239960D02*
Y-243293D01*
G01Y-238626D02*
X520092Y-238543D01*
Y-238376D01*
X520259Y-238293D01*
X520426Y-238376D01*
Y-238543D01*
X520259Y-238626D01*
G01X527359Y-243293D02*
Y-239960D01*
G01Y-240543D02*
X527026Y-240210D01*
X526526Y-240043D01*
X525942Y-239960D01*
X525359Y-240126D01*
X524859Y-240460D01*
X524526Y-240960D01*
X524359Y-241626D01*
X524526Y-242293D01*
X524859Y-242793D01*
X525359Y-243126D01*
X525942Y-243293D01*
X526526Y-243210D01*
X527026Y-242960D01*
X527359Y-242626D01*
G01X528959Y-243293D02*
Y-239960D01*
G01Y-240876D02*
X529209Y-240460D01*
X529626Y-240126D01*
X530209Y-239960D01*
X530792Y-240126D01*
X531209Y-240460D01*
X531459Y-240876D01*
Y-243293D01*
G01Y-240876D02*
X531709Y-240460D01*
X532126Y-240126D01*
X532709Y-239960D01*
X533292Y-240126D01*
X533709Y-240460D01*
X533959Y-240960D01*
Y-243293D01*
G01X535809Y-241043D02*
X538476D01*
X538226Y-240460D01*
X537809Y-240126D01*
X537226Y-239960D01*
X536642Y-240043D01*
X536142Y-240293D01*
X535809Y-240876D01*
X535642Y-241376D01*
Y-241876D01*
X535809Y-242376D01*
X536226Y-242876D01*
X536726Y-243210D01*
X537309Y-243293D01*
X537892Y-243126D01*
X538476Y-242626D01*
G01X542659Y-238293D02*
Y-243293D01*
G01X541492Y-239960D02*
X543826D01*
G01X547009Y-241043D02*
X549676D01*
X549426Y-240460D01*
X549009Y-240126D01*
X548426Y-239960D01*
X547842Y-240043D01*
X547342Y-240293D01*
X547009Y-240876D01*
X546842Y-241376D01*
Y-241876D01*
X547009Y-242376D01*
X547426Y-242876D01*
X547926Y-243210D01*
X548509Y-243293D01*
X549092Y-243126D01*
X549676Y-242626D01*
G01X552692Y-243293D02*
Y-239960D01*
G01Y-240626D02*
X553109Y-240293D01*
X553526Y-240043D01*
X554109Y-239960D01*
X554526Y-240043D01*
X555026Y-240293D01*
G01X565059Y-243293D02*
Y-238293D01*
X564059Y-239293D01*
G01Y-243293D02*
X566059D01*
G01X569076Y-241210D02*
X569659Y-240626D01*
X570159Y-240293D01*
X570826Y-240126D01*
X571409Y-240293D01*
X571826Y-240626D01*
X572159Y-241126D01*
X572242Y-241710D01*
X572159Y-242210D01*
X571826Y-242710D01*
X571326Y-243126D01*
X570742Y-243293D01*
X570076Y-243126D01*
X569492Y-242626D01*
X569159Y-241876D01*
X569076Y-241043D01*
X569242Y-239960D01*
X569492Y-239376D01*
X569909Y-238793D01*
X570492Y-238376D01*
X571076Y-238293D01*
X571659Y-238460D01*
X572076Y-238876D01*
G01X573759Y-243293D02*
Y-239960D01*
G01Y-240876D02*
X574009Y-240460D01*
X574426Y-240126D01*
X575009Y-239960D01*
X575592Y-240126D01*
X576009Y-240460D01*
X576259Y-240876D01*
Y-243293D01*
G01Y-240876D02*
X576509Y-240460D01*
X576926Y-240126D01*
X577509Y-239960D01*
X578092Y-240126D01*
X578509Y-240460D01*
X578759Y-240960D01*
Y-243293D01*
G01X581859Y-239960D02*
Y-243293D01*
G01Y-238626D02*
X581692Y-238543D01*
Y-238376D01*
X581859Y-238293D01*
X582026Y-238376D01*
Y-238543D01*
X581859Y-238626D01*
G01X587459Y-243293D02*
Y-238293D01*
G01X475426Y-232293D02*
X472092D01*
Y-227293D01*
X475426D01*
G01X474092Y-229710D02*
X472092D01*
G01X478109Y-228960D02*
X480609Y-232293D01*
G01Y-228960D02*
X478109Y-232293D01*
G01X484959Y-232460D02*
X484792Y-232376D01*
Y-232210D01*
X484959Y-232126D01*
X485126Y-232210D01*
Y-232376D01*
X484959Y-232460D01*
G01X488809Y-232293D02*
Y-227293D01*
G01X492309D02*
Y-232293D01*
G01Y-229793D02*
X488809D01*
G01X494492Y-232293D02*
Y-227293D01*
X496576D01*
X497242Y-227543D01*
X497659Y-227876D01*
X497826Y-228543D01*
X497659Y-229210D01*
X497159Y-229626D01*
X496576Y-229876D01*
X494492D01*
G01X496576D02*
X497826Y-232293D01*
G01X503426D02*
X500092D01*
Y-227293D01*
X503426D01*
G01X502092Y-229710D02*
X500092D01*
G01X508359Y-232293D02*
Y-227293D01*
X505276Y-230876D01*
X509442D01*
G01X511126Y-231543D02*
X511626Y-231960D01*
X512209Y-232210D01*
X512959Y-232293D01*
X513709Y-232126D01*
X514292Y-231793D01*
X514709Y-231210D01*
X514792Y-230543D01*
X514626Y-229876D01*
X514209Y-229460D01*
X513626Y-229126D01*
X513042Y-229043D01*
X512459Y-229126D01*
X511709Y-229460D01*
X511959Y-227293D01*
X514209D01*
G01X516809Y-232293D02*
X520309Y-227293D01*
G01X516809D02*
X520309Y-232293D01*
G01X522742Y-231710D02*
X523326Y-232126D01*
X523992Y-232293D01*
X524659Y-232126D01*
X525242Y-231626D01*
X525659Y-230876D01*
X525826Y-230126D01*
Y-229210D01*
X525659Y-228460D01*
X525242Y-227793D01*
X524742Y-227460D01*
X524159Y-227293D01*
X523492Y-227460D01*
X522992Y-227793D01*
X522659Y-228293D01*
X522492Y-228960D01*
X522659Y-229543D01*
X523076Y-230126D01*
X523576Y-230460D01*
X524159Y-230543D01*
X524826Y-230376D01*
X525326Y-229960D01*
X525826Y-229210D01*
G01X528176Y-230210D02*
X528759Y-229626D01*
X529259Y-229293D01*
X529926Y-229126D01*
X530509Y-229293D01*
X530926Y-229626D01*
X531259Y-230126D01*
X531342Y-230710D01*
X531259Y-231210D01*
X530926Y-231710D01*
X530426Y-232126D01*
X529842Y-232293D01*
X529176Y-232126D01*
X528592Y-231626D01*
X528259Y-230876D01*
X528176Y-230043D01*
X528342Y-228960D01*
X528592Y-228376D01*
X529009Y-227793D01*
X529592Y-227376D01*
X530176Y-227293D01*
X530759Y-227460D01*
X531176Y-227876D01*
G01X534942Y-233960D02*
X534109Y-233126D01*
X533692Y-232293D01*
Y-228960D01*
X534109Y-228126D01*
X534942Y-227293D01*
G01X539126Y-232293D02*
Y-227293D01*
X540792D01*
X541459Y-227543D01*
X541959Y-227876D01*
X542376Y-228376D01*
X542709Y-228960D01*
X542792Y-229793D01*
X542709Y-230626D01*
X542376Y-231210D01*
X541959Y-231710D01*
X541459Y-232043D01*
X540792Y-232293D01*
X539126D01*
G01X546559D02*
Y-227293D01*
X545559Y-228293D01*
G01Y-232293D02*
X547559D01*
G01X550576Y-230210D02*
X551159Y-229626D01*
X551659Y-229293D01*
X552326Y-229126D01*
X552909Y-229293D01*
X553326Y-229626D01*
X553659Y-230126D01*
X553742Y-230710D01*
X553659Y-231210D01*
X553326Y-231710D01*
X552826Y-232126D01*
X552242Y-232293D01*
X551576Y-232126D01*
X550992Y-231626D01*
X550659Y-230876D01*
X550576Y-230043D01*
X550742Y-228960D01*
X550992Y-228376D01*
X551409Y-227793D01*
X551992Y-227376D01*
X552576Y-227293D01*
X553159Y-227460D01*
X553576Y-227876D01*
G01X556009Y-232293D02*
X559509Y-227293D01*
G01X556009D02*
X559509Y-232293D01*
G01X564359D02*
Y-227293D01*
X561276Y-230876D01*
X565442D01*
G01X569376Y-233960D02*
X570209Y-233126D01*
X570626Y-232293D01*
Y-228960D01*
X570209Y-228126D01*
X569376Y-227293D01*
G01X472092Y-183293D02*
Y-178293D01*
X474176D01*
X474842Y-178543D01*
X475259Y-178876D01*
X475426Y-179543D01*
X475259Y-180210D01*
X474759Y-180626D01*
X474176Y-180876D01*
X472092D01*
G01X474176D02*
X475426Y-183293D01*
G01X481026D02*
X477692D01*
Y-178293D01*
X481026D01*
G01X479692Y-180710D02*
X477692D01*
G01X486792Y-178710D02*
X486292Y-178460D01*
X485709Y-178293D01*
X485042D01*
X484292Y-178543D01*
X483709Y-178960D01*
X483292Y-179460D01*
X482959Y-180293D01*
X482876Y-181043D01*
X483042Y-181793D01*
X483292Y-182293D01*
X483792Y-182793D01*
X484376Y-183126D01*
X484959Y-183293D01*
X485542D01*
X486126Y-183126D01*
X486626Y-182876D01*
X487042Y-182543D01*
G01X490559Y-178293D02*
Y-183293D01*
G01X488642Y-178293D02*
X492476D01*
G01X494076Y-183293D02*
X496159Y-178293D01*
X498242Y-183293D01*
G01X497492Y-181543D02*
X494826D01*
G01X499842Y-183293D02*
Y-178293D01*
X503676Y-183293D01*
Y-178293D01*
G01X507859Y-180793D02*
X509526D01*
Y-182293D01*
X509026Y-182793D01*
X508442Y-183126D01*
X507609Y-183293D01*
X506776Y-183126D01*
X506192Y-182793D01*
X505692Y-182293D01*
X505359Y-181710D01*
X505192Y-181043D01*
Y-180460D01*
X505359Y-179960D01*
X505692Y-179376D01*
X506192Y-178876D01*
X506692Y-178543D01*
X507359Y-178293D01*
X507942D01*
X508609Y-178460D01*
X509109Y-178793D01*
G01X511292Y-178293D02*
Y-183293D01*
X514626D01*
G01X520226D02*
X516892D01*
Y-178293D01*
X520226D01*
G01X518892Y-180710D02*
X516892D01*
G01X527926Y-183293D02*
Y-178293D01*
X529592D01*
X530259Y-178543D01*
X530759Y-178876D01*
X531176Y-179376D01*
X531509Y-179960D01*
X531592Y-180793D01*
X531509Y-181626D01*
X531176Y-182210D01*
X530759Y-182710D01*
X530259Y-183043D01*
X529592Y-183293D01*
X527926D01*
G01X533692D02*
Y-178293D01*
X535776D01*
X536442Y-178543D01*
X536859Y-178876D01*
X537026Y-179543D01*
X536859Y-180210D01*
X536359Y-180626D01*
X535776Y-180876D01*
X533692D01*
G01X535776D02*
X537026Y-183293D01*
G01X539959Y-178293D02*
X541959D01*
G01X540959D02*
Y-183293D01*
G01X539959D02*
X541959D01*
G01X544892Y-178293D02*
Y-183293D01*
X548226D01*
G01X550492Y-178293D02*
Y-183293D01*
X553826D01*
G01X561609D02*
Y-178293D01*
G01X565109D02*
Y-183293D01*
G01Y-180793D02*
X561609D01*
G01X568959Y-183293D02*
X568292Y-183210D01*
X567709Y-182876D01*
X567209Y-182376D01*
X566876Y-181793D01*
X566709Y-181126D01*
Y-180460D01*
X566876Y-179793D01*
X567209Y-179210D01*
X567709Y-178710D01*
X568292Y-178376D01*
X568959Y-178293D01*
X569626Y-178376D01*
X570209Y-178710D01*
X570709Y-179210D01*
X571042Y-179793D01*
X571209Y-180460D01*
Y-181126D01*
X571042Y-181793D01*
X570709Y-182376D01*
X570209Y-182876D01*
X569626Y-183210D01*
X568959Y-183293D01*
G01X572892Y-178293D02*
Y-183293D01*
X576226D01*
G01X581826D02*
X578492D01*
Y-178293D01*
X581826D01*
G01X580492Y-180710D02*
X578492D01*
G01X589526Y-183293D02*
Y-178293D01*
X591192D01*
X591859Y-178543D01*
X592359Y-178876D01*
X592776Y-179376D01*
X593109Y-179960D01*
X593192Y-180793D01*
X593109Y-181626D01*
X592776Y-182210D01*
X592359Y-182710D01*
X591859Y-183043D01*
X591192Y-183293D01*
X589526D01*
G01X598626D02*
X595292D01*
Y-178293D01*
X598626D01*
G01X597292Y-180710D02*
X595292D01*
G01X600976Y-183293D02*
Y-178293D01*
X604142D01*
G01X602976Y-180710D02*
X600976D01*
G01X607159Y-178293D02*
X609159D01*
G01X608159D02*
Y-183293D01*
G01X607159D02*
X609159D01*
G01X611842D02*
Y-178293D01*
X615676Y-183293D01*
Y-178293D01*
G01X621026Y-183293D02*
X617692D01*
Y-178293D01*
X621026D01*
G01X619692Y-180710D02*
X617692D01*
G01X520759Y87207D02*
Y-162793D01*
G01X516176Y134874D02*
X516676Y135374D01*
X517259Y135624D01*
X517926Y135707D01*
X518759Y135540D01*
X519342Y135124D01*
X519509Y134624D01*
X519426Y134124D01*
X519092Y133707D01*
X517426Y132874D01*
X516676Y132290D01*
X516176Y131457D01*
X516009Y130707D01*
X519509D01*
G01X523359Y130540D02*
X523192Y130624D01*
Y130790D01*
X523359Y130874D01*
X523526Y130790D01*
Y130624D01*
X523359Y130540D01*
G01X526876Y135707D02*
X528959Y130707D01*
X531042Y135707D01*
G01X534559Y134040D02*
Y130707D01*
G01Y135374D02*
X534392Y135457D01*
Y135624D01*
X534559Y135707D01*
X534726Y135624D01*
Y135457D01*
X534559Y135374D01*
G01X541659Y130707D02*
Y134040D01*
G01Y133457D02*
X541326Y133790D01*
X540826Y133957D01*
X540242Y134040D01*
X539659Y133874D01*
X539159Y133540D01*
X538826Y133040D01*
X538659Y132374D01*
X538826Y131707D01*
X539159Y131207D01*
X539659Y130874D01*
X540242Y130707D01*
X540826Y130790D01*
X541326Y131040D01*
X541659Y131374D01*
G01X550109Y131290D02*
X550526Y130957D01*
X551109Y130707D01*
X551609D01*
X552109Y130874D01*
X552442Y131124D01*
X552609Y131457D01*
X552526Y131957D01*
X552192Y132207D01*
X550692Y132707D01*
X550359Y133290D01*
X550526Y133707D01*
X550859Y133957D01*
X551359Y134040D01*
X551859Y133957D01*
X552359Y133707D01*
G01X555542Y130707D02*
Y135707D01*
G01Y133290D02*
X555959Y133707D01*
X556376Y133957D01*
X557042Y134040D01*
X557542Y133957D01*
X558126Y133624D01*
X558376Y133124D01*
Y130707D01*
G01X562559D02*
X562059Y130790D01*
X561559Y131124D01*
X561226Y131707D01*
X561059Y132374D01*
X561226Y133040D01*
X561559Y133624D01*
X562059Y133957D01*
X562559Y134040D01*
X563059Y133957D01*
X563559Y133624D01*
X563892Y133040D01*
X563976Y132374D01*
X563892Y131707D01*
X563559Y131124D01*
X563059Y130790D01*
X562559Y130707D01*
G01X566742Y134040D02*
Y131707D01*
X567076Y131124D01*
X567576Y130790D01*
X568159Y130707D01*
X568742Y130790D01*
X569242Y131124D01*
X569576Y131707D01*
G01Y130707D02*
Y134040D01*
G01X573759Y130707D02*
Y135707D01*
G01X580859D02*
Y130707D01*
G01Y131457D02*
X580526Y131040D01*
X580026Y130790D01*
X579442Y130707D01*
X578776Y130874D01*
X578276Y131290D01*
X577942Y131790D01*
X577859Y132374D01*
X577942Y132957D01*
X578276Y133457D01*
X578776Y133874D01*
X579442Y134040D01*
X580026Y133957D01*
X580442Y133790D01*
X580859Y133457D01*
G01X589059Y130707D02*
Y135707D01*
G01Y133207D02*
X589476Y133707D01*
X589976Y133957D01*
X590476Y134040D01*
X591226Y133874D01*
X591726Y133540D01*
X592059Y132957D01*
Y132290D01*
X591892Y131624D01*
X591559Y131124D01*
X590976Y130790D01*
X590476Y130707D01*
X589976Y130790D01*
X589476Y131040D01*
X589059Y131457D01*
G01X594909Y132957D02*
X597576D01*
X597326Y133540D01*
X596909Y133874D01*
X596326Y134040D01*
X595742Y133957D01*
X595242Y133707D01*
X594909Y133124D01*
X594742Y132624D01*
Y132124D01*
X594909Y131624D01*
X595326Y131124D01*
X595826Y130790D01*
X596409Y130707D01*
X596992Y130874D01*
X597576Y131374D01*
G01X605859Y129040D02*
Y134040D01*
G01Y133290D02*
X606276Y133707D01*
X606692Y133957D01*
X607359Y134040D01*
X607942Y133957D01*
X608526Y133540D01*
X608776Y132957D01*
X608859Y132374D01*
X608776Y131790D01*
X608526Y131207D01*
X608026Y130874D01*
X607359Y130707D01*
X606776Y130790D01*
X606192Y131040D01*
X605859Y131374D01*
G01X612959Y130707D02*
Y135707D01*
G01X617142Y134040D02*
Y131707D01*
X617476Y131124D01*
X617976Y130790D01*
X618559Y130707D01*
X619142Y130790D01*
X619642Y131124D01*
X619976Y131707D01*
G01Y130707D02*
Y134040D01*
G01X622992Y129457D02*
X623576Y129124D01*
X624242Y129040D01*
X624826Y129124D01*
X625326Y129540D01*
X625659Y130124D01*
Y134040D01*
G01Y133374D02*
X625326Y133707D01*
X624826Y133957D01*
X624242Y134040D01*
X623576Y133874D01*
X623159Y133540D01*
X622826Y132957D01*
X622659Y132374D01*
X622742Y131874D01*
X623076Y131290D01*
X623576Y130874D01*
X624242Y130707D01*
X624742Y130790D01*
X625326Y131124D01*
X625659Y131457D01*
G01X628592Y129457D02*
X629176Y129124D01*
X629842Y129040D01*
X630426Y129124D01*
X630926Y129540D01*
X631259Y130124D01*
Y134040D01*
G01Y133374D02*
X630926Y133707D01*
X630426Y133957D01*
X629842Y134040D01*
X629176Y133874D01*
X628759Y133540D01*
X628426Y132957D01*
X628259Y132374D01*
X628342Y131874D01*
X628676Y131290D01*
X629176Y130874D01*
X629842Y130707D01*
X630342Y130790D01*
X630926Y131124D01*
X631259Y131457D01*
G01X634109Y132957D02*
X636776D01*
X636526Y133540D01*
X636109Y133874D01*
X635526Y134040D01*
X634942Y133957D01*
X634442Y133707D01*
X634109Y133124D01*
X633942Y132624D01*
Y132124D01*
X634109Y131624D01*
X634526Y131124D01*
X635026Y130790D01*
X635609Y130707D01*
X636192Y130874D01*
X636776Y131374D01*
G01X642459Y135707D02*
Y130707D01*
G01Y131457D02*
X642126Y131040D01*
X641626Y130790D01*
X641042Y130707D01*
X640376Y130874D01*
X639876Y131290D01*
X639542Y131790D01*
X639459Y132374D01*
X639542Y132957D01*
X639876Y133457D01*
X640376Y133874D01*
X641042Y134040D01*
X641626Y133957D01*
X642042Y133790D01*
X642459Y133457D01*
G01X650076Y134040D02*
X651076Y130707D01*
X652159Y134040D01*
X653242Y130707D01*
X654242Y134040D01*
G01X657759D02*
Y130707D01*
G01Y135374D02*
X657592Y135457D01*
Y135624D01*
X657759Y135707D01*
X657926Y135624D01*
Y135457D01*
X657759Y135374D01*
G01X663359Y135707D02*
Y130707D01*
G01X662192Y134040D02*
X664526D01*
G01X667542Y130707D02*
Y135707D01*
G01Y133290D02*
X667959Y133707D01*
X668376Y133957D01*
X669042Y134040D01*
X669542Y133957D01*
X670126Y133624D01*
X670376Y133124D01*
Y130707D01*
G01X678492D02*
X681826Y132374D01*
X678492Y134040D01*
G01X684342Y131290D02*
X684926Y130874D01*
X685592Y130707D01*
X686259Y130874D01*
X686842Y131374D01*
X687259Y132124D01*
X687426Y132874D01*
Y133790D01*
X687259Y134540D01*
X686842Y135207D01*
X686342Y135540D01*
X685759Y135707D01*
X685092Y135540D01*
X684592Y135207D01*
X684259Y134707D01*
X684092Y134040D01*
X684259Y133457D01*
X684676Y132874D01*
X685176Y132540D01*
X685759Y132457D01*
X686426Y132624D01*
X686926Y133040D01*
X687426Y133790D01*
G01X691359Y135707D02*
X690692Y135540D01*
X690192Y135124D01*
X689859Y134624D01*
X689609Y133957D01*
X689526Y133207D01*
X689609Y132457D01*
X689859Y131790D01*
X690192Y131290D01*
X690692Y130874D01*
X691359Y130707D01*
X692026Y130874D01*
X692526Y131290D01*
X692859Y131790D01*
X693109Y132457D01*
X693192Y133207D01*
X693109Y133957D01*
X692859Y134624D01*
X692526Y135124D01*
X692026Y135540D01*
X691359Y135707D01*
G01X695459Y130540D02*
X698459Y135707D01*
G01X695459D02*
X694959Y135540D01*
X694709Y135290D01*
X694542Y134790D01*
X694709Y134290D01*
X694959Y134040D01*
X695459Y133874D01*
X695959Y134040D01*
X696209Y134290D01*
X696376Y134790D01*
X696209Y135290D01*
X695959Y135540D01*
X695459Y135707D01*
G01X698459Y132374D02*
X697959Y132207D01*
X697709Y131957D01*
X697542Y131457D01*
X697709Y130957D01*
X697959Y130707D01*
X698459Y130540D01*
X698959Y130707D01*
X699209Y130957D01*
X699376Y131457D01*
X699209Y131957D01*
X698959Y132207D01*
X698459Y132374D01*
G01X706992Y130707D02*
Y134040D01*
G01Y133374D02*
X707409Y133707D01*
X707826Y133957D01*
X708409Y134040D01*
X708826Y133957D01*
X709326Y133707D01*
G01X712509Y132957D02*
X715176D01*
X714926Y133540D01*
X714509Y133874D01*
X713926Y134040D01*
X713342Y133957D01*
X712842Y133707D01*
X712509Y133124D01*
X712342Y132624D01*
Y132124D01*
X712509Y131624D01*
X712926Y131124D01*
X713426Y130790D01*
X714009Y130707D01*
X714592Y130874D01*
X715176Y131374D01*
G01X718109Y131290D02*
X718526Y130957D01*
X719109Y130707D01*
X719609D01*
X720109Y130874D01*
X720442Y131124D01*
X720609Y131457D01*
X720526Y131957D01*
X720192Y132207D01*
X718692Y132707D01*
X718359Y133290D01*
X718526Y133707D01*
X718859Y133957D01*
X719359Y134040D01*
X719859Y133957D01*
X720359Y133707D01*
G01X724959Y134040D02*
Y130707D01*
G01Y135374D02*
X724792Y135457D01*
Y135624D01*
X724959Y135707D01*
X725126Y135624D01*
Y135457D01*
X724959Y135374D01*
G01X729142Y130707D02*
Y134040D01*
G01Y133207D02*
X729476Y133624D01*
X729976Y133957D01*
X730642Y134040D01*
X731226Y133957D01*
X731726Y133624D01*
X731976Y133040D01*
Y130707D01*
G01X741176Y129207D02*
X742342Y130374D01*
Y131540D01*
X741176D01*
Y130374D01*
X742342D01*
G01Y132374D02*
Y133540D01*
X741176D01*
Y132374D01*
X742342D01*
G01X745526Y130707D02*
Y135707D01*
X747192D01*
X747859Y135457D01*
X748359Y135124D01*
X748776Y134624D01*
X749109Y134040D01*
X749192Y133207D01*
X749109Y132374D01*
X748776Y131790D01*
X748359Y131290D01*
X747859Y130957D01*
X747192Y130707D01*
X745526D01*
G01X752959D02*
X752459Y130790D01*
X751959Y131124D01*
X751626Y131707D01*
X751459Y132374D01*
X751626Y133040D01*
X751959Y133624D01*
X752459Y133957D01*
X752959Y134040D01*
X753459Y133957D01*
X753959Y133624D01*
X754292Y133040D01*
X754376Y132374D01*
X754292Y131707D01*
X753959Y131124D01*
X753459Y130790D01*
X752959Y130707D01*
G01X762742D02*
Y134040D01*
G01Y133207D02*
X763076Y133624D01*
X763576Y133957D01*
X764242Y134040D01*
X764826Y133957D01*
X765326Y133624D01*
X765576Y133040D01*
Y130707D01*
G01X769759D02*
X769259Y130790D01*
X768759Y131124D01*
X768426Y131707D01*
X768259Y132374D01*
X768426Y133040D01*
X768759Y133624D01*
X769259Y133957D01*
X769759Y134040D01*
X770259Y133957D01*
X770759Y133624D01*
X771092Y133040D01*
X771176Y132374D01*
X771092Y131707D01*
X770759Y131124D01*
X770259Y130790D01*
X769759Y130707D01*
G01X775359Y135707D02*
Y130707D01*
G01X774192Y134040D02*
X776526D01*
G01X788059Y130707D02*
Y134040D01*
G01Y133457D02*
X787726Y133790D01*
X787226Y133957D01*
X786642Y134040D01*
X786059Y133874D01*
X785559Y133540D01*
X785226Y133040D01*
X785059Y132374D01*
X785226Y131707D01*
X785559Y131207D01*
X786059Y130874D01*
X786642Y130707D01*
X787226Y130790D01*
X787726Y131040D01*
X788059Y131374D01*
G01X792159Y130707D02*
Y135707D01*
G01X797759Y130707D02*
Y135707D01*
G01X803359Y130707D02*
X802859Y130790D01*
X802359Y131124D01*
X802026Y131707D01*
X801859Y132374D01*
X802026Y133040D01*
X802359Y133624D01*
X802859Y133957D01*
X803359Y134040D01*
X803859Y133957D01*
X804359Y133624D01*
X804692Y133040D01*
X804776Y132374D01*
X804692Y131707D01*
X804359Y131124D01*
X803859Y130790D01*
X803359Y130707D01*
G01X806876Y134040D02*
X807876Y130707D01*
X808959Y134040D01*
X810042Y130707D01*
X811042Y134040D01*
G01X517759Y141207D02*
Y146207D01*
X516759Y145207D01*
G01Y141207D02*
X518759D01*
G01X523359Y141040D02*
X523192Y141124D01*
Y141290D01*
X523359Y141374D01*
X523526Y141290D01*
Y141124D01*
X523359Y141040D01*
G01X527126Y141207D02*
Y146207D01*
X528792D01*
X529459Y145957D01*
X529959Y145624D01*
X530376Y145124D01*
X530709Y144540D01*
X530792Y143707D01*
X530709Y142874D01*
X530376Y142290D01*
X529959Y141790D01*
X529459Y141457D01*
X528792Y141207D01*
X527126D01*
G01X534559Y144540D02*
Y141207D01*
G01Y145874D02*
X534392Y145957D01*
Y146124D01*
X534559Y146207D01*
X534726Y146124D01*
Y145957D01*
X534559Y145874D01*
G01X537659Y141207D02*
Y144540D01*
G01Y143624D02*
X537909Y144040D01*
X538326Y144374D01*
X538909Y144540D01*
X539492Y144374D01*
X539909Y144040D01*
X540159Y143624D01*
Y141207D01*
G01Y143624D02*
X540409Y144040D01*
X540826Y144374D01*
X541409Y144540D01*
X541992Y144374D01*
X542409Y144040D01*
X542659Y143540D01*
Y141207D01*
G01X544259Y139540D02*
Y144540D01*
G01Y143790D02*
X544676Y144207D01*
X545092Y144457D01*
X545759Y144540D01*
X546342Y144457D01*
X546926Y144040D01*
X547176Y143457D01*
X547259Y142874D01*
X547176Y142290D01*
X546926Y141707D01*
X546426Y141374D01*
X545759Y141207D01*
X545176Y141290D01*
X544592Y141540D01*
X544259Y141874D01*
G01X551359Y141207D02*
Y146207D01*
G01X555709Y143457D02*
X558376D01*
X558126Y144040D01*
X557709Y144374D01*
X557126Y144540D01*
X556542Y144457D01*
X556042Y144207D01*
X555709Y143624D01*
X555542Y143124D01*
Y142624D01*
X555709Y142124D01*
X556126Y141624D01*
X556626Y141290D01*
X557209Y141207D01*
X557792Y141374D01*
X558376Y141874D01*
G01X569826Y141207D02*
X566492Y142874D01*
X569826Y144540D01*
G01X579359Y141207D02*
Y146207D01*
X578359Y145207D01*
G01Y141207D02*
X580359D01*
G01X588059D02*
Y144540D01*
G01Y143624D02*
X588309Y144040D01*
X588726Y144374D01*
X589309Y144540D01*
X589892Y144374D01*
X590309Y144040D01*
X590559Y143624D01*
Y141207D01*
G01Y143624D02*
X590809Y144040D01*
X591226Y144374D01*
X591809Y144540D01*
X592392Y144374D01*
X592809Y144040D01*
X593059Y143540D01*
Y141207D01*
G01X596159Y144540D02*
Y141207D01*
G01Y145874D02*
X595992Y145957D01*
Y146124D01*
X596159Y146207D01*
X596326Y146124D01*
Y145957D01*
X596159Y145874D01*
G01X601759Y141207D02*
Y146207D01*
G01X612376Y139707D02*
X613542Y140874D01*
Y142040D01*
X612376D01*
Y140874D01*
X613542D01*
G01Y142874D02*
Y144040D01*
X612376D01*
Y142874D01*
X613542D01*
G01X510759Y355707D02*
Y117207D01*
G01X517759Y175207D02*
Y180207D01*
X516759Y179207D01*
G01Y175207D02*
X518759D01*
G01X523359Y175040D02*
X523192Y175124D01*
Y175290D01*
X523359Y175374D01*
X523526Y175290D01*
Y175124D01*
X523359Y175040D01*
G01X526876Y180207D02*
X528959Y175207D01*
X531042Y180207D01*
G01X534559Y178540D02*
Y175207D01*
G01Y179874D02*
X534392Y179957D01*
Y180124D01*
X534559Y180207D01*
X534726Y180124D01*
Y179957D01*
X534559Y179874D01*
G01X541659Y175207D02*
Y178540D01*
G01Y177957D02*
X541326Y178290D01*
X540826Y178457D01*
X540242Y178540D01*
X539659Y178374D01*
X539159Y178040D01*
X538826Y177540D01*
X538659Y176874D01*
X538826Y176207D01*
X539159Y175707D01*
X539659Y175374D01*
X540242Y175207D01*
X540826Y175290D01*
X541326Y175540D01*
X541659Y175874D01*
G01X550109Y175790D02*
X550526Y175457D01*
X551109Y175207D01*
X551609D01*
X552109Y175374D01*
X552442Y175624D01*
X552609Y175957D01*
X552526Y176457D01*
X552192Y176707D01*
X550692Y177207D01*
X550359Y177790D01*
X550526Y178207D01*
X550859Y178457D01*
X551359Y178540D01*
X551859Y178457D01*
X552359Y178207D01*
G01X555542Y175207D02*
Y180207D01*
G01Y177790D02*
X555959Y178207D01*
X556376Y178457D01*
X557042Y178540D01*
X557542Y178457D01*
X558126Y178124D01*
X558376Y177624D01*
Y175207D01*
G01X562559D02*
X562059Y175290D01*
X561559Y175624D01*
X561226Y176207D01*
X561059Y176874D01*
X561226Y177540D01*
X561559Y178124D01*
X562059Y178457D01*
X562559Y178540D01*
X563059Y178457D01*
X563559Y178124D01*
X563892Y177540D01*
X563976Y176874D01*
X563892Y176207D01*
X563559Y175624D01*
X563059Y175290D01*
X562559Y175207D01*
G01X566742Y178540D02*
Y176207D01*
X567076Y175624D01*
X567576Y175290D01*
X568159Y175207D01*
X568742Y175290D01*
X569242Y175624D01*
X569576Y176207D01*
G01Y175207D02*
Y178540D01*
G01X573759Y175207D02*
Y180207D01*
G01X580859D02*
Y175207D01*
G01Y175957D02*
X580526Y175540D01*
X580026Y175290D01*
X579442Y175207D01*
X578776Y175374D01*
X578276Y175790D01*
X577942Y176290D01*
X577859Y176874D01*
X577942Y177457D01*
X578276Y177957D01*
X578776Y178374D01*
X579442Y178540D01*
X580026Y178457D01*
X580442Y178290D01*
X580859Y177957D01*
G01X589059Y175207D02*
Y180207D01*
G01Y177707D02*
X589476Y178207D01*
X589976Y178457D01*
X590476Y178540D01*
X591226Y178374D01*
X591726Y178040D01*
X592059Y177457D01*
Y176790D01*
X591892Y176124D01*
X591559Y175624D01*
X590976Y175290D01*
X590476Y175207D01*
X589976Y175290D01*
X589476Y175540D01*
X589059Y175957D01*
G01X594909Y177457D02*
X597576D01*
X597326Y178040D01*
X596909Y178374D01*
X596326Y178540D01*
X595742Y178457D01*
X595242Y178207D01*
X594909Y177624D01*
X594742Y177124D01*
Y176624D01*
X594909Y176124D01*
X595326Y175624D01*
X595826Y175290D01*
X596409Y175207D01*
X596992Y175374D01*
X597576Y175874D01*
G01X605859Y173540D02*
Y178540D01*
G01Y177790D02*
X606276Y178207D01*
X606692Y178457D01*
X607359Y178540D01*
X607942Y178457D01*
X608526Y178040D01*
X608776Y177457D01*
X608859Y176874D01*
X608776Y176290D01*
X608526Y175707D01*
X608026Y175374D01*
X607359Y175207D01*
X606776Y175290D01*
X606192Y175540D01*
X605859Y175874D01*
G01X612959Y175207D02*
Y180207D01*
G01X617142Y178540D02*
Y176207D01*
X617476Y175624D01*
X617976Y175290D01*
X618559Y175207D01*
X619142Y175290D01*
X619642Y175624D01*
X619976Y176207D01*
G01Y175207D02*
Y178540D01*
G01X622992Y173957D02*
X623576Y173624D01*
X624242Y173540D01*
X624826Y173624D01*
X625326Y174040D01*
X625659Y174624D01*
Y178540D01*
G01Y177874D02*
X625326Y178207D01*
X624826Y178457D01*
X624242Y178540D01*
X623576Y178374D01*
X623159Y178040D01*
X622826Y177457D01*
X622659Y176874D01*
X622742Y176374D01*
X623076Y175790D01*
X623576Y175374D01*
X624242Y175207D01*
X624742Y175290D01*
X625326Y175624D01*
X625659Y175957D01*
G01X628592Y173957D02*
X629176Y173624D01*
X629842Y173540D01*
X630426Y173624D01*
X630926Y174040D01*
X631259Y174624D01*
Y178540D01*
G01Y177874D02*
X630926Y178207D01*
X630426Y178457D01*
X629842Y178540D01*
X629176Y178374D01*
X628759Y178040D01*
X628426Y177457D01*
X628259Y176874D01*
X628342Y176374D01*
X628676Y175790D01*
X629176Y175374D01*
X629842Y175207D01*
X630342Y175290D01*
X630926Y175624D01*
X631259Y175957D01*
G01X634109Y177457D02*
X636776D01*
X636526Y178040D01*
X636109Y178374D01*
X635526Y178540D01*
X634942Y178457D01*
X634442Y178207D01*
X634109Y177624D01*
X633942Y177124D01*
Y176624D01*
X634109Y176124D01*
X634526Y175624D01*
X635026Y175290D01*
X635609Y175207D01*
X636192Y175374D01*
X636776Y175874D01*
G01X642459Y180207D02*
Y175207D01*
G01Y175957D02*
X642126Y175540D01*
X641626Y175290D01*
X641042Y175207D01*
X640376Y175374D01*
X639876Y175790D01*
X639542Y176290D01*
X639459Y176874D01*
X639542Y177457D01*
X639876Y177957D01*
X640376Y178374D01*
X641042Y178540D01*
X641626Y178457D01*
X642042Y178290D01*
X642459Y177957D01*
G01X650076Y178540D02*
X651076Y175207D01*
X652159Y178540D01*
X653242Y175207D01*
X654242Y178540D01*
G01X657759D02*
Y175207D01*
G01Y179874D02*
X657592Y179957D01*
Y180124D01*
X657759Y180207D01*
X657926Y180124D01*
Y179957D01*
X657759Y179874D01*
G01X663359Y180207D02*
Y175207D01*
G01X662192Y178540D02*
X664526D01*
G01X667542Y175207D02*
Y180207D01*
G01Y177790D02*
X667959Y178207D01*
X668376Y178457D01*
X669042Y178540D01*
X669542Y178457D01*
X670126Y178124D01*
X670376Y177624D01*
Y175207D01*
G01X678492D02*
X681826Y176874D01*
X678492Y178540D01*
G01X684342Y175790D02*
X684926Y175374D01*
X685592Y175207D01*
X686259Y175374D01*
X686842Y175874D01*
X687259Y176624D01*
X687426Y177374D01*
Y178290D01*
X687259Y179040D01*
X686842Y179707D01*
X686342Y180040D01*
X685759Y180207D01*
X685092Y180040D01*
X684592Y179707D01*
X684259Y179207D01*
X684092Y178540D01*
X684259Y177957D01*
X684676Y177374D01*
X685176Y177040D01*
X685759Y176957D01*
X686426Y177124D01*
X686926Y177540D01*
X687426Y178290D01*
G01X691359Y180207D02*
X690692Y180040D01*
X690192Y179624D01*
X689859Y179124D01*
X689609Y178457D01*
X689526Y177707D01*
X689609Y176957D01*
X689859Y176290D01*
X690192Y175790D01*
X690692Y175374D01*
X691359Y175207D01*
X692026Y175374D01*
X692526Y175790D01*
X692859Y176290D01*
X693109Y176957D01*
X693192Y177707D01*
X693109Y178457D01*
X692859Y179124D01*
X692526Y179624D01*
X692026Y180040D01*
X691359Y180207D01*
G01X695459Y175040D02*
X698459Y180207D01*
G01X695459D02*
X694959Y180040D01*
X694709Y179790D01*
X694542Y179290D01*
X694709Y178790D01*
X694959Y178540D01*
X695459Y178374D01*
X695959Y178540D01*
X696209Y178790D01*
X696376Y179290D01*
X696209Y179790D01*
X695959Y180040D01*
X695459Y180207D01*
G01X698459Y176874D02*
X697959Y176707D01*
X697709Y176457D01*
X697542Y175957D01*
X697709Y175457D01*
X697959Y175207D01*
X698459Y175040D01*
X698959Y175207D01*
X699209Y175457D01*
X699376Y175957D01*
X699209Y176457D01*
X698959Y176707D01*
X698459Y176874D01*
G01X706992Y175207D02*
Y178540D01*
G01Y177874D02*
X707409Y178207D01*
X707826Y178457D01*
X708409Y178540D01*
X708826Y178457D01*
X709326Y178207D01*
G01X712509Y177457D02*
X715176D01*
X714926Y178040D01*
X714509Y178374D01*
X713926Y178540D01*
X713342Y178457D01*
X712842Y178207D01*
X712509Y177624D01*
X712342Y177124D01*
Y176624D01*
X712509Y176124D01*
X712926Y175624D01*
X713426Y175290D01*
X714009Y175207D01*
X714592Y175374D01*
X715176Y175874D01*
G01X718109Y175790D02*
X718526Y175457D01*
X719109Y175207D01*
X719609D01*
X720109Y175374D01*
X720442Y175624D01*
X720609Y175957D01*
X720526Y176457D01*
X720192Y176707D01*
X718692Y177207D01*
X718359Y177790D01*
X718526Y178207D01*
X718859Y178457D01*
X719359Y178540D01*
X719859Y178457D01*
X720359Y178207D01*
G01X724959Y178540D02*
Y175207D01*
G01Y179874D02*
X724792Y179957D01*
Y180124D01*
X724959Y180207D01*
X725126Y180124D01*
Y179957D01*
X724959Y179874D01*
G01X729142Y175207D02*
Y178540D01*
G01Y177707D02*
X729476Y178124D01*
X729976Y178457D01*
X730642Y178540D01*
X731226Y178457D01*
X731726Y178124D01*
X731976Y177540D01*
Y175207D01*
G01X741176Y173707D02*
X742342Y174874D01*
Y176040D01*
X741176D01*
Y174874D01*
X742342D01*
G01Y176874D02*
Y178040D01*
X741176D01*
Y176874D01*
X742342D01*
G01X745526Y175207D02*
Y180207D01*
X747192D01*
X747859Y179957D01*
X748359Y179624D01*
X748776Y179124D01*
X749109Y178540D01*
X749192Y177707D01*
X749109Y176874D01*
X748776Y176290D01*
X748359Y175790D01*
X747859Y175457D01*
X747192Y175207D01*
X745526D01*
G01X752959D02*
X752459Y175290D01*
X751959Y175624D01*
X751626Y176207D01*
X751459Y176874D01*
X751626Y177540D01*
X751959Y178124D01*
X752459Y178457D01*
X752959Y178540D01*
X753459Y178457D01*
X753959Y178124D01*
X754292Y177540D01*
X754376Y176874D01*
X754292Y176207D01*
X753959Y175624D01*
X753459Y175290D01*
X752959Y175207D01*
G01X762742D02*
Y178540D01*
G01Y177707D02*
X763076Y178124D01*
X763576Y178457D01*
X764242Y178540D01*
X764826Y178457D01*
X765326Y178124D01*
X765576Y177540D01*
Y175207D01*
G01X769759D02*
X769259Y175290D01*
X768759Y175624D01*
X768426Y176207D01*
X768259Y176874D01*
X768426Y177540D01*
X768759Y178124D01*
X769259Y178457D01*
X769759Y178540D01*
X770259Y178457D01*
X770759Y178124D01*
X771092Y177540D01*
X771176Y176874D01*
X771092Y176207D01*
X770759Y175624D01*
X770259Y175290D01*
X769759Y175207D01*
G01X775359Y180207D02*
Y175207D01*
G01X774192Y178540D02*
X776526D01*
G01X788059Y175207D02*
Y178540D01*
G01Y177957D02*
X787726Y178290D01*
X787226Y178457D01*
X786642Y178540D01*
X786059Y178374D01*
X785559Y178040D01*
X785226Y177540D01*
X785059Y176874D01*
X785226Y176207D01*
X785559Y175707D01*
X786059Y175374D01*
X786642Y175207D01*
X787226Y175290D01*
X787726Y175540D01*
X788059Y175874D01*
G01X792159Y175207D02*
Y180207D01*
G01X797759Y175207D02*
Y180207D01*
G01X803359Y175207D02*
X802859Y175290D01*
X802359Y175624D01*
X802026Y176207D01*
X801859Y176874D01*
X802026Y177540D01*
X802359Y178124D01*
X802859Y178457D01*
X803359Y178540D01*
X803859Y178457D01*
X804359Y178124D01*
X804692Y177540D01*
X804776Y176874D01*
X804692Y176207D01*
X804359Y175624D01*
X803859Y175290D01*
X803359Y175207D01*
G01X806876Y178540D02*
X807876Y175207D01*
X808959Y178540D01*
X810042Y175207D01*
X811042Y178540D01*
G01X520176Y196707D02*
X522259Y191707D01*
X524342Y196707D01*
G01X527859Y195040D02*
Y191707D01*
G01Y196374D02*
X527692Y196457D01*
Y196624D01*
X527859Y196707D01*
X528026Y196624D01*
Y196457D01*
X527859Y196374D01*
G01X534959Y191707D02*
Y195040D01*
G01Y194457D02*
X534626Y194790D01*
X534126Y194957D01*
X533542Y195040D01*
X532959Y194874D01*
X532459Y194540D01*
X532126Y194040D01*
X531959Y193374D01*
X532126Y192707D01*
X532459Y192207D01*
X532959Y191874D01*
X533542Y191707D01*
X534126Y191790D01*
X534626Y192040D01*
X534959Y192374D01*
G01X543409Y192290D02*
X543826Y191957D01*
X544409Y191707D01*
X544909D01*
X545409Y191874D01*
X545742Y192124D01*
X545909Y192457D01*
X545826Y192957D01*
X545492Y193207D01*
X543992Y193707D01*
X543659Y194290D01*
X543826Y194707D01*
X544159Y194957D01*
X544659Y195040D01*
X545159Y194957D01*
X545659Y194707D01*
G01X548842Y191707D02*
Y196707D01*
G01Y194290D02*
X549259Y194707D01*
X549676Y194957D01*
X550342Y195040D01*
X550842Y194957D01*
X551426Y194624D01*
X551676Y194124D01*
Y191707D01*
G01X555859D02*
X555359Y191790D01*
X554859Y192124D01*
X554526Y192707D01*
X554359Y193374D01*
X554526Y194040D01*
X554859Y194624D01*
X555359Y194957D01*
X555859Y195040D01*
X556359Y194957D01*
X556859Y194624D01*
X557192Y194040D01*
X557276Y193374D01*
X557192Y192707D01*
X556859Y192124D01*
X556359Y191790D01*
X555859Y191707D01*
G01X560042Y195040D02*
Y192707D01*
X560376Y192124D01*
X560876Y191790D01*
X561459Y191707D01*
X562042Y191790D01*
X562542Y192124D01*
X562876Y192707D01*
G01Y191707D02*
Y195040D01*
G01X567059Y191707D02*
Y196707D01*
G01X574159D02*
Y191707D01*
G01Y192457D02*
X573826Y192040D01*
X573326Y191790D01*
X572742Y191707D01*
X572076Y191874D01*
X571576Y192290D01*
X571242Y192790D01*
X571159Y193374D01*
X571242Y193957D01*
X571576Y194457D01*
X572076Y194874D01*
X572742Y195040D01*
X573326Y194957D01*
X573742Y194790D01*
X574159Y194457D01*
G01X582359Y191707D02*
Y196707D01*
G01Y194207D02*
X582776Y194707D01*
X583276Y194957D01*
X583776Y195040D01*
X584526Y194874D01*
X585026Y194540D01*
X585359Y193957D01*
Y193290D01*
X585192Y192624D01*
X584859Y192124D01*
X584276Y191790D01*
X583776Y191707D01*
X583276Y191790D01*
X582776Y192040D01*
X582359Y192457D01*
G01X588209Y193957D02*
X590876D01*
X590626Y194540D01*
X590209Y194874D01*
X589626Y195040D01*
X589042Y194957D01*
X588542Y194707D01*
X588209Y194124D01*
X588042Y193624D01*
Y193124D01*
X588209Y192624D01*
X588626Y192124D01*
X589126Y191790D01*
X589709Y191707D01*
X590292Y191874D01*
X590876Y192374D01*
G01X599159Y190040D02*
Y195040D01*
G01Y194290D02*
X599576Y194707D01*
X599992Y194957D01*
X600659Y195040D01*
X601242Y194957D01*
X601826Y194540D01*
X602076Y193957D01*
X602159Y193374D01*
X602076Y192790D01*
X601826Y192207D01*
X601326Y191874D01*
X600659Y191707D01*
X600076Y191790D01*
X599492Y192040D01*
X599159Y192374D01*
G01X606259Y191707D02*
Y196707D01*
G01X610442Y195040D02*
Y192707D01*
X610776Y192124D01*
X611276Y191790D01*
X611859Y191707D01*
X612442Y191790D01*
X612942Y192124D01*
X613276Y192707D01*
G01Y191707D02*
Y195040D01*
G01X616292Y190457D02*
X616876Y190124D01*
X617542Y190040D01*
X618126Y190124D01*
X618626Y190540D01*
X618959Y191124D01*
Y195040D01*
G01Y194374D02*
X618626Y194707D01*
X618126Y194957D01*
X617542Y195040D01*
X616876Y194874D01*
X616459Y194540D01*
X616126Y193957D01*
X615959Y193374D01*
X616042Y192874D01*
X616376Y192290D01*
X616876Y191874D01*
X617542Y191707D01*
X618042Y191790D01*
X618626Y192124D01*
X618959Y192457D01*
G01X621892Y190457D02*
X622476Y190124D01*
X623142Y190040D01*
X623726Y190124D01*
X624226Y190540D01*
X624559Y191124D01*
Y195040D01*
G01Y194374D02*
X624226Y194707D01*
X623726Y194957D01*
X623142Y195040D01*
X622476Y194874D01*
X622059Y194540D01*
X621726Y193957D01*
X621559Y193374D01*
X621642Y192874D01*
X621976Y192290D01*
X622476Y191874D01*
X623142Y191707D01*
X623642Y191790D01*
X624226Y192124D01*
X624559Y192457D01*
G01X627409Y193957D02*
X630076D01*
X629826Y194540D01*
X629409Y194874D01*
X628826Y195040D01*
X628242Y194957D01*
X627742Y194707D01*
X627409Y194124D01*
X627242Y193624D01*
Y193124D01*
X627409Y192624D01*
X627826Y192124D01*
X628326Y191790D01*
X628909Y191707D01*
X629492Y191874D01*
X630076Y192374D01*
G01X635759Y196707D02*
Y191707D01*
G01Y192457D02*
X635426Y192040D01*
X634926Y191790D01*
X634342Y191707D01*
X633676Y191874D01*
X633176Y192290D01*
X632842Y192790D01*
X632759Y193374D01*
X632842Y193957D01*
X633176Y194457D01*
X633676Y194874D01*
X634342Y195040D01*
X634926Y194957D01*
X635342Y194790D01*
X635759Y194457D01*
G01X643376Y195040D02*
X644376Y191707D01*
X645459Y195040D01*
X646542Y191707D01*
X647542Y195040D01*
G01X651059D02*
Y191707D01*
G01Y196374D02*
X650892Y196457D01*
Y196624D01*
X651059Y196707D01*
X651226Y196624D01*
Y196457D01*
X651059Y196374D01*
G01X656659Y196707D02*
Y191707D01*
G01X655492Y195040D02*
X657826D01*
G01X660842Y191707D02*
Y196707D01*
G01Y194290D02*
X661259Y194707D01*
X661676Y194957D01*
X662342Y195040D01*
X662842Y194957D01*
X663426Y194624D01*
X663676Y194124D01*
Y191707D01*
G01X671792D02*
X675126Y193374D01*
X671792Y195040D01*
G01X677642Y192290D02*
X678226Y191874D01*
X678892Y191707D01*
X679559Y191874D01*
X680142Y192374D01*
X680559Y193124D01*
X680726Y193874D01*
Y194790D01*
X680559Y195540D01*
X680142Y196207D01*
X679642Y196540D01*
X679059Y196707D01*
X678392Y196540D01*
X677892Y196207D01*
X677559Y195707D01*
X677392Y195040D01*
X677559Y194457D01*
X677976Y193874D01*
X678476Y193540D01*
X679059Y193457D01*
X679726Y193624D01*
X680226Y194040D01*
X680726Y194790D01*
G01X684659Y196707D02*
X683992Y196540D01*
X683492Y196124D01*
X683159Y195624D01*
X682909Y194957D01*
X682826Y194207D01*
X682909Y193457D01*
X683159Y192790D01*
X683492Y192290D01*
X683992Y191874D01*
X684659Y191707D01*
X685326Y191874D01*
X685826Y192290D01*
X686159Y192790D01*
X686409Y193457D01*
X686492Y194207D01*
X686409Y194957D01*
X686159Y195624D01*
X685826Y196124D01*
X685326Y196540D01*
X684659Y196707D01*
G01X688759Y191540D02*
X691759Y196707D01*
G01X688759D02*
X688259Y196540D01*
X688009Y196290D01*
X687842Y195790D01*
X688009Y195290D01*
X688259Y195040D01*
X688759Y194874D01*
X689259Y195040D01*
X689509Y195290D01*
X689676Y195790D01*
X689509Y196290D01*
X689259Y196540D01*
X688759Y196707D01*
G01X691759Y193374D02*
X691259Y193207D01*
X691009Y192957D01*
X690842Y192457D01*
X691009Y191957D01*
X691259Y191707D01*
X691759Y191540D01*
X692259Y191707D01*
X692509Y191957D01*
X692676Y192457D01*
X692509Y192957D01*
X692259Y193207D01*
X691759Y193374D01*
G01X700292Y191707D02*
Y195040D01*
G01Y194374D02*
X700709Y194707D01*
X701126Y194957D01*
X701709Y195040D01*
X702126Y194957D01*
X702626Y194707D01*
G01X705809Y193957D02*
X708476D01*
X708226Y194540D01*
X707809Y194874D01*
X707226Y195040D01*
X706642Y194957D01*
X706142Y194707D01*
X705809Y194124D01*
X705642Y193624D01*
Y193124D01*
X705809Y192624D01*
X706226Y192124D01*
X706726Y191790D01*
X707309Y191707D01*
X707892Y191874D01*
X708476Y192374D01*
G01X711409Y192290D02*
X711826Y191957D01*
X712409Y191707D01*
X712909D01*
X713409Y191874D01*
X713742Y192124D01*
X713909Y192457D01*
X713826Y192957D01*
X713492Y193207D01*
X711992Y193707D01*
X711659Y194290D01*
X711826Y194707D01*
X712159Y194957D01*
X712659Y195040D01*
X713159Y194957D01*
X713659Y194707D01*
G01X718259Y195040D02*
Y191707D01*
G01Y196374D02*
X718092Y196457D01*
Y196624D01*
X718259Y196707D01*
X718426Y196624D01*
Y196457D01*
X718259Y196374D01*
G01X722442Y191707D02*
Y195040D01*
G01Y194207D02*
X722776Y194624D01*
X723276Y194957D01*
X723942Y195040D01*
X724526Y194957D01*
X725026Y194624D01*
X725276Y194040D01*
Y191707D01*
G01X518676Y217707D02*
X520759Y212707D01*
X522842Y217707D01*
G01X526359Y216040D02*
Y212707D01*
G01Y217374D02*
X526192Y217457D01*
Y217624D01*
X526359Y217707D01*
X526526Y217624D01*
Y217457D01*
X526359Y217374D01*
G01X533459Y212707D02*
Y216040D01*
G01Y215457D02*
X533126Y215790D01*
X532626Y215957D01*
X532042Y216040D01*
X531459Y215874D01*
X530959Y215540D01*
X530626Y215040D01*
X530459Y214374D01*
X530626Y213707D01*
X530959Y213207D01*
X531459Y212874D01*
X532042Y212707D01*
X532626Y212790D01*
X533126Y213040D01*
X533459Y213374D01*
G01X541909Y213290D02*
X542326Y212957D01*
X542909Y212707D01*
X543409D01*
X543909Y212874D01*
X544242Y213124D01*
X544409Y213457D01*
X544326Y213957D01*
X543992Y214207D01*
X542492Y214707D01*
X542159Y215290D01*
X542326Y215707D01*
X542659Y215957D01*
X543159Y216040D01*
X543659Y215957D01*
X544159Y215707D01*
G01X547342Y212707D02*
Y217707D01*
G01Y215290D02*
X547759Y215707D01*
X548176Y215957D01*
X548842Y216040D01*
X549342Y215957D01*
X549926Y215624D01*
X550176Y215124D01*
Y212707D01*
G01X554359D02*
X553859Y212790D01*
X553359Y213124D01*
X553026Y213707D01*
X552859Y214374D01*
X553026Y215040D01*
X553359Y215624D01*
X553859Y215957D01*
X554359Y216040D01*
X554859Y215957D01*
X555359Y215624D01*
X555692Y215040D01*
X555776Y214374D01*
X555692Y213707D01*
X555359Y213124D01*
X554859Y212790D01*
X554359Y212707D01*
G01X558542Y216040D02*
Y213707D01*
X558876Y213124D01*
X559376Y212790D01*
X559959Y212707D01*
X560542Y212790D01*
X561042Y213124D01*
X561376Y213707D01*
G01Y212707D02*
Y216040D01*
G01X565559Y212707D02*
Y217707D01*
G01X572659D02*
Y212707D01*
G01Y213457D02*
X572326Y213040D01*
X571826Y212790D01*
X571242Y212707D01*
X570576Y212874D01*
X570076Y213290D01*
X569742Y213790D01*
X569659Y214374D01*
X569742Y214957D01*
X570076Y215457D01*
X570576Y215874D01*
X571242Y216040D01*
X571826Y215957D01*
X572242Y215790D01*
X572659Y215457D01*
G01X580859Y212707D02*
Y217707D01*
G01Y215207D02*
X581276Y215707D01*
X581776Y215957D01*
X582276Y216040D01*
X583026Y215874D01*
X583526Y215540D01*
X583859Y214957D01*
Y214290D01*
X583692Y213624D01*
X583359Y213124D01*
X582776Y212790D01*
X582276Y212707D01*
X581776Y212790D01*
X581276Y213040D01*
X580859Y213457D01*
G01X586709Y214957D02*
X589376D01*
X589126Y215540D01*
X588709Y215874D01*
X588126Y216040D01*
X587542Y215957D01*
X587042Y215707D01*
X586709Y215124D01*
X586542Y214624D01*
Y214124D01*
X586709Y213624D01*
X587126Y213124D01*
X587626Y212790D01*
X588209Y212707D01*
X588792Y212874D01*
X589376Y213374D01*
G01X597659Y211040D02*
Y216040D01*
G01Y215290D02*
X598076Y215707D01*
X598492Y215957D01*
X599159Y216040D01*
X599742Y215957D01*
X600326Y215540D01*
X600576Y214957D01*
X600659Y214374D01*
X600576Y213790D01*
X600326Y213207D01*
X599826Y212874D01*
X599159Y212707D01*
X598576Y212790D01*
X597992Y213040D01*
X597659Y213374D01*
G01X604759Y212707D02*
Y217707D01*
G01X608942Y216040D02*
Y213707D01*
X609276Y213124D01*
X609776Y212790D01*
X610359Y212707D01*
X610942Y212790D01*
X611442Y213124D01*
X611776Y213707D01*
G01Y212707D02*
Y216040D01*
G01X614792Y211457D02*
X615376Y211124D01*
X616042Y211040D01*
X616626Y211124D01*
X617126Y211540D01*
X617459Y212124D01*
Y216040D01*
G01Y215374D02*
X617126Y215707D01*
X616626Y215957D01*
X616042Y216040D01*
X615376Y215874D01*
X614959Y215540D01*
X614626Y214957D01*
X614459Y214374D01*
X614542Y213874D01*
X614876Y213290D01*
X615376Y212874D01*
X616042Y212707D01*
X616542Y212790D01*
X617126Y213124D01*
X617459Y213457D01*
G01X620392Y211457D02*
X620976Y211124D01*
X621642Y211040D01*
X622226Y211124D01*
X622726Y211540D01*
X623059Y212124D01*
Y216040D01*
G01Y215374D02*
X622726Y215707D01*
X622226Y215957D01*
X621642Y216040D01*
X620976Y215874D01*
X620559Y215540D01*
X620226Y214957D01*
X620059Y214374D01*
X620142Y213874D01*
X620476Y213290D01*
X620976Y212874D01*
X621642Y212707D01*
X622142Y212790D01*
X622726Y213124D01*
X623059Y213457D01*
G01X625909Y214957D02*
X628576D01*
X628326Y215540D01*
X627909Y215874D01*
X627326Y216040D01*
X626742Y215957D01*
X626242Y215707D01*
X625909Y215124D01*
X625742Y214624D01*
Y214124D01*
X625909Y213624D01*
X626326Y213124D01*
X626826Y212790D01*
X627409Y212707D01*
X627992Y212874D01*
X628576Y213374D01*
G01X634259Y217707D02*
Y212707D01*
G01Y213457D02*
X633926Y213040D01*
X633426Y212790D01*
X632842Y212707D01*
X632176Y212874D01*
X631676Y213290D01*
X631342Y213790D01*
X631259Y214374D01*
X631342Y214957D01*
X631676Y215457D01*
X632176Y215874D01*
X632842Y216040D01*
X633426Y215957D01*
X633842Y215790D01*
X634259Y215457D01*
G01X644959Y212707D02*
Y217707D01*
X641876Y214124D01*
X646042D01*
G01X649559Y217707D02*
X648892Y217540D01*
X648392Y217124D01*
X648059Y216624D01*
X647809Y215957D01*
X647726Y215207D01*
X647809Y214457D01*
X648059Y213790D01*
X648392Y213290D01*
X648892Y212874D01*
X649559Y212707D01*
X650226Y212874D01*
X650726Y213290D01*
X651059Y213790D01*
X651309Y214457D01*
X651392Y215207D01*
X651309Y215957D01*
X651059Y216624D01*
X650726Y217124D01*
X650226Y217540D01*
X649559Y217707D01*
G01X653659Y212540D02*
X656659Y217707D01*
G01X653659D02*
X653159Y217540D01*
X652909Y217290D01*
X652742Y216790D01*
X652909Y216290D01*
X653159Y216040D01*
X653659Y215874D01*
X654159Y216040D01*
X654409Y216290D01*
X654576Y216790D01*
X654409Y217290D01*
X654159Y217540D01*
X653659Y217707D01*
G01X656659Y214374D02*
X656159Y214207D01*
X655909Y213957D01*
X655742Y213457D01*
X655909Y212957D01*
X656159Y212707D01*
X656659Y212540D01*
X657159Y212707D01*
X657409Y212957D01*
X657576Y213457D01*
X657409Y213957D01*
X657159Y214207D01*
X656659Y214374D01*
G01X663859D02*
X664692Y216040D01*
X665526D01*
X667192Y212707D01*
X668026D01*
X668859Y214374D01*
G01X677559Y212707D02*
Y217707D01*
X676559Y216707D01*
G01Y212707D02*
X678559D01*
G01X683159Y217707D02*
X682492Y217540D01*
X681992Y217124D01*
X681659Y216624D01*
X681409Y215957D01*
X681326Y215207D01*
X681409Y214457D01*
X681659Y213790D01*
X681992Y213290D01*
X682492Y212874D01*
X683159Y212707D01*
X683826Y212874D01*
X684326Y213290D01*
X684659Y213790D01*
X684909Y214457D01*
X684992Y215207D01*
X684909Y215957D01*
X684659Y216624D01*
X684326Y217124D01*
X683826Y217540D01*
X683159Y217707D01*
G01X688759D02*
X688092Y217540D01*
X687592Y217124D01*
X687259Y216624D01*
X687009Y215957D01*
X686926Y215207D01*
X687009Y214457D01*
X687259Y213790D01*
X687592Y213290D01*
X688092Y212874D01*
X688759Y212707D01*
X689426Y212874D01*
X689926Y213290D01*
X690259Y213790D01*
X690509Y214457D01*
X690592Y215207D01*
X690509Y215957D01*
X690259Y216624D01*
X689926Y217124D01*
X689426Y217540D01*
X688759Y217707D01*
G01X692859Y212540D02*
X695859Y217707D01*
G01X692859D02*
X692359Y217540D01*
X692109Y217290D01*
X691942Y216790D01*
X692109Y216290D01*
X692359Y216040D01*
X692859Y215874D01*
X693359Y216040D01*
X693609Y216290D01*
X693776Y216790D01*
X693609Y217290D01*
X693359Y217540D01*
X692859Y217707D01*
G01X695859Y214374D02*
X695359Y214207D01*
X695109Y213957D01*
X694942Y213457D01*
X695109Y212957D01*
X695359Y212707D01*
X695859Y212540D01*
X696359Y212707D01*
X696609Y212957D01*
X696776Y213457D01*
X696609Y213957D01*
X696359Y214207D01*
X695859Y214374D01*
G01X704309Y213290D02*
X704726Y212957D01*
X705309Y212707D01*
X705809D01*
X706309Y212874D01*
X706642Y213124D01*
X706809Y213457D01*
X706726Y213957D01*
X706392Y214207D01*
X704892Y214707D01*
X704559Y215290D01*
X704726Y215707D01*
X705059Y215957D01*
X705559Y216040D01*
X706059Y215957D01*
X706559Y215707D01*
G01X711159Y212707D02*
X710659Y212790D01*
X710159Y213124D01*
X709826Y213707D01*
X709659Y214374D01*
X709826Y215040D01*
X710159Y215624D01*
X710659Y215957D01*
X711159Y216040D01*
X711659Y215957D01*
X712159Y215624D01*
X712492Y215040D01*
X712576Y214374D01*
X712492Y213707D01*
X712159Y213124D01*
X711659Y212790D01*
X711159Y212707D01*
G01X716759D02*
Y217707D01*
G01X723859D02*
Y212707D01*
G01Y213457D02*
X723526Y213040D01*
X723026Y212790D01*
X722442Y212707D01*
X721776Y212874D01*
X721276Y213290D01*
X720942Y213790D01*
X720859Y214374D01*
X720942Y214957D01*
X721276Y215457D01*
X721776Y215874D01*
X722442Y216040D01*
X723026Y215957D01*
X723442Y215790D01*
X723859Y215457D01*
G01X726709Y214957D02*
X729376D01*
X729126Y215540D01*
X728709Y215874D01*
X728126Y216040D01*
X727542Y215957D01*
X727042Y215707D01*
X726709Y215124D01*
X726542Y214624D01*
Y214124D01*
X726709Y213624D01*
X727126Y213124D01*
X727626Y212790D01*
X728209Y212707D01*
X728792Y212874D01*
X729376Y213374D01*
G01X732392Y212707D02*
Y216040D01*
G01Y215374D02*
X732809Y215707D01*
X733226Y215957D01*
X733809Y216040D01*
X734226Y215957D01*
X734726Y215707D01*
G01X742259Y212707D02*
Y216040D01*
G01Y215124D02*
X742509Y215540D01*
X742926Y215874D01*
X743509Y216040D01*
X744092Y215874D01*
X744509Y215540D01*
X744759Y215124D01*
Y212707D01*
G01Y215124D02*
X745009Y215540D01*
X745426Y215874D01*
X746009Y216040D01*
X746592Y215874D01*
X747009Y215540D01*
X747259Y215040D01*
Y212707D01*
G01X751859D02*
Y216040D01*
G01Y215457D02*
X751526Y215790D01*
X751026Y215957D01*
X750442Y216040D01*
X749859Y215874D01*
X749359Y215540D01*
X749026Y215040D01*
X748859Y214374D01*
X749026Y213707D01*
X749359Y213207D01*
X749859Y212874D01*
X750442Y212707D01*
X751026Y212790D01*
X751526Y213040D01*
X751859Y213374D01*
G01X754709Y213290D02*
X755126Y212957D01*
X755709Y212707D01*
X756209D01*
X756709Y212874D01*
X757042Y213124D01*
X757209Y213457D01*
X757126Y213957D01*
X756792Y214207D01*
X755292Y214707D01*
X754959Y215290D01*
X755126Y215707D01*
X755459Y215957D01*
X755959Y216040D01*
X756459Y215957D01*
X756959Y215707D01*
G01X760142Y212707D02*
Y217707D01*
G01X762809Y216040D02*
X760142Y214124D01*
G01X761226Y214874D02*
X762976Y212707D01*
G01X515176Y293874D02*
X515676Y294374D01*
X516259Y294624D01*
X516926Y294707D01*
X517759Y294540D01*
X518342Y294124D01*
X518509Y293624D01*
X518426Y293124D01*
X518092Y292707D01*
X516426Y291874D01*
X515676Y291290D01*
X515176Y290457D01*
X515009Y289707D01*
X518509D01*
G01X522359Y289540D02*
X522192Y289624D01*
Y289790D01*
X522359Y289874D01*
X522526Y289790D01*
Y289624D01*
X522359Y289540D01*
G01X527959Y294707D02*
Y289707D01*
G01X526042Y294707D02*
X529876D01*
G01X532142Y289707D02*
Y294707D01*
G01Y292290D02*
X532559Y292707D01*
X532976Y292957D01*
X533642Y293040D01*
X534142Y292957D01*
X534726Y292624D01*
X534976Y292124D01*
Y289707D01*
G01X537909Y291957D02*
X540576D01*
X540326Y292540D01*
X539909Y292874D01*
X539326Y293040D01*
X538742Y292957D01*
X538242Y292707D01*
X537909Y292124D01*
X537742Y291624D01*
Y291124D01*
X537909Y290624D01*
X538326Y290124D01*
X538826Y289790D01*
X539409Y289707D01*
X539992Y289874D01*
X540576Y290374D01*
G01X549109Y290290D02*
X549526Y289957D01*
X550109Y289707D01*
X550609D01*
X551109Y289874D01*
X551442Y290124D01*
X551609Y290457D01*
X551526Y290957D01*
X551192Y291207D01*
X549692Y291707D01*
X549359Y292290D01*
X549526Y292707D01*
X549859Y292957D01*
X550359Y293040D01*
X550859Y292957D01*
X551359Y292707D01*
G01X555959Y293040D02*
Y289707D01*
G01Y294374D02*
X555792Y294457D01*
Y294624D01*
X555959Y294707D01*
X556126Y294624D01*
Y294457D01*
X555959Y294374D01*
G01X563059Y294707D02*
Y289707D01*
G01Y290457D02*
X562726Y290040D01*
X562226Y289790D01*
X561642Y289707D01*
X560976Y289874D01*
X560476Y290290D01*
X560142Y290790D01*
X560059Y291374D01*
X560142Y291957D01*
X560476Y292457D01*
X560976Y292874D01*
X561642Y293040D01*
X562226Y292957D01*
X562642Y292790D01*
X563059Y292457D01*
G01X565909Y291957D02*
X568576D01*
X568326Y292540D01*
X567909Y292874D01*
X567326Y293040D01*
X566742Y292957D01*
X566242Y292707D01*
X565909Y292124D01*
X565742Y291624D01*
Y291124D01*
X565909Y290624D01*
X566326Y290124D01*
X566826Y289790D01*
X567409Y289707D01*
X567992Y289874D01*
X568576Y290374D01*
G01X576276Y293040D02*
X577276Y289707D01*
X578359Y293040D01*
X579442Y289707D01*
X580442Y293040D01*
G01X583959D02*
Y289707D01*
G01Y294374D02*
X583792Y294457D01*
Y294624D01*
X583959Y294707D01*
X584126Y294624D01*
Y294457D01*
X583959Y294374D01*
G01X589559Y294707D02*
Y289707D01*
G01X588392Y293040D02*
X590726D01*
G01X593742Y289707D02*
Y294707D01*
G01Y292290D02*
X594159Y292707D01*
X594576Y292957D01*
X595242Y293040D01*
X595742Y292957D01*
X596326Y292624D01*
X596576Y292124D01*
Y289707D01*
G01X605109Y290290D02*
X605526Y289957D01*
X606109Y289707D01*
X606609D01*
X607109Y289874D01*
X607442Y290124D01*
X607609Y290457D01*
X607526Y290957D01*
X607192Y291207D01*
X605692Y291707D01*
X605359Y292290D01*
X605526Y292707D01*
X605859Y292957D01*
X606359Y293040D01*
X606859Y292957D01*
X607359Y292707D01*
G01X611959Y289707D02*
X611459Y289790D01*
X610959Y290124D01*
X610626Y290707D01*
X610459Y291374D01*
X610626Y292040D01*
X610959Y292624D01*
X611459Y292957D01*
X611959Y293040D01*
X612459Y292957D01*
X612959Y292624D01*
X613292Y292040D01*
X613376Y291374D01*
X613292Y290707D01*
X612959Y290124D01*
X612459Y289790D01*
X611959Y289707D01*
G01X617559D02*
Y294707D01*
G01X624659D02*
Y289707D01*
G01Y290457D02*
X624326Y290040D01*
X623826Y289790D01*
X623242Y289707D01*
X622576Y289874D01*
X622076Y290290D01*
X621742Y290790D01*
X621659Y291374D01*
X621742Y291957D01*
X622076Y292457D01*
X622576Y292874D01*
X623242Y293040D01*
X623826Y292957D01*
X624242Y292790D01*
X624659Y292457D01*
G01X627509Y291957D02*
X630176D01*
X629926Y292540D01*
X629509Y292874D01*
X628926Y293040D01*
X628342Y292957D01*
X627842Y292707D01*
X627509Y292124D01*
X627342Y291624D01*
Y291124D01*
X627509Y290624D01*
X627926Y290124D01*
X628426Y289790D01*
X629009Y289707D01*
X629592Y289874D01*
X630176Y290374D01*
G01X633192Y289707D02*
Y293040D01*
G01Y292374D02*
X633609Y292707D01*
X634026Y292957D01*
X634609Y293040D01*
X635026Y292957D01*
X635526Y292707D01*
G01X643059Y289707D02*
Y293040D01*
G01Y292124D02*
X643309Y292540D01*
X643726Y292874D01*
X644309Y293040D01*
X644892Y292874D01*
X645309Y292540D01*
X645559Y292124D01*
Y289707D01*
G01Y292124D02*
X645809Y292540D01*
X646226Y292874D01*
X646809Y293040D01*
X647392Y292874D01*
X647809Y292540D01*
X648059Y292040D01*
Y289707D01*
G01X652659D02*
Y293040D01*
G01Y292457D02*
X652326Y292790D01*
X651826Y292957D01*
X651242Y293040D01*
X650659Y292874D01*
X650159Y292540D01*
X649826Y292040D01*
X649659Y291374D01*
X649826Y290707D01*
X650159Y290207D01*
X650659Y289874D01*
X651242Y289707D01*
X651826Y289790D01*
X652326Y290040D01*
X652659Y290374D01*
G01X655509Y290290D02*
X655926Y289957D01*
X656509Y289707D01*
X657009D01*
X657509Y289874D01*
X657842Y290124D01*
X658009Y290457D01*
X657926Y290957D01*
X657592Y291207D01*
X656092Y291707D01*
X655759Y292290D01*
X655926Y292707D01*
X656259Y292957D01*
X656759Y293040D01*
X657259Y292957D01*
X657759Y292707D01*
G01X660942Y289707D02*
Y294707D01*
G01X663609Y293040D02*
X660942Y291124D01*
G01X662026Y291874D02*
X663776Y289707D01*
G01X672059Y288040D02*
Y293040D01*
G01Y292290D02*
X672476Y292707D01*
X672892Y292957D01*
X673559Y293040D01*
X674142Y292957D01*
X674726Y292540D01*
X674976Y291957D01*
X675059Y291374D01*
X674976Y290790D01*
X674726Y290207D01*
X674226Y289874D01*
X673559Y289707D01*
X672976Y289790D01*
X672392Y290040D01*
X672059Y290374D01*
G01X680659Y289707D02*
Y293040D01*
G01Y292457D02*
X680326Y292790D01*
X679826Y292957D01*
X679242Y293040D01*
X678659Y292874D01*
X678159Y292540D01*
X677826Y292040D01*
X677659Y291374D01*
X677826Y290707D01*
X678159Y290207D01*
X678659Y289874D01*
X679242Y289707D01*
X679826Y289790D01*
X680326Y290040D01*
X680659Y290374D01*
G01X686259Y294707D02*
Y289707D01*
G01Y290457D02*
X685926Y290040D01*
X685426Y289790D01*
X684842Y289707D01*
X684176Y289874D01*
X683676Y290290D01*
X683342Y290790D01*
X683259Y291374D01*
X683342Y291957D01*
X683676Y292457D01*
X684176Y292874D01*
X684842Y293040D01*
X685426Y292957D01*
X685842Y292790D01*
X686259Y292457D01*
G01X690192Y288790D02*
X690526Y289874D01*
G01X701559Y294707D02*
Y289707D01*
G01X700392Y293040D02*
X702726D01*
G01X705742Y289707D02*
Y294707D01*
G01Y292290D02*
X706159Y292707D01*
X706576Y292957D01*
X707242Y293040D01*
X707742Y292957D01*
X708326Y292624D01*
X708576Y292124D01*
Y289707D01*
G01X711509Y291957D02*
X714176D01*
X713926Y292540D01*
X713509Y292874D01*
X712926Y293040D01*
X712342Y292957D01*
X711842Y292707D01*
X711509Y292124D01*
X711342Y291624D01*
Y291124D01*
X711509Y290624D01*
X711926Y290124D01*
X712426Y289790D01*
X713009Y289707D01*
X713592Y289874D01*
X714176Y290374D01*
G01X725459Y289707D02*
Y293040D01*
G01Y292457D02*
X725126Y292790D01*
X724626Y292957D01*
X724042Y293040D01*
X723459Y292874D01*
X722959Y292540D01*
X722626Y292040D01*
X722459Y291374D01*
X722626Y290707D01*
X722959Y290207D01*
X723459Y289874D01*
X724042Y289707D01*
X724626Y289790D01*
X725126Y290040D01*
X725459Y290374D01*
G01X728142Y289707D02*
Y293040D01*
G01Y292207D02*
X728476Y292624D01*
X728976Y292957D01*
X729642Y293040D01*
X730226Y292957D01*
X730726Y292624D01*
X730976Y292040D01*
Y289707D01*
G01X733742D02*
Y293040D01*
G01Y292207D02*
X734076Y292624D01*
X734576Y292957D01*
X735242Y293040D01*
X735826Y292957D01*
X736326Y292624D01*
X736576Y292040D01*
Y289707D01*
G01X739342Y293040D02*
Y290707D01*
X739676Y290124D01*
X740176Y289790D01*
X740759Y289707D01*
X741342Y289790D01*
X741842Y290124D01*
X742176Y290707D01*
G01Y289707D02*
Y293040D01*
G01X747859Y289707D02*
Y293040D01*
G01Y292457D02*
X747526Y292790D01*
X747026Y292957D01*
X746442Y293040D01*
X745859Y292874D01*
X745359Y292540D01*
X745026Y292040D01*
X744859Y291374D01*
X745026Y290707D01*
X745359Y290207D01*
X745859Y289874D01*
X746442Y289707D01*
X747026Y289790D01*
X747526Y290040D01*
X747859Y290374D01*
G01X751959Y289707D02*
Y294707D01*
G01X761992Y289707D02*
Y293040D01*
G01Y292374D02*
X762409Y292707D01*
X762826Y292957D01*
X763409Y293040D01*
X763826Y292957D01*
X764326Y292707D01*
G01X768759Y293040D02*
Y289707D01*
G01Y294374D02*
X768592Y294457D01*
Y294624D01*
X768759Y294707D01*
X768926Y294624D01*
Y294457D01*
X768759Y294374D01*
G01X772942Y289707D02*
Y293040D01*
G01Y292207D02*
X773276Y292624D01*
X773776Y292957D01*
X774442Y293040D01*
X775026Y292957D01*
X775526Y292624D01*
X775776Y292040D01*
Y289707D01*
G01X778792Y288457D02*
X779376Y288124D01*
X780042Y288040D01*
X780626Y288124D01*
X781126Y288540D01*
X781459Y289124D01*
Y293040D01*
G01Y292374D02*
X781126Y292707D01*
X780626Y292957D01*
X780042Y293040D01*
X779376Y292874D01*
X778959Y292540D01*
X778626Y291957D01*
X778459Y291374D01*
X778542Y290874D01*
X778876Y290290D01*
X779376Y289874D01*
X780042Y289707D01*
X780542Y289790D01*
X781126Y290124D01*
X781459Y290457D01*
G01X789909Y290290D02*
X790326Y289957D01*
X790909Y289707D01*
X791409D01*
X791909Y289874D01*
X792242Y290124D01*
X792409Y290457D01*
X792326Y290957D01*
X791992Y291207D01*
X790492Y291707D01*
X790159Y292290D01*
X790326Y292707D01*
X790659Y292957D01*
X791159Y293040D01*
X791659Y292957D01*
X792159Y292707D01*
G01X795342Y289707D02*
Y294707D01*
G01Y292290D02*
X795759Y292707D01*
X796176Y292957D01*
X796842Y293040D01*
X797342Y292957D01*
X797926Y292624D01*
X798176Y292124D01*
Y289707D01*
G01X802359D02*
X801859Y289790D01*
X801359Y290124D01*
X801026Y290707D01*
X800859Y291374D01*
X801026Y292040D01*
X801359Y292624D01*
X801859Y292957D01*
X802359Y293040D01*
X802859Y292957D01*
X803359Y292624D01*
X803692Y292040D01*
X803776Y291374D01*
X803692Y290707D01*
X803359Y290124D01*
X802859Y289790D01*
X802359Y289707D01*
G01X806542Y293040D02*
Y290707D01*
X806876Y290124D01*
X807376Y289790D01*
X807959Y289707D01*
X808542Y289790D01*
X809042Y290124D01*
X809376Y290707D01*
G01Y289707D02*
Y293040D01*
G01X813559Y289707D02*
Y294707D01*
G01X820659D02*
Y289707D01*
G01Y290457D02*
X820326Y290040D01*
X819826Y289790D01*
X819242Y289707D01*
X818576Y289874D01*
X818076Y290290D01*
X817742Y290790D01*
X817659Y291374D01*
X817742Y291957D01*
X818076Y292457D01*
X818576Y292874D01*
X819242Y293040D01*
X819826Y292957D01*
X820242Y292790D01*
X820659Y292457D01*
G01X527259Y303707D02*
Y308707D01*
G01Y306207D02*
X527676Y306707D01*
X528176Y306957D01*
X528676Y307040D01*
X529426Y306874D01*
X529926Y306540D01*
X530259Y305957D01*
Y305290D01*
X530092Y304624D01*
X529759Y304124D01*
X529176Y303790D01*
X528676Y303707D01*
X528176Y303790D01*
X527676Y304040D01*
X527259Y304457D01*
G01X533109Y305957D02*
X535776D01*
X535526Y306540D01*
X535109Y306874D01*
X534526Y307040D01*
X533942Y306957D01*
X533442Y306707D01*
X533109Y306124D01*
X532942Y305624D01*
Y305124D01*
X533109Y304624D01*
X533526Y304124D01*
X534026Y303790D01*
X534609Y303707D01*
X535192Y303874D01*
X535776Y304374D01*
G01X545559Y308707D02*
Y303707D01*
G01X544392Y307040D02*
X546726D01*
G01X549909Y305957D02*
X552576D01*
X552326Y306540D01*
X551909Y306874D01*
X551326Y307040D01*
X550742Y306957D01*
X550242Y306707D01*
X549909Y306124D01*
X549742Y305624D01*
Y305124D01*
X549909Y304624D01*
X550326Y304124D01*
X550826Y303790D01*
X551409Y303707D01*
X551992Y303874D01*
X552576Y304374D01*
G01X555342Y303707D02*
Y307040D01*
G01Y306207D02*
X555676Y306624D01*
X556176Y306957D01*
X556842Y307040D01*
X557426Y306957D01*
X557926Y306624D01*
X558176Y306040D01*
Y303707D01*
G01X562359Y308707D02*
Y303707D01*
G01X561192Y307040D02*
X563526D01*
G01X566709Y305957D02*
X569376D01*
X569126Y306540D01*
X568709Y306874D01*
X568126Y307040D01*
X567542Y306957D01*
X567042Y306707D01*
X566709Y306124D01*
X566542Y305624D01*
Y305124D01*
X566709Y304624D01*
X567126Y304124D01*
X567626Y303790D01*
X568209Y303707D01*
X568792Y303874D01*
X569376Y304374D01*
G01X575059Y308707D02*
Y303707D01*
G01Y304457D02*
X574726Y304040D01*
X574226Y303790D01*
X573642Y303707D01*
X572976Y303874D01*
X572476Y304290D01*
X572142Y304790D01*
X572059Y305374D01*
X572142Y305957D01*
X572476Y306457D01*
X572976Y306874D01*
X573642Y307040D01*
X574226Y306957D01*
X574642Y306790D01*
X575059Y306457D01*
G01X582676Y307040D02*
X583676Y303707D01*
X584759Y307040D01*
X585842Y303707D01*
X586842Y307040D01*
G01X590359D02*
Y303707D01*
G01Y308374D02*
X590192Y308457D01*
Y308624D01*
X590359Y308707D01*
X590526Y308624D01*
Y308457D01*
X590359Y308374D01*
G01X595959Y308707D02*
Y303707D01*
G01X594792Y307040D02*
X597126D01*
G01X600142Y303707D02*
Y308707D01*
G01Y306290D02*
X600559Y306707D01*
X600976Y306957D01*
X601642Y307040D01*
X602142Y306957D01*
X602726Y306624D01*
X602976Y306124D01*
Y303707D01*
G01X611509Y304290D02*
X611926Y303957D01*
X612509Y303707D01*
X613009D01*
X613509Y303874D01*
X613842Y304124D01*
X614009Y304457D01*
X613926Y304957D01*
X613592Y305207D01*
X612092Y305707D01*
X611759Y306290D01*
X611926Y306707D01*
X612259Y306957D01*
X612759Y307040D01*
X613259Y306957D01*
X613759Y306707D01*
G01X618359Y303707D02*
X617859Y303790D01*
X617359Y304124D01*
X617026Y304707D01*
X616859Y305374D01*
X617026Y306040D01*
X617359Y306624D01*
X617859Y306957D01*
X618359Y307040D01*
X618859Y306957D01*
X619359Y306624D01*
X619692Y306040D01*
X619776Y305374D01*
X619692Y304707D01*
X619359Y304124D01*
X618859Y303790D01*
X618359Y303707D01*
G01X623959D02*
Y308707D01*
G01X631059D02*
Y303707D01*
G01Y304457D02*
X630726Y304040D01*
X630226Y303790D01*
X629642Y303707D01*
X628976Y303874D01*
X628476Y304290D01*
X628142Y304790D01*
X628059Y305374D01*
X628142Y305957D01*
X628476Y306457D01*
X628976Y306874D01*
X629642Y307040D01*
X630226Y306957D01*
X630642Y306790D01*
X631059Y306457D01*
G01X633909Y305957D02*
X636576D01*
X636326Y306540D01*
X635909Y306874D01*
X635326Y307040D01*
X634742Y306957D01*
X634242Y306707D01*
X633909Y306124D01*
X633742Y305624D01*
Y305124D01*
X633909Y304624D01*
X634326Y304124D01*
X634826Y303790D01*
X635409Y303707D01*
X635992Y303874D01*
X636576Y304374D01*
G01X639592Y303707D02*
Y307040D01*
G01Y306374D02*
X640009Y306707D01*
X640426Y306957D01*
X641009Y307040D01*
X641426Y306957D01*
X641926Y306707D01*
G01X649459Y303707D02*
Y307040D01*
G01Y306124D02*
X649709Y306540D01*
X650126Y306874D01*
X650709Y307040D01*
X651292Y306874D01*
X651709Y306540D01*
X651959Y306124D01*
Y303707D01*
G01Y306124D02*
X652209Y306540D01*
X652626Y306874D01*
X653209Y307040D01*
X653792Y306874D01*
X654209Y306540D01*
X654459Y306040D01*
Y303707D01*
G01X659059D02*
Y307040D01*
G01Y306457D02*
X658726Y306790D01*
X658226Y306957D01*
X657642Y307040D01*
X657059Y306874D01*
X656559Y306540D01*
X656226Y306040D01*
X656059Y305374D01*
X656226Y304707D01*
X656559Y304207D01*
X657059Y303874D01*
X657642Y303707D01*
X658226Y303790D01*
X658726Y304040D01*
X659059Y304374D01*
G01X661909Y304290D02*
X662326Y303957D01*
X662909Y303707D01*
X663409D01*
X663909Y303874D01*
X664242Y304124D01*
X664409Y304457D01*
X664326Y304957D01*
X663992Y305207D01*
X662492Y305707D01*
X662159Y306290D01*
X662326Y306707D01*
X662659Y306957D01*
X663159Y307040D01*
X663659Y306957D01*
X664159Y306707D01*
G01X667342Y303707D02*
Y308707D01*
G01X670009Y307040D02*
X667342Y305124D01*
G01X668426Y305874D02*
X670176Y303707D01*
G01X674359Y303540D02*
X674192Y303624D01*
Y303790D01*
X674359Y303874D01*
X674526Y303790D01*
Y303624D01*
X674359Y303540D01*
G01X528759Y317707D02*
Y312707D01*
G01X527592Y316040D02*
X529926D01*
G01X534359Y312707D02*
X533859Y312790D01*
X533359Y313124D01*
X533026Y313707D01*
X532859Y314374D01*
X533026Y315040D01*
X533359Y315624D01*
X533859Y315957D01*
X534359Y316040D01*
X534859Y315957D01*
X535359Y315624D01*
X535692Y315040D01*
X535776Y314374D01*
X535692Y313707D01*
X535359Y313124D01*
X534859Y312790D01*
X534359Y312707D01*
G01X544059D02*
Y317707D01*
G01Y315207D02*
X544476Y315707D01*
X544976Y315957D01*
X545476Y316040D01*
X546226Y315874D01*
X546726Y315540D01*
X547059Y314957D01*
Y314290D01*
X546892Y313624D01*
X546559Y313124D01*
X545976Y312790D01*
X545476Y312707D01*
X544976Y312790D01*
X544476Y313040D01*
X544059Y313457D01*
G01X549909Y314957D02*
X552576D01*
X552326Y315540D01*
X551909Y315874D01*
X551326Y316040D01*
X550742Y315957D01*
X550242Y315707D01*
X549909Y315124D01*
X549742Y314624D01*
Y314124D01*
X549909Y313624D01*
X550326Y313124D01*
X550826Y312790D01*
X551409Y312707D01*
X551992Y312874D01*
X552576Y313374D01*
G01X563692Y315624D02*
X563109Y315957D01*
X562609Y316040D01*
X561942Y315874D01*
X561442Y315540D01*
X561109Y314957D01*
X561026Y314374D01*
X561109Y313790D01*
X561442Y313290D01*
X561942Y312874D01*
X562609Y312707D01*
X563192Y312874D01*
X563692Y313207D01*
G01X567959Y312707D02*
X567459Y312790D01*
X566959Y313124D01*
X566626Y313707D01*
X566459Y314374D01*
X566626Y315040D01*
X566959Y315624D01*
X567459Y315957D01*
X567959Y316040D01*
X568459Y315957D01*
X568959Y315624D01*
X569292Y315040D01*
X569376Y314374D01*
X569292Y313707D01*
X568959Y313124D01*
X568459Y312790D01*
X567959Y312707D01*
G01X572059Y316040D02*
X573559Y312707D01*
X575059Y316040D01*
G01X577909Y314957D02*
X580576D01*
X580326Y315540D01*
X579909Y315874D01*
X579326Y316040D01*
X578742Y315957D01*
X578242Y315707D01*
X577909Y315124D01*
X577742Y314624D01*
Y314124D01*
X577909Y313624D01*
X578326Y313124D01*
X578826Y312790D01*
X579409Y312707D01*
X579992Y312874D01*
X580576Y313374D01*
G01X583592Y312707D02*
Y316040D01*
G01Y315374D02*
X584009Y315707D01*
X584426Y315957D01*
X585009Y316040D01*
X585426Y315957D01*
X585926Y315707D01*
G01X589109Y314957D02*
X591776D01*
X591526Y315540D01*
X591109Y315874D01*
X590526Y316040D01*
X589942Y315957D01*
X589442Y315707D01*
X589109Y315124D01*
X588942Y314624D01*
Y314124D01*
X589109Y313624D01*
X589526Y313124D01*
X590026Y312790D01*
X590609Y312707D01*
X591192Y312874D01*
X591776Y313374D01*
G01X597459Y317707D02*
Y312707D01*
G01Y313457D02*
X597126Y313040D01*
X596626Y312790D01*
X596042Y312707D01*
X595376Y312874D01*
X594876Y313290D01*
X594542Y313790D01*
X594459Y314374D01*
X594542Y314957D01*
X594876Y315457D01*
X595376Y315874D01*
X596042Y316040D01*
X596626Y315957D01*
X597042Y315790D01*
X597459Y315457D01*
G01X605659Y312707D02*
Y317707D01*
G01Y315207D02*
X606076Y315707D01*
X606576Y315957D01*
X607076Y316040D01*
X607826Y315874D01*
X608326Y315540D01*
X608659Y314957D01*
Y314290D01*
X608492Y313624D01*
X608159Y313124D01*
X607576Y312790D01*
X607076Y312707D01*
X606576Y312790D01*
X606076Y313040D01*
X605659Y313457D01*
G01X611009Y311207D02*
X611509Y311040D01*
X612176Y311207D01*
X612592Y311540D01*
X612926Y311957D01*
X613426Y313290D01*
X614509Y316040D01*
G01X611842D02*
X613426Y313290D01*
G01X622709D02*
X623126Y312957D01*
X623709Y312707D01*
X624209D01*
X624709Y312874D01*
X625042Y313124D01*
X625209Y313457D01*
X625126Y313957D01*
X624792Y314207D01*
X623292Y314707D01*
X622959Y315290D01*
X623126Y315707D01*
X623459Y315957D01*
X623959Y316040D01*
X624459Y315957D01*
X624959Y315707D01*
G01X629559Y312707D02*
X629059Y312790D01*
X628559Y313124D01*
X628226Y313707D01*
X628059Y314374D01*
X628226Y315040D01*
X628559Y315624D01*
X629059Y315957D01*
X629559Y316040D01*
X630059Y315957D01*
X630559Y315624D01*
X630892Y315040D01*
X630976Y314374D01*
X630892Y313707D01*
X630559Y313124D01*
X630059Y312790D01*
X629559Y312707D01*
G01X635159D02*
Y317707D01*
G01X642259D02*
Y312707D01*
G01Y313457D02*
X641926Y313040D01*
X641426Y312790D01*
X640842Y312707D01*
X640176Y312874D01*
X639676Y313290D01*
X639342Y313790D01*
X639259Y314374D01*
X639342Y314957D01*
X639676Y315457D01*
X640176Y315874D01*
X640842Y316040D01*
X641426Y315957D01*
X641842Y315790D01*
X642259Y315457D01*
G01X645109Y314957D02*
X647776D01*
X647526Y315540D01*
X647109Y315874D01*
X646526Y316040D01*
X645942Y315957D01*
X645442Y315707D01*
X645109Y315124D01*
X644942Y314624D01*
Y314124D01*
X645109Y313624D01*
X645526Y313124D01*
X646026Y312790D01*
X646609Y312707D01*
X647192Y312874D01*
X647776Y313374D01*
G01X650792Y312707D02*
Y316040D01*
G01Y315374D02*
X651209Y315707D01*
X651626Y315957D01*
X652209Y316040D01*
X652626Y315957D01*
X653126Y315707D01*
G01X660659Y312707D02*
Y316040D01*
G01Y315124D02*
X660909Y315540D01*
X661326Y315874D01*
X661909Y316040D01*
X662492Y315874D01*
X662909Y315540D01*
X663159Y315124D01*
Y312707D01*
G01Y315124D02*
X663409Y315540D01*
X663826Y315874D01*
X664409Y316040D01*
X664992Y315874D01*
X665409Y315540D01*
X665659Y315040D01*
Y312707D01*
G01X670259D02*
Y316040D01*
G01Y315457D02*
X669926Y315790D01*
X669426Y315957D01*
X668842Y316040D01*
X668259Y315874D01*
X667759Y315540D01*
X667426Y315040D01*
X667259Y314374D01*
X667426Y313707D01*
X667759Y313207D01*
X668259Y312874D01*
X668842Y312707D01*
X669426Y312790D01*
X669926Y313040D01*
X670259Y313374D01*
G01X673109Y313290D02*
X673526Y312957D01*
X674109Y312707D01*
X674609D01*
X675109Y312874D01*
X675442Y313124D01*
X675609Y313457D01*
X675526Y313957D01*
X675192Y314207D01*
X673692Y314707D01*
X673359Y315290D01*
X673526Y315707D01*
X673859Y315957D01*
X674359Y316040D01*
X674859Y315957D01*
X675359Y315707D01*
G01X678542Y312707D02*
Y317707D01*
G01X681209Y316040D02*
X678542Y314124D01*
G01X679626Y314874D02*
X681376Y312707D01*
G01X692659D02*
Y316040D01*
G01Y315457D02*
X692326Y315790D01*
X691826Y315957D01*
X691242Y316040D01*
X690659Y315874D01*
X690159Y315540D01*
X689826Y315040D01*
X689659Y314374D01*
X689826Y313707D01*
X690159Y313207D01*
X690659Y312874D01*
X691242Y312707D01*
X691826Y312790D01*
X692326Y313040D01*
X692659Y313374D01*
G01X695342Y312707D02*
Y316040D01*
G01Y315207D02*
X695676Y315624D01*
X696176Y315957D01*
X696842Y316040D01*
X697426Y315957D01*
X697926Y315624D01*
X698176Y315040D01*
Y312707D01*
G01X703859Y317707D02*
Y312707D01*
G01Y313457D02*
X703526Y313040D01*
X703026Y312790D01*
X702442Y312707D01*
X701776Y312874D01*
X701276Y313290D01*
X700942Y313790D01*
X700859Y314374D01*
X700942Y314957D01*
X701276Y315457D01*
X701776Y315874D01*
X702442Y316040D01*
X703026Y315957D01*
X703442Y315790D01*
X703859Y315457D01*
G01X712142Y312707D02*
Y317707D01*
G01Y315290D02*
X712559Y315707D01*
X712976Y315957D01*
X713642Y316040D01*
X714142Y315957D01*
X714726Y315624D01*
X714976Y315124D01*
Y312707D01*
G01X719159D02*
X718659Y312790D01*
X718159Y313124D01*
X717826Y313707D01*
X717659Y314374D01*
X717826Y315040D01*
X718159Y315624D01*
X718659Y315957D01*
X719159Y316040D01*
X719659Y315957D01*
X720159Y315624D01*
X720492Y315040D01*
X720576Y314374D01*
X720492Y313707D01*
X720159Y313124D01*
X719659Y312790D01*
X719159Y312707D01*
G01X724759D02*
Y317707D01*
G01X729109Y314957D02*
X731776D01*
X731526Y315540D01*
X731109Y315874D01*
X730526Y316040D01*
X729942Y315957D01*
X729442Y315707D01*
X729109Y315124D01*
X728942Y314624D01*
Y314124D01*
X729109Y313624D01*
X729526Y313124D01*
X730026Y312790D01*
X730609Y312707D01*
X731192Y312874D01*
X731776Y313374D01*
G01X743059Y312707D02*
Y316040D01*
G01Y315457D02*
X742726Y315790D01*
X742226Y315957D01*
X741642Y316040D01*
X741059Y315874D01*
X740559Y315540D01*
X740226Y315040D01*
X740059Y314374D01*
X740226Y313707D01*
X740559Y313207D01*
X741059Y312874D01*
X741642Y312707D01*
X742226Y312790D01*
X742726Y313040D01*
X743059Y313374D01*
G01X747159Y312707D02*
Y317707D01*
G01X751509Y313290D02*
X751926Y312957D01*
X752509Y312707D01*
X753009D01*
X753509Y312874D01*
X753842Y313124D01*
X754009Y313457D01*
X753926Y313957D01*
X753592Y314207D01*
X752092Y314707D01*
X751759Y315290D01*
X751926Y315707D01*
X752259Y315957D01*
X752759Y316040D01*
X753259Y315957D01*
X753759Y315707D01*
G01X758359Y312707D02*
X757859Y312790D01*
X757359Y313124D01*
X757026Y313707D01*
X756859Y314374D01*
X757026Y315040D01*
X757359Y315624D01*
X757859Y315957D01*
X758359Y316040D01*
X758859Y315957D01*
X759359Y315624D01*
X759692Y315040D01*
X759776Y314374D01*
X759692Y313707D01*
X759359Y313124D01*
X758859Y312790D01*
X758359Y312707D01*
G01X768142D02*
Y316040D01*
G01Y315207D02*
X768476Y315624D01*
X768976Y315957D01*
X769642Y316040D01*
X770226Y315957D01*
X770726Y315624D01*
X770976Y315040D01*
Y312707D01*
G01X773909Y314957D02*
X776576D01*
X776326Y315540D01*
X775909Y315874D01*
X775326Y316040D01*
X774742Y315957D01*
X774242Y315707D01*
X773909Y315124D01*
X773742Y314624D01*
Y314124D01*
X773909Y313624D01*
X774326Y313124D01*
X774826Y312790D01*
X775409Y312707D01*
X775992Y312874D01*
X776576Y313374D01*
G01X779509Y314957D02*
X782176D01*
X781926Y315540D01*
X781509Y315874D01*
X780926Y316040D01*
X780342Y315957D01*
X779842Y315707D01*
X779509Y315124D01*
X779342Y314624D01*
Y314124D01*
X779509Y313624D01*
X779926Y313124D01*
X780426Y312790D01*
X781009Y312707D01*
X781592Y312874D01*
X782176Y313374D01*
G01X787859Y317707D02*
Y312707D01*
G01Y313457D02*
X787526Y313040D01*
X787026Y312790D01*
X786442Y312707D01*
X785776Y312874D01*
X785276Y313290D01*
X784942Y313790D01*
X784859Y314374D01*
X784942Y314957D01*
X785276Y315457D01*
X785776Y315874D01*
X786442Y316040D01*
X787026Y315957D01*
X787442Y315790D01*
X787859Y315457D01*
G01X797559Y317707D02*
Y312707D01*
G01X796392Y316040D02*
X798726D01*
G01X803159Y312707D02*
X802659Y312790D01*
X802159Y313124D01*
X801826Y313707D01*
X801659Y314374D01*
X801826Y315040D01*
X802159Y315624D01*
X802659Y315957D01*
X803159Y316040D01*
X803659Y315957D01*
X804159Y315624D01*
X804492Y315040D01*
X804576Y314374D01*
X804492Y313707D01*
X804159Y313124D01*
X803659Y312790D01*
X803159Y312707D01*
G01X516759Y320707D02*
Y325707D01*
X515759Y324707D01*
G01Y320707D02*
X517759D01*
G01X522359Y320540D02*
X522192Y320624D01*
Y320790D01*
X522359Y320874D01*
X522526Y320790D01*
Y320624D01*
X522359Y320540D01*
G01X527959Y325707D02*
Y320707D01*
G01X526042Y325707D02*
X529876D01*
G01X532142Y320707D02*
Y325707D01*
G01Y323290D02*
X532559Y323707D01*
X532976Y323957D01*
X533642Y324040D01*
X534142Y323957D01*
X534726Y323624D01*
X534976Y323124D01*
Y320707D01*
G01X537909Y322957D02*
X540576D01*
X540326Y323540D01*
X539909Y323874D01*
X539326Y324040D01*
X538742Y323957D01*
X538242Y323707D01*
X537909Y323124D01*
X537742Y322624D01*
Y322124D01*
X537909Y321624D01*
X538326Y321124D01*
X538826Y320790D01*
X539409Y320707D01*
X539992Y320874D01*
X540576Y321374D01*
G01X549109Y321290D02*
X549526Y320957D01*
X550109Y320707D01*
X550609D01*
X551109Y320874D01*
X551442Y321124D01*
X551609Y321457D01*
X551526Y321957D01*
X551192Y322207D01*
X549692Y322707D01*
X549359Y323290D01*
X549526Y323707D01*
X549859Y323957D01*
X550359Y324040D01*
X550859Y323957D01*
X551359Y323707D01*
G01X555959Y324040D02*
Y320707D01*
G01Y325374D02*
X555792Y325457D01*
Y325624D01*
X555959Y325707D01*
X556126Y325624D01*
Y325457D01*
X555959Y325374D01*
G01X563059Y325707D02*
Y320707D01*
G01Y321457D02*
X562726Y321040D01*
X562226Y320790D01*
X561642Y320707D01*
X560976Y320874D01*
X560476Y321290D01*
X560142Y321790D01*
X560059Y322374D01*
X560142Y322957D01*
X560476Y323457D01*
X560976Y323874D01*
X561642Y324040D01*
X562226Y323957D01*
X562642Y323790D01*
X563059Y323457D01*
G01X565909Y322957D02*
X568576D01*
X568326Y323540D01*
X567909Y323874D01*
X567326Y324040D01*
X566742Y323957D01*
X566242Y323707D01*
X565909Y323124D01*
X565742Y322624D01*
Y322124D01*
X565909Y321624D01*
X566326Y321124D01*
X566826Y320790D01*
X567409Y320707D01*
X567992Y320874D01*
X568576Y321374D01*
G01X576276Y324040D02*
X577276Y320707D01*
X578359Y324040D01*
X579442Y320707D01*
X580442Y324040D01*
G01X583959D02*
Y320707D01*
G01Y325374D02*
X583792Y325457D01*
Y325624D01*
X583959Y325707D01*
X584126Y325624D01*
Y325457D01*
X583959Y325374D01*
G01X589559Y325707D02*
Y320707D01*
G01X588392Y324040D02*
X590726D01*
G01X593742Y320707D02*
Y325707D01*
G01Y323290D02*
X594159Y323707D01*
X594576Y323957D01*
X595242Y324040D01*
X595742Y323957D01*
X596326Y323624D01*
X596576Y323124D01*
Y320707D01*
G01X600759D02*
X600259Y320790D01*
X599759Y321124D01*
X599426Y321707D01*
X599259Y322374D01*
X599426Y323040D01*
X599759Y323624D01*
X600259Y323957D01*
X600759Y324040D01*
X601259Y323957D01*
X601759Y323624D01*
X602092Y323040D01*
X602176Y322374D01*
X602092Y321707D01*
X601759Y321124D01*
X601259Y320790D01*
X600759Y320707D01*
G01X604942Y324040D02*
Y321707D01*
X605276Y321124D01*
X605776Y320790D01*
X606359Y320707D01*
X606942Y320790D01*
X607442Y321124D01*
X607776Y321707D01*
G01Y320707D02*
Y324040D01*
G01X611959Y325707D02*
Y320707D01*
G01X610792Y324040D02*
X613126D01*
G01X621909Y321290D02*
X622326Y320957D01*
X622909Y320707D01*
X623409D01*
X623909Y320874D01*
X624242Y321124D01*
X624409Y321457D01*
X624326Y321957D01*
X623992Y322207D01*
X622492Y322707D01*
X622159Y323290D01*
X622326Y323707D01*
X622659Y323957D01*
X623159Y324040D01*
X623659Y323957D01*
X624159Y323707D01*
G01X628759Y320707D02*
X628259Y320790D01*
X627759Y321124D01*
X627426Y321707D01*
X627259Y322374D01*
X627426Y323040D01*
X627759Y323624D01*
X628259Y323957D01*
X628759Y324040D01*
X629259Y323957D01*
X629759Y323624D01*
X630092Y323040D01*
X630176Y322374D01*
X630092Y321707D01*
X629759Y321124D01*
X629259Y320790D01*
X628759Y320707D01*
G01X634359D02*
Y325707D01*
G01X641459D02*
Y320707D01*
G01Y321457D02*
X641126Y321040D01*
X640626Y320790D01*
X640042Y320707D01*
X639376Y320874D01*
X638876Y321290D01*
X638542Y321790D01*
X638459Y322374D01*
X638542Y322957D01*
X638876Y323457D01*
X639376Y323874D01*
X640042Y324040D01*
X640626Y323957D01*
X641042Y323790D01*
X641459Y323457D01*
G01X644309Y322957D02*
X646976D01*
X646726Y323540D01*
X646309Y323874D01*
X645726Y324040D01*
X645142Y323957D01*
X644642Y323707D01*
X644309Y323124D01*
X644142Y322624D01*
Y322124D01*
X644309Y321624D01*
X644726Y321124D01*
X645226Y320790D01*
X645809Y320707D01*
X646392Y320874D01*
X646976Y321374D01*
G01X649992Y320707D02*
Y324040D01*
G01Y323374D02*
X650409Y323707D01*
X650826Y323957D01*
X651409Y324040D01*
X651826Y323957D01*
X652326Y323707D01*
G01X659859Y320707D02*
Y324040D01*
G01Y323124D02*
X660109Y323540D01*
X660526Y323874D01*
X661109Y324040D01*
X661692Y323874D01*
X662109Y323540D01*
X662359Y323124D01*
Y320707D01*
G01Y323124D02*
X662609Y323540D01*
X663026Y323874D01*
X663609Y324040D01*
X664192Y323874D01*
X664609Y323540D01*
X664859Y323040D01*
Y320707D01*
G01X669459D02*
Y324040D01*
G01Y323457D02*
X669126Y323790D01*
X668626Y323957D01*
X668042Y324040D01*
X667459Y323874D01*
X666959Y323540D01*
X666626Y323040D01*
X666459Y322374D01*
X666626Y321707D01*
X666959Y321207D01*
X667459Y320874D01*
X668042Y320707D01*
X668626Y320790D01*
X669126Y321040D01*
X669459Y321374D01*
G01X672309Y321290D02*
X672726Y320957D01*
X673309Y320707D01*
X673809D01*
X674309Y320874D01*
X674642Y321124D01*
X674809Y321457D01*
X674726Y321957D01*
X674392Y322207D01*
X672892Y322707D01*
X672559Y323290D01*
X672726Y323707D01*
X673059Y323957D01*
X673559Y324040D01*
X674059Y323957D01*
X674559Y323707D01*
G01X677742Y320707D02*
Y325707D01*
G01X680409Y324040D02*
X677742Y322124D01*
G01X678826Y322874D02*
X680576Y320707D01*
G01X688859Y319040D02*
Y324040D01*
G01Y323290D02*
X689276Y323707D01*
X689692Y323957D01*
X690359Y324040D01*
X690942Y323957D01*
X691526Y323540D01*
X691776Y322957D01*
X691859Y322374D01*
X691776Y321790D01*
X691526Y321207D01*
X691026Y320874D01*
X690359Y320707D01*
X689776Y320790D01*
X689192Y321040D01*
X688859Y321374D01*
G01X697459Y320707D02*
Y324040D01*
G01Y323457D02*
X697126Y323790D01*
X696626Y323957D01*
X696042Y324040D01*
X695459Y323874D01*
X694959Y323540D01*
X694626Y323040D01*
X694459Y322374D01*
X694626Y321707D01*
X694959Y321207D01*
X695459Y320874D01*
X696042Y320707D01*
X696626Y320790D01*
X697126Y321040D01*
X697459Y321374D01*
G01X703059Y325707D02*
Y320707D01*
G01Y321457D02*
X702726Y321040D01*
X702226Y320790D01*
X701642Y320707D01*
X700976Y320874D01*
X700476Y321290D01*
X700142Y321790D01*
X700059Y322374D01*
X700142Y322957D01*
X700476Y323457D01*
X700976Y323874D01*
X701642Y324040D01*
X702226Y323957D01*
X702642Y323790D01*
X703059Y323457D01*
G01X712592Y319790D02*
X712926Y320874D01*
G01X725459Y320707D02*
Y324040D01*
G01Y323457D02*
X725126Y323790D01*
X724626Y323957D01*
X724042Y324040D01*
X723459Y323874D01*
X722959Y323540D01*
X722626Y323040D01*
X722459Y322374D01*
X722626Y321707D01*
X722959Y321207D01*
X723459Y320874D01*
X724042Y320707D01*
X724626Y320790D01*
X725126Y321040D01*
X725459Y321374D01*
G01X728142Y320707D02*
Y324040D01*
G01Y323207D02*
X728476Y323624D01*
X728976Y323957D01*
X729642Y324040D01*
X730226Y323957D01*
X730726Y323624D01*
X730976Y323040D01*
Y320707D01*
G01X733742D02*
Y324040D01*
G01Y323207D02*
X734076Y323624D01*
X734576Y323957D01*
X735242Y324040D01*
X735826Y323957D01*
X736326Y323624D01*
X736576Y323040D01*
Y320707D01*
G01X739342Y324040D02*
Y321707D01*
X739676Y321124D01*
X740176Y320790D01*
X740759Y320707D01*
X741342Y320790D01*
X741842Y321124D01*
X742176Y321707D01*
G01Y320707D02*
Y324040D01*
G01X747859Y320707D02*
Y324040D01*
G01Y323457D02*
X747526Y323790D01*
X747026Y323957D01*
X746442Y324040D01*
X745859Y323874D01*
X745359Y323540D01*
X745026Y323040D01*
X744859Y322374D01*
X745026Y321707D01*
X745359Y321207D01*
X745859Y320874D01*
X746442Y320707D01*
X747026Y320790D01*
X747526Y321040D01*
X747859Y321374D01*
G01X751959Y320707D02*
Y325707D01*
G01X761992Y320707D02*
Y324040D01*
G01Y323374D02*
X762409Y323707D01*
X762826Y323957D01*
X763409Y324040D01*
X763826Y323957D01*
X764326Y323707D01*
G01X768759Y324040D02*
Y320707D01*
G01Y325374D02*
X768592Y325457D01*
Y325624D01*
X768759Y325707D01*
X768926Y325624D01*
Y325457D01*
X768759Y325374D01*
G01X772942Y320707D02*
Y324040D01*
G01Y323207D02*
X773276Y323624D01*
X773776Y323957D01*
X774442Y324040D01*
X775026Y323957D01*
X775526Y323624D01*
X775776Y323040D01*
Y320707D01*
G01X778792Y319457D02*
X779376Y319124D01*
X780042Y319040D01*
X780626Y319124D01*
X781126Y319540D01*
X781459Y320124D01*
Y324040D01*
G01Y323374D02*
X781126Y323707D01*
X780626Y323957D01*
X780042Y324040D01*
X779376Y323874D01*
X778959Y323540D01*
X778626Y322957D01*
X778459Y322374D01*
X778542Y321874D01*
X778876Y321290D01*
X779376Y320874D01*
X780042Y320707D01*
X780542Y320790D01*
X781126Y321124D01*
X781459Y321457D01*
G01X789742Y320707D02*
Y324040D01*
G01Y323207D02*
X790076Y323624D01*
X790576Y323957D01*
X791242Y324040D01*
X791826Y323957D01*
X792326Y323624D01*
X792576Y323040D01*
Y320707D01*
G01X795509Y322957D02*
X798176D01*
X797926Y323540D01*
X797509Y323874D01*
X796926Y324040D01*
X796342Y323957D01*
X795842Y323707D01*
X795509Y323124D01*
X795342Y322624D01*
Y322124D01*
X795509Y321624D01*
X795926Y321124D01*
X796426Y320790D01*
X797009Y320707D01*
X797592Y320874D01*
X798176Y321374D01*
G01X801109Y322957D02*
X803776D01*
X803526Y323540D01*
X803109Y323874D01*
X802526Y324040D01*
X801942Y323957D01*
X801442Y323707D01*
X801109Y323124D01*
X800942Y322624D01*
Y322124D01*
X801109Y321624D01*
X801526Y321124D01*
X802026Y320790D01*
X802609Y320707D01*
X803192Y320874D01*
X803776Y321374D01*
G01X809459Y325707D02*
Y320707D01*
G01Y321457D02*
X809126Y321040D01*
X808626Y320790D01*
X808042Y320707D01*
X807376Y320874D01*
X806876Y321290D01*
X806542Y321790D01*
X806459Y322374D01*
X806542Y322957D01*
X806876Y323457D01*
X807376Y323874D01*
X808042Y324040D01*
X808626Y323957D01*
X809042Y323790D01*
X809459Y323457D01*
G01X506842Y481707D02*
Y485040D01*
G01Y484207D02*
X507176Y484624D01*
X507676Y484957D01*
X508342Y485040D01*
X508926Y484957D01*
X509426Y484624D01*
X509676Y484040D01*
Y481707D01*
G01X513859D02*
X513359Y481790D01*
X512859Y482124D01*
X512526Y482707D01*
X512359Y483374D01*
X512526Y484040D01*
X512859Y484624D01*
X513359Y484957D01*
X513859Y485040D01*
X514359Y484957D01*
X514859Y484624D01*
X515192Y484040D01*
X515276Y483374D01*
X515192Y482707D01*
X514859Y482124D01*
X514359Y481790D01*
X513859Y481707D01*
G01X523559Y480040D02*
Y485040D01*
G01Y484290D02*
X523976Y484707D01*
X524392Y484957D01*
X525059Y485040D01*
X525642Y484957D01*
X526226Y484540D01*
X526476Y483957D01*
X526559Y483374D01*
X526476Y482790D01*
X526226Y482207D01*
X525726Y481874D01*
X525059Y481707D01*
X524476Y481790D01*
X523892Y482040D01*
X523559Y482374D01*
G01X530659Y481707D02*
Y486707D01*
G01X534842Y485040D02*
Y482707D01*
X535176Y482124D01*
X535676Y481790D01*
X536259Y481707D01*
X536842Y481790D01*
X537342Y482124D01*
X537676Y482707D01*
G01Y481707D02*
Y485040D01*
G01X540692Y480457D02*
X541276Y480124D01*
X541942Y480040D01*
X542526Y480124D01*
X543026Y480540D01*
X543359Y481124D01*
Y485040D01*
G01Y484374D02*
X543026Y484707D01*
X542526Y484957D01*
X541942Y485040D01*
X541276Y484874D01*
X540859Y484540D01*
X540526Y483957D01*
X540359Y483374D01*
X540442Y482874D01*
X540776Y482290D01*
X541276Y481874D01*
X541942Y481707D01*
X542442Y481790D01*
X543026Y482124D01*
X543359Y482457D01*
G01X546292Y480457D02*
X546876Y480124D01*
X547542Y480040D01*
X548126Y480124D01*
X548626Y480540D01*
X548959Y481124D01*
Y485040D01*
G01Y484374D02*
X548626Y484707D01*
X548126Y484957D01*
X547542Y485040D01*
X546876Y484874D01*
X546459Y484540D01*
X546126Y483957D01*
X545959Y483374D01*
X546042Y482874D01*
X546376Y482290D01*
X546876Y481874D01*
X547542Y481707D01*
X548042Y481790D01*
X548626Y482124D01*
X548959Y482457D01*
G01X553059Y485040D02*
Y481707D01*
G01Y486374D02*
X552892Y486457D01*
Y486624D01*
X553059Y486707D01*
X553226Y486624D01*
Y486457D01*
X553059Y486374D01*
G01X557242Y481707D02*
Y485040D01*
G01Y484207D02*
X557576Y484624D01*
X558076Y484957D01*
X558742Y485040D01*
X559326Y484957D01*
X559826Y484624D01*
X560076Y484040D01*
Y481707D01*
G01X563092Y480457D02*
X563676Y480124D01*
X564342Y480040D01*
X564926Y480124D01*
X565426Y480540D01*
X565759Y481124D01*
Y485040D01*
G01Y484374D02*
X565426Y484707D01*
X564926Y484957D01*
X564342Y485040D01*
X563676Y484874D01*
X563259Y484540D01*
X562926Y483957D01*
X562759Y483374D01*
X562842Y482874D01*
X563176Y482290D01*
X563676Y481874D01*
X564342Y481707D01*
X564842Y481790D01*
X565426Y482124D01*
X565759Y482457D01*
G01X582426Y-124793D02*
Y-119793D01*
X584092D01*
X584759Y-120043D01*
X585259Y-120376D01*
X585676Y-120876D01*
X586009Y-121460D01*
X586092Y-122293D01*
X586009Y-123126D01*
X585676Y-123710D01*
X585259Y-124210D01*
X584759Y-124543D01*
X584092Y-124793D01*
X582426D01*
G01X588692D02*
Y-121460D01*
G01Y-122126D02*
X589109Y-121793D01*
X589526Y-121543D01*
X590109Y-121460D01*
X590526Y-121543D01*
X591026Y-121793D01*
G01X595459Y-121460D02*
Y-124793D01*
G01Y-120126D02*
X595292Y-120043D01*
Y-119876D01*
X595459Y-119793D01*
X595626Y-119876D01*
Y-120043D01*
X595459Y-120126D01*
G01X601059Y-124793D02*
Y-119793D01*
G01X606659Y-124793D02*
Y-119793D01*
G01X616276Y-124793D02*
Y-119793D01*
X619442D01*
G01X618276Y-122210D02*
X616276D01*
G01X622292Y-124793D02*
Y-121460D01*
G01Y-122126D02*
X622709Y-121793D01*
X623126Y-121543D01*
X623709Y-121460D01*
X624126Y-121543D01*
X624626Y-121793D01*
G01X629059Y-124793D02*
X628559Y-124710D01*
X628059Y-124376D01*
X627726Y-123793D01*
X627559Y-123126D01*
X627726Y-122460D01*
X628059Y-121876D01*
X628559Y-121543D01*
X629059Y-121460D01*
X629559Y-121543D01*
X630059Y-121876D01*
X630392Y-122460D01*
X630476Y-123126D01*
X630392Y-123793D01*
X630059Y-124376D01*
X629559Y-124710D01*
X629059Y-124793D01*
G01X632159D02*
Y-121460D01*
G01Y-122376D02*
X632409Y-121960D01*
X632826Y-121626D01*
X633409Y-121460D01*
X633992Y-121626D01*
X634409Y-121960D01*
X634659Y-122376D01*
Y-124793D01*
G01Y-122376D02*
X634909Y-121960D01*
X635326Y-121626D01*
X635909Y-121460D01*
X636492Y-121626D01*
X636909Y-121960D01*
X637159Y-122460D01*
Y-124793D01*
G01X662242Y-126460D02*
X661409Y-125626D01*
X660992Y-124793D01*
Y-121460D01*
X661409Y-120626D01*
X662242Y-119793D01*
G01X668926Y-122126D02*
X669259Y-121876D01*
X669509Y-121460D01*
X669676Y-120876D01*
X669509Y-120376D01*
X669176Y-120043D01*
X668592Y-119793D01*
X666342D01*
Y-124793D01*
X669092D01*
X669676Y-124460D01*
X670009Y-123960D01*
X670176Y-123376D01*
X670009Y-122793D01*
X669509Y-122293D01*
X668926Y-122126D01*
X666342D01*
G01X673859Y-124793D02*
X673192Y-124710D01*
X672609Y-124376D01*
X672109Y-123876D01*
X671776Y-123293D01*
X671609Y-122626D01*
Y-121960D01*
X671776Y-121293D01*
X672109Y-120710D01*
X672609Y-120210D01*
X673192Y-119876D01*
X673859Y-119793D01*
X674526Y-119876D01*
X675109Y-120210D01*
X675609Y-120710D01*
X675942Y-121293D01*
X676109Y-121960D01*
Y-122626D01*
X675942Y-123293D01*
X675609Y-123876D01*
X675109Y-124376D01*
X674526Y-124710D01*
X673859Y-124793D01*
G01X679459Y-119793D02*
Y-124793D01*
G01X677542Y-119793D02*
X681376D01*
G01X685059D02*
Y-124793D01*
G01X683142Y-119793D02*
X686976D01*
G01X690659Y-124793D02*
X689992Y-124710D01*
X689409Y-124376D01*
X688909Y-123876D01*
X688576Y-123293D01*
X688409Y-122626D01*
Y-121960D01*
X688576Y-121293D01*
X688909Y-120710D01*
X689409Y-120210D01*
X689992Y-119876D01*
X690659Y-119793D01*
X691326Y-119876D01*
X691909Y-120210D01*
X692409Y-120710D01*
X692742Y-121293D01*
X692909Y-121960D01*
Y-122626D01*
X692742Y-123293D01*
X692409Y-123876D01*
X691909Y-124376D01*
X691326Y-124710D01*
X690659Y-124793D01*
G01X694092D02*
Y-119793D01*
X696259Y-123960D01*
X698426Y-119793D01*
Y-124793D01*
G01X702276Y-126460D02*
X703109Y-125626D01*
X703526Y-124793D01*
Y-121460D01*
X703109Y-120626D01*
X702276Y-119793D01*
G01X713059D02*
Y-124793D01*
G01X711892Y-121460D02*
X714226D01*
G01X718659Y-124793D02*
X718159Y-124710D01*
X717659Y-124376D01*
X717326Y-123793D01*
X717159Y-123126D01*
X717326Y-122460D01*
X717659Y-121876D01*
X718159Y-121543D01*
X718659Y-121460D01*
X719159Y-121543D01*
X719659Y-121876D01*
X719992Y-122460D01*
X720076Y-123126D01*
X719992Y-123793D01*
X719659Y-124376D01*
X719159Y-124710D01*
X718659Y-124793D01*
G01X728192Y-119793D02*
Y-124793D01*
X731526D01*
G01X734209Y-121460D02*
X736709Y-124793D01*
G01Y-121460D02*
X734209Y-124793D01*
G01X584252Y-144093D02*
Y-149093D01*
X587586D01*
G01X590269Y-145760D02*
X592769Y-149093D01*
G01Y-145760D02*
X590269Y-149093D01*
G01X597119Y-149260D02*
X596952Y-149176D01*
Y-149010D01*
X597119Y-148926D01*
X597286Y-149010D01*
Y-149176D01*
X597119Y-149260D01*
G01Y-147010D02*
X596952Y-146926D01*
Y-146760D01*
X597119Y-146676D01*
X597286Y-146760D01*
Y-146926D01*
X597119Y-147010D01*
G01X605819Y-149093D02*
Y-145760D01*
G01Y-146676D02*
X606069Y-146260D01*
X606486Y-145926D01*
X607069Y-145760D01*
X607652Y-145926D01*
X608069Y-146260D01*
X608319Y-146676D01*
Y-149093D01*
G01Y-146676D02*
X608569Y-146260D01*
X608986Y-145926D01*
X609569Y-145760D01*
X610152Y-145926D01*
X610569Y-146260D01*
X610819Y-146760D01*
Y-149093D01*
G01X612502Y-145760D02*
Y-148093D01*
X612836Y-148676D01*
X613336Y-149010D01*
X613919Y-149093D01*
X614502Y-149010D01*
X615002Y-148676D01*
X615336Y-148093D01*
G01Y-149093D02*
Y-145760D01*
G01X618269Y-148510D02*
X618686Y-148843D01*
X619269Y-149093D01*
X619769D01*
X620269Y-148926D01*
X620602Y-148676D01*
X620769Y-148343D01*
X620686Y-147843D01*
X620352Y-147593D01*
X618852Y-147093D01*
X618519Y-146510D01*
X618686Y-146093D01*
X619019Y-145843D01*
X619519Y-145760D01*
X620019Y-145843D01*
X620519Y-146093D01*
G01X625119Y-144093D02*
Y-149093D01*
G01X623952Y-145760D02*
X626286D01*
G01X634819Y-149093D02*
Y-144093D01*
G01Y-146593D02*
X635236Y-146093D01*
X635736Y-145843D01*
X636236Y-145760D01*
X636986Y-145926D01*
X637486Y-146260D01*
X637819Y-146843D01*
Y-147510D01*
X637652Y-148176D01*
X637319Y-148676D01*
X636736Y-149010D01*
X636236Y-149093D01*
X635736Y-149010D01*
X635236Y-148760D01*
X634819Y-148343D01*
G01X640669Y-146843D02*
X643336D01*
X643086Y-146260D01*
X642669Y-145926D01*
X642086Y-145760D01*
X641502Y-145843D01*
X641002Y-146093D01*
X640669Y-146676D01*
X640502Y-147176D01*
Y-147676D01*
X640669Y-148176D01*
X641086Y-148676D01*
X641586Y-149010D01*
X642169Y-149093D01*
X642752Y-148926D01*
X643336Y-148426D01*
G01X651619Y-149093D02*
Y-144093D01*
G01Y-146593D02*
X652036Y-146093D01*
X652536Y-145843D01*
X653036Y-145760D01*
X653786Y-145926D01*
X654286Y-146260D01*
X654619Y-146843D01*
Y-147510D01*
X654452Y-148176D01*
X654119Y-148676D01*
X653536Y-149010D01*
X653036Y-149093D01*
X652536Y-149010D01*
X652036Y-148760D01*
X651619Y-148343D01*
G01X657552Y-149093D02*
Y-145760D01*
G01Y-146426D02*
X657969Y-146093D01*
X658386Y-145843D01*
X658969Y-145760D01*
X659386Y-145843D01*
X659886Y-146093D01*
G01X664319Y-149093D02*
X663819Y-149010D01*
X663319Y-148676D01*
X662986Y-148093D01*
X662819Y-147426D01*
X662986Y-146760D01*
X663319Y-146176D01*
X663819Y-145843D01*
X664319Y-145760D01*
X664819Y-145843D01*
X665319Y-146176D01*
X665652Y-146760D01*
X665736Y-147426D01*
X665652Y-148093D01*
X665319Y-148676D01*
X664819Y-149010D01*
X664319Y-149093D01*
G01X668502D02*
Y-144093D01*
G01X671169Y-145760D02*
X668502Y-147676D01*
G01X669586Y-146926D02*
X671336Y-149093D01*
G01X674269Y-146843D02*
X676936D01*
X676686Y-146260D01*
X676269Y-145926D01*
X675686Y-145760D01*
X675102Y-145843D01*
X674602Y-146093D01*
X674269Y-146676D01*
X674102Y-147176D01*
Y-147676D01*
X674269Y-148176D01*
X674686Y-148676D01*
X675186Y-149010D01*
X675769Y-149093D01*
X676352Y-148926D01*
X676936Y-148426D01*
G01X679702Y-149093D02*
Y-145760D01*
G01Y-146593D02*
X680036Y-146176D01*
X680536Y-145843D01*
X681202Y-145760D01*
X681786Y-145843D01*
X682286Y-146176D01*
X682536Y-146760D01*
Y-149093D01*
G01X692319D02*
Y-144093D01*
G01X699419Y-149093D02*
Y-145760D01*
G01Y-146343D02*
X699086Y-146010D01*
X698586Y-145843D01*
X698002Y-145760D01*
X697419Y-145926D01*
X696919Y-146260D01*
X696586Y-146760D01*
X696419Y-147426D01*
X696586Y-148093D01*
X696919Y-148593D01*
X697419Y-148926D01*
X698002Y-149093D01*
X698586Y-149010D01*
X699086Y-148760D01*
X699419Y-148426D01*
G01X701769Y-150593D02*
X702269Y-150760D01*
X702936Y-150593D01*
X703352Y-150260D01*
X703686Y-149843D01*
X704186Y-148510D01*
X705269Y-145760D01*
G01X702602D02*
X704186Y-148510D01*
G01X707869Y-146843D02*
X710536D01*
X710286Y-146260D01*
X709869Y-145926D01*
X709286Y-145760D01*
X708702Y-145843D01*
X708202Y-146093D01*
X707869Y-146676D01*
X707702Y-147176D01*
Y-147676D01*
X707869Y-148176D01*
X708286Y-148676D01*
X708786Y-149010D01*
X709369Y-149093D01*
X709952Y-148926D01*
X710536Y-148426D01*
G01X713552Y-149093D02*
Y-145760D01*
G01Y-146426D02*
X713969Y-146093D01*
X714386Y-145843D01*
X714969Y-145760D01*
X715386Y-145843D01*
X715886Y-146093D01*
G01X583652Y-131593D02*
Y-136593D01*
X586986D01*
G01X589502D02*
Y-133260D01*
G01Y-134093D02*
X589836Y-133676D01*
X590336Y-133343D01*
X591002Y-133260D01*
X591586Y-133343D01*
X592086Y-133676D01*
X592336Y-134260D01*
Y-136593D01*
G01X596519Y-136760D02*
X596352Y-136676D01*
Y-136510D01*
X596519Y-136426D01*
X596686Y-136510D01*
Y-136676D01*
X596519Y-136760D01*
G01Y-134510D02*
X596352Y-134426D01*
Y-134260D01*
X596519Y-134176D01*
X596686Y-134260D01*
Y-134426D01*
X596519Y-134510D01*
G01X609052Y-133676D02*
X608469Y-133343D01*
X607969Y-133260D01*
X607302Y-133426D01*
X606802Y-133760D01*
X606469Y-134343D01*
X606386Y-134926D01*
X606469Y-135510D01*
X606802Y-136010D01*
X607302Y-136426D01*
X607969Y-136593D01*
X608552Y-136426D01*
X609052Y-136093D01*
G01X614819Y-136593D02*
Y-133260D01*
G01Y-133843D02*
X614486Y-133510D01*
X613986Y-133343D01*
X613402Y-133260D01*
X612819Y-133426D01*
X612319Y-133760D01*
X611986Y-134260D01*
X611819Y-134926D01*
X611986Y-135593D01*
X612319Y-136093D01*
X612819Y-136426D01*
X613402Y-136593D01*
X613986Y-136510D01*
X614486Y-136260D01*
X614819Y-135926D01*
G01X617502Y-136593D02*
Y-133260D01*
G01Y-134093D02*
X617836Y-133676D01*
X618336Y-133343D01*
X619002Y-133260D01*
X619586Y-133343D01*
X620086Y-133676D01*
X620336Y-134260D01*
Y-136593D01*
G01X624519Y-133260D02*
X625352Y-132218D01*
Y-131593D01*
X624727D01*
Y-132218D01*
X625352D01*
G01X630119Y-131593D02*
Y-136593D01*
G01X628952Y-133260D02*
X631286D01*
G01X639819Y-136593D02*
Y-131593D01*
G01Y-134093D02*
X640236Y-133593D01*
X640736Y-133343D01*
X641236Y-133260D01*
X641986Y-133426D01*
X642486Y-133760D01*
X642819Y-134343D01*
Y-135010D01*
X642652Y-135676D01*
X642319Y-136176D01*
X641736Y-136510D01*
X641236Y-136593D01*
X640736Y-136510D01*
X640236Y-136260D01*
X639819Y-135843D01*
G01X645669Y-134343D02*
X648336D01*
X648086Y-133760D01*
X647669Y-133426D01*
X647086Y-133260D01*
X646502Y-133343D01*
X646002Y-133593D01*
X645669Y-134176D01*
X645502Y-134676D01*
Y-135176D01*
X645669Y-135676D01*
X646086Y-136176D01*
X646586Y-136510D01*
X647169Y-136593D01*
X647752Y-136426D01*
X648336Y-135926D01*
G01X656619Y-136593D02*
Y-131593D01*
G01Y-134093D02*
X657036Y-133593D01*
X657536Y-133343D01*
X658036Y-133260D01*
X658786Y-133426D01*
X659286Y-133760D01*
X659619Y-134343D01*
Y-135010D01*
X659452Y-135676D01*
X659119Y-136176D01*
X658536Y-136510D01*
X658036Y-136593D01*
X657536Y-136510D01*
X657036Y-136260D01*
X656619Y-135843D01*
G01X662552Y-136593D02*
Y-133260D01*
G01Y-133926D02*
X662969Y-133593D01*
X663386Y-133343D01*
X663969Y-133260D01*
X664386Y-133343D01*
X664886Y-133593D01*
G01X669319Y-136593D02*
X668819Y-136510D01*
X668319Y-136176D01*
X667986Y-135593D01*
X667819Y-134926D01*
X667986Y-134260D01*
X668319Y-133676D01*
X668819Y-133343D01*
X669319Y-133260D01*
X669819Y-133343D01*
X670319Y-133676D01*
X670652Y-134260D01*
X670736Y-134926D01*
X670652Y-135593D01*
X670319Y-136176D01*
X669819Y-136510D01*
X669319Y-136593D01*
G01X673502D02*
Y-131593D01*
G01X676169Y-133260D02*
X673502Y-135176D01*
G01X674586Y-134426D02*
X676336Y-136593D01*
G01X679269Y-134343D02*
X681936D01*
X681686Y-133760D01*
X681269Y-133426D01*
X680686Y-133260D01*
X680102Y-133343D01*
X679602Y-133593D01*
X679269Y-134176D01*
X679102Y-134676D01*
Y-135176D01*
X679269Y-135676D01*
X679686Y-136176D01*
X680186Y-136510D01*
X680769Y-136593D01*
X681352Y-136426D01*
X681936Y-135926D01*
G01X684702Y-136593D02*
Y-133260D01*
G01Y-134093D02*
X685036Y-133676D01*
X685536Y-133343D01*
X686202Y-133260D01*
X686786Y-133343D01*
X687286Y-133676D01*
X687536Y-134260D01*
Y-136593D01*
G01X697319D02*
Y-131593D01*
G01X704419Y-136593D02*
Y-133260D01*
G01Y-133843D02*
X704086Y-133510D01*
X703586Y-133343D01*
X703002Y-133260D01*
X702419Y-133426D01*
X701919Y-133760D01*
X701586Y-134260D01*
X701419Y-134926D01*
X701586Y-135593D01*
X701919Y-136093D01*
X702419Y-136426D01*
X703002Y-136593D01*
X703586Y-136510D01*
X704086Y-136260D01*
X704419Y-135926D01*
G01X706769Y-138093D02*
X707269Y-138260D01*
X707936Y-138093D01*
X708352Y-137760D01*
X708686Y-137343D01*
X709186Y-136010D01*
X710269Y-133260D01*
G01X707602D02*
X709186Y-136010D01*
G01X712869Y-134343D02*
X715536D01*
X715286Y-133760D01*
X714869Y-133426D01*
X714286Y-133260D01*
X713702Y-133343D01*
X713202Y-133593D01*
X712869Y-134176D01*
X712702Y-134676D01*
Y-135176D01*
X712869Y-135676D01*
X713286Y-136176D01*
X713786Y-136510D01*
X714369Y-136593D01*
X714952Y-136426D01*
X715536Y-135926D01*
G01X718552Y-136593D02*
Y-133260D01*
G01Y-133926D02*
X718969Y-133593D01*
X719386Y-133343D01*
X719969Y-133260D01*
X720386Y-133343D01*
X720886Y-133593D01*
G01X528259Y121707D02*
Y126707D01*
G01Y124207D02*
X528676Y124707D01*
X529176Y124957D01*
X529676Y125040D01*
X530426Y124874D01*
X530926Y124540D01*
X531259Y123957D01*
Y123290D01*
X531092Y122624D01*
X530759Y122124D01*
X530176Y121790D01*
X529676Y121707D01*
X529176Y121790D01*
X528676Y122040D01*
X528259Y122457D01*
G01X533942Y125040D02*
Y122707D01*
X534276Y122124D01*
X534776Y121790D01*
X535359Y121707D01*
X535942Y121790D01*
X536442Y122124D01*
X536776Y122707D01*
G01Y121707D02*
Y125040D01*
G01X539459Y121707D02*
Y126707D01*
G01Y124207D02*
X539876Y124707D01*
X540376Y124957D01*
X540876Y125040D01*
X541626Y124874D01*
X542126Y124540D01*
X542459Y123957D01*
Y123290D01*
X542292Y122624D01*
X541959Y122124D01*
X541376Y121790D01*
X540876Y121707D01*
X540376Y121790D01*
X539876Y122040D01*
X539459Y122457D01*
G01X545059Y121707D02*
Y126707D01*
G01Y124207D02*
X545476Y124707D01*
X545976Y124957D01*
X546476Y125040D01*
X547226Y124874D01*
X547726Y124540D01*
X548059Y123957D01*
Y123290D01*
X547892Y122624D01*
X547559Y122124D01*
X546976Y121790D01*
X546476Y121707D01*
X545976Y121790D01*
X545476Y122040D01*
X545059Y122457D01*
G01X552159Y121707D02*
Y126707D01*
G01X556509Y123957D02*
X559176D01*
X558926Y124540D01*
X558509Y124874D01*
X557926Y125040D01*
X557342Y124957D01*
X556842Y124707D01*
X556509Y124124D01*
X556342Y123624D01*
Y123124D01*
X556509Y122624D01*
X556926Y122124D01*
X557426Y121790D01*
X558009Y121707D01*
X558592Y121874D01*
X559176Y122374D01*
G01X568959Y125040D02*
Y121707D01*
G01Y126374D02*
X568792Y126457D01*
Y126624D01*
X568959Y126707D01*
X569126Y126624D01*
Y126457D01*
X568959Y126374D01*
G01X573142Y121707D02*
Y125040D01*
G01Y124207D02*
X573476Y124624D01*
X573976Y124957D01*
X574642Y125040D01*
X575226Y124957D01*
X575726Y124624D01*
X575976Y124040D01*
Y121707D01*
G01X578909Y122290D02*
X579326Y121957D01*
X579909Y121707D01*
X580409D01*
X580909Y121874D01*
X581242Y122124D01*
X581409Y122457D01*
X581326Y122957D01*
X580992Y123207D01*
X579492Y123707D01*
X579159Y124290D01*
X579326Y124707D01*
X579659Y124957D01*
X580159Y125040D01*
X580659Y124957D01*
X581159Y124707D01*
G01X585759Y125040D02*
Y121707D01*
G01Y126374D02*
X585592Y126457D01*
Y126624D01*
X585759Y126707D01*
X585926Y126624D01*
Y126457D01*
X585759Y126374D01*
G01X592859Y126707D02*
Y121707D01*
G01Y122457D02*
X592526Y122040D01*
X592026Y121790D01*
X591442Y121707D01*
X590776Y121874D01*
X590276Y122290D01*
X589942Y122790D01*
X589859Y123374D01*
X589942Y123957D01*
X590276Y124457D01*
X590776Y124874D01*
X591442Y125040D01*
X592026Y124957D01*
X592442Y124790D01*
X592859Y124457D01*
G01X595709Y123957D02*
X598376D01*
X598126Y124540D01*
X597709Y124874D01*
X597126Y125040D01*
X596542Y124957D01*
X596042Y124707D01*
X595709Y124124D01*
X595542Y123624D01*
Y123124D01*
X595709Y122624D01*
X596126Y122124D01*
X596626Y121790D01*
X597209Y121707D01*
X597792Y121874D01*
X598376Y122374D01*
G01X608159Y126707D02*
Y121707D01*
G01X606992Y125040D02*
X609326D01*
G01X612342Y121707D02*
Y126707D01*
G01Y124290D02*
X612759Y124707D01*
X613176Y124957D01*
X613842Y125040D01*
X614342Y124957D01*
X614926Y124624D01*
X615176Y124124D01*
Y121707D01*
G01X618109Y123957D02*
X620776D01*
X620526Y124540D01*
X620109Y124874D01*
X619526Y125040D01*
X618942Y124957D01*
X618442Y124707D01*
X618109Y124124D01*
X617942Y123624D01*
Y123124D01*
X618109Y122624D01*
X618526Y122124D01*
X619026Y121790D01*
X619609Y121707D01*
X620192Y121874D01*
X620776Y122374D01*
G01X629392Y121707D02*
Y125040D01*
G01Y124374D02*
X629809Y124707D01*
X630226Y124957D01*
X630809Y125040D01*
X631226Y124957D01*
X631726Y124707D01*
G01X634909Y123957D02*
X637576D01*
X637326Y124540D01*
X636909Y124874D01*
X636326Y125040D01*
X635742Y124957D01*
X635242Y124707D01*
X634909Y124124D01*
X634742Y123624D01*
Y123124D01*
X634909Y122624D01*
X635326Y122124D01*
X635826Y121790D01*
X636409Y121707D01*
X636992Y121874D01*
X637576Y122374D01*
G01X640509Y122290D02*
X640926Y121957D01*
X641509Y121707D01*
X642009D01*
X642509Y121874D01*
X642842Y122124D01*
X643009Y122457D01*
X642926Y122957D01*
X642592Y123207D01*
X641092Y123707D01*
X640759Y124290D01*
X640926Y124707D01*
X641259Y124957D01*
X641759Y125040D01*
X642259Y124957D01*
X642759Y124707D01*
G01X647359Y125040D02*
Y121707D01*
G01Y126374D02*
X647192Y126457D01*
Y126624D01*
X647359Y126707D01*
X647526Y126624D01*
Y126457D01*
X647359Y126374D01*
G01X651542Y121707D02*
Y125040D01*
G01Y124207D02*
X651876Y124624D01*
X652376Y124957D01*
X653042Y125040D01*
X653626Y124957D01*
X654126Y124624D01*
X654376Y124040D01*
Y121707D01*
G01X658559Y121540D02*
X658392Y121624D01*
Y121790D01*
X658559Y121874D01*
X658726Y121790D01*
Y121624D01*
X658559Y121540D01*
G01X528259Y164707D02*
Y169707D01*
G01Y167207D02*
X528676Y167707D01*
X529176Y167957D01*
X529676Y168040D01*
X530426Y167874D01*
X530926Y167540D01*
X531259Y166957D01*
Y166290D01*
X531092Y165624D01*
X530759Y165124D01*
X530176Y164790D01*
X529676Y164707D01*
X529176Y164790D01*
X528676Y165040D01*
X528259Y165457D01*
G01X533942Y168040D02*
Y165707D01*
X534276Y165124D01*
X534776Y164790D01*
X535359Y164707D01*
X535942Y164790D01*
X536442Y165124D01*
X536776Y165707D01*
G01Y164707D02*
Y168040D01*
G01X539459Y164707D02*
Y169707D01*
G01Y167207D02*
X539876Y167707D01*
X540376Y167957D01*
X540876Y168040D01*
X541626Y167874D01*
X542126Y167540D01*
X542459Y166957D01*
Y166290D01*
X542292Y165624D01*
X541959Y165124D01*
X541376Y164790D01*
X540876Y164707D01*
X540376Y164790D01*
X539876Y165040D01*
X539459Y165457D01*
G01X545059Y164707D02*
Y169707D01*
G01Y167207D02*
X545476Y167707D01*
X545976Y167957D01*
X546476Y168040D01*
X547226Y167874D01*
X547726Y167540D01*
X548059Y166957D01*
Y166290D01*
X547892Y165624D01*
X547559Y165124D01*
X546976Y164790D01*
X546476Y164707D01*
X545976Y164790D01*
X545476Y165040D01*
X545059Y165457D01*
G01X552159Y164707D02*
Y169707D01*
G01X556509Y166957D02*
X559176D01*
X558926Y167540D01*
X558509Y167874D01*
X557926Y168040D01*
X557342Y167957D01*
X556842Y167707D01*
X556509Y167124D01*
X556342Y166624D01*
Y166124D01*
X556509Y165624D01*
X556926Y165124D01*
X557426Y164790D01*
X558009Y164707D01*
X558592Y164874D01*
X559176Y165374D01*
G01X568959Y168040D02*
Y164707D01*
G01Y169374D02*
X568792Y169457D01*
Y169624D01*
X568959Y169707D01*
X569126Y169624D01*
Y169457D01*
X568959Y169374D01*
G01X573142Y164707D02*
Y168040D01*
G01Y167207D02*
X573476Y167624D01*
X573976Y167957D01*
X574642Y168040D01*
X575226Y167957D01*
X575726Y167624D01*
X575976Y167040D01*
Y164707D01*
G01X578909Y165290D02*
X579326Y164957D01*
X579909Y164707D01*
X580409D01*
X580909Y164874D01*
X581242Y165124D01*
X581409Y165457D01*
X581326Y165957D01*
X580992Y166207D01*
X579492Y166707D01*
X579159Y167290D01*
X579326Y167707D01*
X579659Y167957D01*
X580159Y168040D01*
X580659Y167957D01*
X581159Y167707D01*
G01X585759Y168040D02*
Y164707D01*
G01Y169374D02*
X585592Y169457D01*
Y169624D01*
X585759Y169707D01*
X585926Y169624D01*
Y169457D01*
X585759Y169374D01*
G01X592859Y169707D02*
Y164707D01*
G01Y165457D02*
X592526Y165040D01*
X592026Y164790D01*
X591442Y164707D01*
X590776Y164874D01*
X590276Y165290D01*
X589942Y165790D01*
X589859Y166374D01*
X589942Y166957D01*
X590276Y167457D01*
X590776Y167874D01*
X591442Y168040D01*
X592026Y167957D01*
X592442Y167790D01*
X592859Y167457D01*
G01X595709Y166957D02*
X598376D01*
X598126Y167540D01*
X597709Y167874D01*
X597126Y168040D01*
X596542Y167957D01*
X596042Y167707D01*
X595709Y167124D01*
X595542Y166624D01*
Y166124D01*
X595709Y165624D01*
X596126Y165124D01*
X596626Y164790D01*
X597209Y164707D01*
X597792Y164874D01*
X598376Y165374D01*
G01X608159Y169707D02*
Y164707D01*
G01X606992Y168040D02*
X609326D01*
G01X612342Y164707D02*
Y169707D01*
G01Y167290D02*
X612759Y167707D01*
X613176Y167957D01*
X613842Y168040D01*
X614342Y167957D01*
X614926Y167624D01*
X615176Y167124D01*
Y164707D01*
G01X618109Y166957D02*
X620776D01*
X620526Y167540D01*
X620109Y167874D01*
X619526Y168040D01*
X618942Y167957D01*
X618442Y167707D01*
X618109Y167124D01*
X617942Y166624D01*
Y166124D01*
X618109Y165624D01*
X618526Y165124D01*
X619026Y164790D01*
X619609Y164707D01*
X620192Y164874D01*
X620776Y165374D01*
G01X629392Y164707D02*
Y168040D01*
G01Y167374D02*
X629809Y167707D01*
X630226Y167957D01*
X630809Y168040D01*
X631226Y167957D01*
X631726Y167707D01*
G01X634909Y166957D02*
X637576D01*
X637326Y167540D01*
X636909Y167874D01*
X636326Y168040D01*
X635742Y167957D01*
X635242Y167707D01*
X634909Y167124D01*
X634742Y166624D01*
Y166124D01*
X634909Y165624D01*
X635326Y165124D01*
X635826Y164790D01*
X636409Y164707D01*
X636992Y164874D01*
X637576Y165374D01*
G01X640509Y165290D02*
X640926Y164957D01*
X641509Y164707D01*
X642009D01*
X642509Y164874D01*
X642842Y165124D01*
X643009Y165457D01*
X642926Y165957D01*
X642592Y166207D01*
X641092Y166707D01*
X640759Y167290D01*
X640926Y167707D01*
X641259Y167957D01*
X641759Y168040D01*
X642259Y167957D01*
X642759Y167707D01*
G01X647359Y168040D02*
Y164707D01*
G01Y169374D02*
X647192Y169457D01*
Y169624D01*
X647359Y169707D01*
X647526Y169624D01*
Y169457D01*
X647359Y169374D01*
G01X651542Y164707D02*
Y168040D01*
G01Y167207D02*
X651876Y167624D01*
X652376Y167957D01*
X653042Y168040D01*
X653626Y167957D01*
X654126Y167624D01*
X654376Y167040D01*
Y164707D01*
G01X658559Y164540D02*
X658392Y164624D01*
Y164790D01*
X658559Y164874D01*
X658726Y164790D01*
Y164624D01*
X658559Y164540D01*
G01X541259Y237040D02*
X542759Y233707D01*
X544259Y237040D01*
G01X548359D02*
Y233707D01*
G01Y238374D02*
X548192Y238457D01*
Y238624D01*
X548359Y238707D01*
X548526Y238624D01*
Y238457D01*
X548359Y238374D01*
G01X555459Y233707D02*
Y237040D01*
G01Y236457D02*
X555126Y236790D01*
X554626Y236957D01*
X554042Y237040D01*
X553459Y236874D01*
X552959Y236540D01*
X552626Y236040D01*
X552459Y235374D01*
X552626Y234707D01*
X552959Y234207D01*
X553459Y233874D01*
X554042Y233707D01*
X554626Y233790D01*
X555126Y234040D01*
X555459Y234374D01*
G01X563909Y234290D02*
X564326Y233957D01*
X564909Y233707D01*
X565409D01*
X565909Y233874D01*
X566242Y234124D01*
X566409Y234457D01*
X566326Y234957D01*
X565992Y235207D01*
X564492Y235707D01*
X564159Y236290D01*
X564326Y236707D01*
X564659Y236957D01*
X565159Y237040D01*
X565659Y236957D01*
X566159Y236707D01*
G01X569342Y233707D02*
Y238707D01*
G01Y236290D02*
X569759Y236707D01*
X570176Y236957D01*
X570842Y237040D01*
X571342Y236957D01*
X571926Y236624D01*
X572176Y236124D01*
Y233707D01*
G01X577859D02*
Y237040D01*
G01Y236457D02*
X577526Y236790D01*
X577026Y236957D01*
X576442Y237040D01*
X575859Y236874D01*
X575359Y236540D01*
X575026Y236040D01*
X574859Y235374D01*
X575026Y234707D01*
X575359Y234207D01*
X575859Y233874D01*
X576442Y233707D01*
X577026Y233790D01*
X577526Y234040D01*
X577859Y234374D01*
G01X581959Y233707D02*
Y238707D01*
G01X587559Y233707D02*
Y238707D01*
G01X597259Y233707D02*
Y238707D01*
G01Y236207D02*
X597676Y236707D01*
X598176Y236957D01*
X598676Y237040D01*
X599426Y236874D01*
X599926Y236540D01*
X600259Y235957D01*
Y235290D01*
X600092Y234624D01*
X599759Y234124D01*
X599176Y233790D01*
X598676Y233707D01*
X598176Y233790D01*
X597676Y234040D01*
X597259Y234457D01*
G01X603109Y235957D02*
X605776D01*
X605526Y236540D01*
X605109Y236874D01*
X604526Y237040D01*
X603942Y236957D01*
X603442Y236707D01*
X603109Y236124D01*
X602942Y235624D01*
Y235124D01*
X603109Y234624D01*
X603526Y234124D01*
X604026Y233790D01*
X604609Y233707D01*
X605192Y233874D01*
X605776Y234374D01*
G01X613476Y237040D02*
X614476Y233707D01*
X615559Y237040D01*
X616642Y233707D01*
X617642Y237040D01*
G01X621159D02*
Y233707D01*
G01Y238374D02*
X620992Y238457D01*
Y238624D01*
X621159Y238707D01*
X621326Y238624D01*
Y238457D01*
X621159Y238374D01*
G01X626759Y238707D02*
Y233707D01*
G01X625592Y237040D02*
X627926D01*
G01X630942Y233707D02*
Y238707D01*
G01Y236290D02*
X631359Y236707D01*
X631776Y236957D01*
X632442Y237040D01*
X632942Y236957D01*
X633526Y236624D01*
X633776Y236124D01*
Y233707D01*
G01X645226D02*
X641892Y235374D01*
X645226Y237040D01*
G01X654759Y233707D02*
X655342Y233790D01*
X656009Y234040D01*
X656426Y234457D01*
X656592Y235040D01*
X656426Y235624D01*
X655926Y236124D01*
X655176Y236374D01*
X654342D01*
X653842Y236540D01*
X653426Y236957D01*
X653259Y237540D01*
X653509Y238124D01*
X654092Y238540D01*
X654759Y238707D01*
X655426Y238540D01*
X656009Y238124D01*
X656259Y237540D01*
X656092Y236957D01*
X655676Y236540D01*
X655176Y236374D01*
X654342D01*
X653592Y236124D01*
X653092Y235624D01*
X652926Y235040D01*
X653092Y234457D01*
X653509Y234040D01*
X654176Y233790D01*
X654759Y233707D01*
G01X660359Y238707D02*
X659692Y238540D01*
X659192Y238124D01*
X658859Y237624D01*
X658609Y236957D01*
X658526Y236207D01*
X658609Y235457D01*
X658859Y234790D01*
X659192Y234290D01*
X659692Y233874D01*
X660359Y233707D01*
X661026Y233874D01*
X661526Y234290D01*
X661859Y234790D01*
X662109Y235457D01*
X662192Y236207D01*
X662109Y236957D01*
X661859Y237624D01*
X661526Y238124D01*
X661026Y238540D01*
X660359Y238707D01*
G01X670059Y233540D02*
X673059Y238707D01*
G01X670059D02*
X669559Y238540D01*
X669309Y238290D01*
X669142Y237790D01*
X669309Y237290D01*
X669559Y237040D01*
X670059Y236874D01*
X670559Y237040D01*
X670809Y237290D01*
X670976Y237790D01*
X670809Y238290D01*
X670559Y238540D01*
X670059Y238707D01*
G01X673059Y235374D02*
X672559Y235207D01*
X672309Y234957D01*
X672142Y234457D01*
X672309Y233957D01*
X672559Y233707D01*
X673059Y233540D01*
X673559Y233707D01*
X673809Y233957D01*
X673976Y234457D01*
X673809Y234957D01*
X673559Y235207D01*
X673059Y235374D01*
G01X681509Y234290D02*
X681926Y233957D01*
X682509Y233707D01*
X683009D01*
X683509Y233874D01*
X683842Y234124D01*
X684009Y234457D01*
X683926Y234957D01*
X683592Y235207D01*
X682092Y235707D01*
X681759Y236290D01*
X681926Y236707D01*
X682259Y236957D01*
X682759Y237040D01*
X683259Y236957D01*
X683759Y236707D01*
G01X688359Y233707D02*
X687859Y233790D01*
X687359Y234124D01*
X687026Y234707D01*
X686859Y235374D01*
X687026Y236040D01*
X687359Y236624D01*
X687859Y236957D01*
X688359Y237040D01*
X688859Y236957D01*
X689359Y236624D01*
X689692Y236040D01*
X689776Y235374D01*
X689692Y234707D01*
X689359Y234124D01*
X688859Y233790D01*
X688359Y233707D01*
G01X693959D02*
Y238707D01*
G01X701059D02*
Y233707D01*
G01Y234457D02*
X700726Y234040D01*
X700226Y233790D01*
X699642Y233707D01*
X698976Y233874D01*
X698476Y234290D01*
X698142Y234790D01*
X698059Y235374D01*
X698142Y235957D01*
X698476Y236457D01*
X698976Y236874D01*
X699642Y237040D01*
X700226Y236957D01*
X700642Y236790D01*
X701059Y236457D01*
G01X703909Y235957D02*
X706576D01*
X706326Y236540D01*
X705909Y236874D01*
X705326Y237040D01*
X704742Y236957D01*
X704242Y236707D01*
X703909Y236124D01*
X703742Y235624D01*
Y235124D01*
X703909Y234624D01*
X704326Y234124D01*
X704826Y233790D01*
X705409Y233707D01*
X705992Y233874D01*
X706576Y234374D01*
G01X709592Y233707D02*
Y237040D01*
G01Y236374D02*
X710009Y236707D01*
X710426Y236957D01*
X711009Y237040D01*
X711426Y236957D01*
X711926Y236707D01*
G01X719459Y233707D02*
Y237040D01*
G01Y236124D02*
X719709Y236540D01*
X720126Y236874D01*
X720709Y237040D01*
X721292Y236874D01*
X721709Y236540D01*
X721959Y236124D01*
Y233707D01*
G01Y236124D02*
X722209Y236540D01*
X722626Y236874D01*
X723209Y237040D01*
X723792Y236874D01*
X724209Y236540D01*
X724459Y236040D01*
Y233707D01*
G01X729059D02*
Y237040D01*
G01Y236457D02*
X728726Y236790D01*
X728226Y236957D01*
X727642Y237040D01*
X727059Y236874D01*
X726559Y236540D01*
X726226Y236040D01*
X726059Y235374D01*
X726226Y234707D01*
X726559Y234207D01*
X727059Y233874D01*
X727642Y233707D01*
X728226Y233790D01*
X728726Y234040D01*
X729059Y234374D01*
G01X731909Y234290D02*
X732326Y233957D01*
X732909Y233707D01*
X733409D01*
X733909Y233874D01*
X734242Y234124D01*
X734409Y234457D01*
X734326Y234957D01*
X733992Y235207D01*
X732492Y235707D01*
X732159Y236290D01*
X732326Y236707D01*
X732659Y236957D01*
X733159Y237040D01*
X733659Y236957D01*
X734159Y236707D01*
G01X737342Y233707D02*
Y238707D01*
G01X740009Y237040D02*
X737342Y235124D01*
G01X738426Y235874D02*
X740176Y233707D01*
G01X530259Y242707D02*
Y247707D01*
G01Y245207D02*
X530676Y245707D01*
X531176Y245957D01*
X531676Y246040D01*
X532426Y245874D01*
X532926Y245540D01*
X533259Y244957D01*
Y244290D01*
X533092Y243624D01*
X532759Y243124D01*
X532176Y242790D01*
X531676Y242707D01*
X531176Y242790D01*
X530676Y243040D01*
X530259Y243457D01*
G01X537359Y242540D02*
X537192Y242624D01*
Y242790D01*
X537359Y242874D01*
X537526Y242790D01*
Y242624D01*
X537359Y242540D01*
G01X543626Y245374D02*
X543959Y245624D01*
X544209Y246040D01*
X544376Y246624D01*
X544209Y247124D01*
X543876Y247457D01*
X543292Y247707D01*
X541042D01*
Y242707D01*
X543792D01*
X544376Y243040D01*
X544709Y243540D01*
X544876Y244124D01*
X544709Y244707D01*
X544209Y245207D01*
X543626Y245374D01*
X541042D01*
G01X548559Y242707D02*
X548059Y242790D01*
X547559Y243124D01*
X547226Y243707D01*
X547059Y244374D01*
X547226Y245040D01*
X547559Y245624D01*
X548059Y245957D01*
X548559Y246040D01*
X549059Y245957D01*
X549559Y245624D01*
X549892Y245040D01*
X549976Y244374D01*
X549892Y243707D01*
X549559Y243124D01*
X549059Y242790D01*
X548559Y242707D01*
G01X555659D02*
Y246040D01*
G01Y245457D02*
X555326Y245790D01*
X554826Y245957D01*
X554242Y246040D01*
X553659Y245874D01*
X553159Y245540D01*
X552826Y245040D01*
X552659Y244374D01*
X552826Y243707D01*
X553159Y243207D01*
X553659Y242874D01*
X554242Y242707D01*
X554826Y242790D01*
X555326Y243040D01*
X555659Y243374D01*
G01X558592Y242707D02*
Y246040D01*
G01Y245374D02*
X559009Y245707D01*
X559426Y245957D01*
X560009Y246040D01*
X560426Y245957D01*
X560926Y245707D01*
G01X566859Y247707D02*
Y242707D01*
G01Y243457D02*
X566526Y243040D01*
X566026Y242790D01*
X565442Y242707D01*
X564776Y242874D01*
X564276Y243290D01*
X563942Y243790D01*
X563859Y244374D01*
X563942Y244957D01*
X564276Y245457D01*
X564776Y245874D01*
X565442Y246040D01*
X566026Y245957D01*
X566442Y245790D01*
X566859Y245457D01*
G01X576559Y247707D02*
Y242707D01*
G01X575392Y246040D02*
X577726D01*
G01X580742Y242707D02*
Y247707D01*
G01Y245290D02*
X581159Y245707D01*
X581576Y245957D01*
X582242Y246040D01*
X582742Y245957D01*
X583326Y245624D01*
X583576Y245124D01*
Y242707D01*
G01X587759Y246040D02*
Y242707D01*
G01Y247374D02*
X587592Y247457D01*
Y247624D01*
X587759Y247707D01*
X587926Y247624D01*
Y247457D01*
X587759Y247374D01*
G01X594692Y245624D02*
X594109Y245957D01*
X593609Y246040D01*
X592942Y245874D01*
X592442Y245540D01*
X592109Y244957D01*
X592026Y244374D01*
X592109Y243790D01*
X592442Y243290D01*
X592942Y242874D01*
X593609Y242707D01*
X594192Y242874D01*
X594692Y243207D01*
G01X597542Y242707D02*
Y247707D01*
G01X600209Y246040D02*
X597542Y244124D01*
G01X598626Y244874D02*
X600376Y242707D01*
G01X603142D02*
Y246040D01*
G01Y245207D02*
X603476Y245624D01*
X603976Y245957D01*
X604642Y246040D01*
X605226Y245957D01*
X605726Y245624D01*
X605976Y245040D01*
Y242707D01*
G01X608909Y244957D02*
X611576D01*
X611326Y245540D01*
X610909Y245874D01*
X610326Y246040D01*
X609742Y245957D01*
X609242Y245707D01*
X608909Y245124D01*
X608742Y244624D01*
Y244124D01*
X608909Y243624D01*
X609326Y243124D01*
X609826Y242790D01*
X610409Y242707D01*
X610992Y242874D01*
X611576Y243374D01*
G01X614509Y243290D02*
X614926Y242957D01*
X615509Y242707D01*
X616009D01*
X616509Y242874D01*
X616842Y243124D01*
X617009Y243457D01*
X616926Y243957D01*
X616592Y244207D01*
X615092Y244707D01*
X614759Y245290D01*
X614926Y245707D01*
X615259Y245957D01*
X615759Y246040D01*
X616259Y245957D01*
X616759Y245707D01*
G01X620109Y243290D02*
X620526Y242957D01*
X621109Y242707D01*
X621609D01*
X622109Y242874D01*
X622442Y243124D01*
X622609Y243457D01*
X622526Y243957D01*
X622192Y244207D01*
X620692Y244707D01*
X620359Y245290D01*
X620526Y245707D01*
X620859Y245957D01*
X621359Y246040D01*
X621859Y245957D01*
X622359Y245707D01*
G01X634226Y242707D02*
X630892Y244374D01*
X634226Y246040D01*
G01X643759Y247707D02*
X643092Y247540D01*
X642592Y247124D01*
X642259Y246624D01*
X642009Y245957D01*
X641926Y245207D01*
X642009Y244457D01*
X642259Y243790D01*
X642592Y243290D01*
X643092Y242874D01*
X643759Y242707D01*
X644426Y242874D01*
X644926Y243290D01*
X645259Y243790D01*
X645509Y244457D01*
X645592Y245207D01*
X645509Y245957D01*
X645259Y246624D01*
X644926Y247124D01*
X644426Y247540D01*
X643759Y247707D01*
G01X649359Y242540D02*
X649192Y242624D01*
Y242790D01*
X649359Y242874D01*
X649526Y242790D01*
Y242624D01*
X649359Y242540D01*
G01X653542Y243290D02*
X654126Y242874D01*
X654792Y242707D01*
X655459Y242874D01*
X656042Y243374D01*
X656459Y244124D01*
X656626Y244874D01*
Y245790D01*
X656459Y246540D01*
X656042Y247207D01*
X655542Y247540D01*
X654959Y247707D01*
X654292Y247540D01*
X653792Y247207D01*
X653459Y246707D01*
X653292Y246040D01*
X653459Y245457D01*
X653876Y244874D01*
X654376Y244540D01*
X654959Y244457D01*
X655626Y244624D01*
X656126Y245040D01*
X656626Y245790D01*
G01X658059Y242707D02*
Y246040D01*
G01Y245124D02*
X658309Y245540D01*
X658726Y245874D01*
X659309Y246040D01*
X659892Y245874D01*
X660309Y245540D01*
X660559Y245124D01*
Y242707D01*
G01Y245124D02*
X660809Y245540D01*
X661226Y245874D01*
X661809Y246040D01*
X662392Y245874D01*
X662809Y245540D01*
X663059Y245040D01*
Y242707D01*
G01X663659D02*
Y246040D01*
G01Y245124D02*
X663909Y245540D01*
X664326Y245874D01*
X664909Y246040D01*
X665492Y245874D01*
X665909Y245540D01*
X666159Y245124D01*
Y242707D01*
G01Y245124D02*
X666409Y245540D01*
X666826Y245874D01*
X667409Y246040D01*
X667992Y245874D01*
X668409Y245540D01*
X668659Y245040D01*
Y242707D01*
G01X671759Y242540D02*
X671592Y242624D01*
Y242790D01*
X671759Y242874D01*
X671926Y242790D01*
Y242624D01*
X671759Y242540D01*
G01Y244790D02*
X671592Y244874D01*
Y245040D01*
X671759Y245124D01*
X671926Y245040D01*
Y244874D01*
X671759Y244790D01*
G01X540259Y256040D02*
X541759Y252707D01*
X543259Y256040D01*
G01X547359D02*
Y252707D01*
G01Y257374D02*
X547192Y257457D01*
Y257624D01*
X547359Y257707D01*
X547526Y257624D01*
Y257457D01*
X547359Y257374D01*
G01X554459Y252707D02*
Y256040D01*
G01Y255457D02*
X554126Y255790D01*
X553626Y255957D01*
X553042Y256040D01*
X552459Y255874D01*
X551959Y255540D01*
X551626Y255040D01*
X551459Y254374D01*
X551626Y253707D01*
X551959Y253207D01*
X552459Y252874D01*
X553042Y252707D01*
X553626Y252790D01*
X554126Y253040D01*
X554459Y253374D01*
G01X562909Y253290D02*
X563326Y252957D01*
X563909Y252707D01*
X564409D01*
X564909Y252874D01*
X565242Y253124D01*
X565409Y253457D01*
X565326Y253957D01*
X564992Y254207D01*
X563492Y254707D01*
X563159Y255290D01*
X563326Y255707D01*
X563659Y255957D01*
X564159Y256040D01*
X564659Y255957D01*
X565159Y255707D01*
G01X568342Y252707D02*
Y257707D01*
G01Y255290D02*
X568759Y255707D01*
X569176Y255957D01*
X569842Y256040D01*
X570342Y255957D01*
X570926Y255624D01*
X571176Y255124D01*
Y252707D01*
G01X576859D02*
Y256040D01*
G01Y255457D02*
X576526Y255790D01*
X576026Y255957D01*
X575442Y256040D01*
X574859Y255874D01*
X574359Y255540D01*
X574026Y255040D01*
X573859Y254374D01*
X574026Y253707D01*
X574359Y253207D01*
X574859Y252874D01*
X575442Y252707D01*
X576026Y252790D01*
X576526Y253040D01*
X576859Y253374D01*
G01X580959Y252707D02*
Y257707D01*
G01X586559Y252707D02*
Y257707D01*
G01X596259Y252707D02*
Y257707D01*
G01Y255207D02*
X596676Y255707D01*
X597176Y255957D01*
X597676Y256040D01*
X598426Y255874D01*
X598926Y255540D01*
X599259Y254957D01*
Y254290D01*
X599092Y253624D01*
X598759Y253124D01*
X598176Y252790D01*
X597676Y252707D01*
X597176Y252790D01*
X596676Y253040D01*
X596259Y253457D01*
G01X602109Y254957D02*
X604776D01*
X604526Y255540D01*
X604109Y255874D01*
X603526Y256040D01*
X602942Y255957D01*
X602442Y255707D01*
X602109Y255124D01*
X601942Y254624D01*
Y254124D01*
X602109Y253624D01*
X602526Y253124D01*
X603026Y252790D01*
X603609Y252707D01*
X604192Y252874D01*
X604776Y253374D01*
G01X613059Y251040D02*
Y256040D01*
G01Y255290D02*
X613476Y255707D01*
X613892Y255957D01*
X614559Y256040D01*
X615142Y255957D01*
X615726Y255540D01*
X615976Y254957D01*
X616059Y254374D01*
X615976Y253790D01*
X615726Y253207D01*
X615226Y252874D01*
X614559Y252707D01*
X613976Y252790D01*
X613392Y253040D01*
X613059Y253374D01*
G01X620159Y252707D02*
Y257707D01*
G01X624342Y256040D02*
Y253707D01*
X624676Y253124D01*
X625176Y252790D01*
X625759Y252707D01*
X626342Y252790D01*
X626842Y253124D01*
X627176Y253707D01*
G01Y252707D02*
Y256040D01*
G01X630192Y251457D02*
X630776Y251124D01*
X631442Y251040D01*
X632026Y251124D01*
X632526Y251540D01*
X632859Y252124D01*
Y256040D01*
G01Y255374D02*
X632526Y255707D01*
X632026Y255957D01*
X631442Y256040D01*
X630776Y255874D01*
X630359Y255540D01*
X630026Y254957D01*
X629859Y254374D01*
X629942Y253874D01*
X630276Y253290D01*
X630776Y252874D01*
X631442Y252707D01*
X631942Y252790D01*
X632526Y253124D01*
X632859Y253457D01*
G01X635792Y251457D02*
X636376Y251124D01*
X637042Y251040D01*
X637626Y251124D01*
X638126Y251540D01*
X638459Y252124D01*
Y256040D01*
G01Y255374D02*
X638126Y255707D01*
X637626Y255957D01*
X637042Y256040D01*
X636376Y255874D01*
X635959Y255540D01*
X635626Y254957D01*
X635459Y254374D01*
X635542Y253874D01*
X635876Y253290D01*
X636376Y252874D01*
X637042Y252707D01*
X637542Y252790D01*
X638126Y253124D01*
X638459Y253457D01*
G01X641309Y254957D02*
X643976D01*
X643726Y255540D01*
X643309Y255874D01*
X642726Y256040D01*
X642142Y255957D01*
X641642Y255707D01*
X641309Y255124D01*
X641142Y254624D01*
Y254124D01*
X641309Y253624D01*
X641726Y253124D01*
X642226Y252790D01*
X642809Y252707D01*
X643392Y252874D01*
X643976Y253374D01*
G01X649659Y257707D02*
Y252707D01*
G01Y253457D02*
X649326Y253040D01*
X648826Y252790D01*
X648242Y252707D01*
X647576Y252874D01*
X647076Y253290D01*
X646742Y253790D01*
X646659Y254374D01*
X646742Y254957D01*
X647076Y255457D01*
X647576Y255874D01*
X648242Y256040D01*
X648826Y255957D01*
X649242Y255790D01*
X649659Y255457D01*
G01X657276Y256040D02*
X658276Y252707D01*
X659359Y256040D01*
X660442Y252707D01*
X661442Y256040D01*
G01X664959D02*
Y252707D01*
G01Y257374D02*
X664792Y257457D01*
Y257624D01*
X664959Y257707D01*
X665126Y257624D01*
Y257457D01*
X664959Y257374D01*
G01X670559Y257707D02*
Y252707D01*
G01X669392Y256040D02*
X671726D01*
G01X674742Y252707D02*
Y257707D01*
G01Y255290D02*
X675159Y255707D01*
X675576Y255957D01*
X676242Y256040D01*
X676742Y255957D01*
X677326Y255624D01*
X677576Y255124D01*
Y252707D01*
G01X689026D02*
X685692Y254374D01*
X689026Y256040D01*
G01X696726Y253457D02*
X697226Y253040D01*
X697809Y252790D01*
X698559Y252707D01*
X699309Y252874D01*
X699892Y253207D01*
X700309Y253790D01*
X700392Y254457D01*
X700226Y255124D01*
X699809Y255540D01*
X699226Y255874D01*
X698642Y255957D01*
X698059Y255874D01*
X697309Y255540D01*
X697559Y257707D01*
X699809D01*
G01X704159D02*
X703492Y257540D01*
X702992Y257124D01*
X702659Y256624D01*
X702409Y255957D01*
X702326Y255207D01*
X702409Y254457D01*
X702659Y253790D01*
X702992Y253290D01*
X703492Y252874D01*
X704159Y252707D01*
X704826Y252874D01*
X705326Y253290D01*
X705659Y253790D01*
X705909Y254457D01*
X705992Y255207D01*
X705909Y255957D01*
X705659Y256624D01*
X705326Y257124D01*
X704826Y257540D01*
X704159Y257707D01*
G01X713859Y252540D02*
X716859Y257707D01*
G01X713859D02*
X713359Y257540D01*
X713109Y257290D01*
X712942Y256790D01*
X713109Y256290D01*
X713359Y256040D01*
X713859Y255874D01*
X714359Y256040D01*
X714609Y256290D01*
X714776Y256790D01*
X714609Y257290D01*
X714359Y257540D01*
X713859Y257707D01*
G01X716859Y254374D02*
X716359Y254207D01*
X716109Y253957D01*
X715942Y253457D01*
X716109Y252957D01*
X716359Y252707D01*
X716859Y252540D01*
X717359Y252707D01*
X717609Y252957D01*
X717776Y253457D01*
X717609Y253957D01*
X717359Y254207D01*
X716859Y254374D01*
G01X725309Y253290D02*
X725726Y252957D01*
X726309Y252707D01*
X726809D01*
X727309Y252874D01*
X727642Y253124D01*
X727809Y253457D01*
X727726Y253957D01*
X727392Y254207D01*
X725892Y254707D01*
X725559Y255290D01*
X725726Y255707D01*
X726059Y255957D01*
X726559Y256040D01*
X727059Y255957D01*
X727559Y255707D01*
G01X732159Y252707D02*
X731659Y252790D01*
X731159Y253124D01*
X730826Y253707D01*
X730659Y254374D01*
X730826Y255040D01*
X731159Y255624D01*
X731659Y255957D01*
X732159Y256040D01*
X732659Y255957D01*
X733159Y255624D01*
X733492Y255040D01*
X733576Y254374D01*
X733492Y253707D01*
X733159Y253124D01*
X732659Y252790D01*
X732159Y252707D01*
G01X737759D02*
Y257707D01*
G01X744859D02*
Y252707D01*
G01Y253457D02*
X744526Y253040D01*
X744026Y252790D01*
X743442Y252707D01*
X742776Y252874D01*
X742276Y253290D01*
X741942Y253790D01*
X741859Y254374D01*
X741942Y254957D01*
X742276Y255457D01*
X742776Y255874D01*
X743442Y256040D01*
X744026Y255957D01*
X744442Y255790D01*
X744859Y255457D01*
G01X747709Y254957D02*
X750376D01*
X750126Y255540D01*
X749709Y255874D01*
X749126Y256040D01*
X748542Y255957D01*
X748042Y255707D01*
X747709Y255124D01*
X747542Y254624D01*
Y254124D01*
X747709Y253624D01*
X748126Y253124D01*
X748626Y252790D01*
X749209Y252707D01*
X749792Y252874D01*
X750376Y253374D01*
G01X753392Y252707D02*
Y256040D01*
G01Y255374D02*
X753809Y255707D01*
X754226Y255957D01*
X754809Y256040D01*
X755226Y255957D01*
X755726Y255707D01*
G01X763259Y252707D02*
Y256040D01*
G01Y255124D02*
X763509Y255540D01*
X763926Y255874D01*
X764509Y256040D01*
X765092Y255874D01*
X765509Y255540D01*
X765759Y255124D01*
Y252707D01*
G01Y255124D02*
X766009Y255540D01*
X766426Y255874D01*
X767009Y256040D01*
X767592Y255874D01*
X768009Y255540D01*
X768259Y255040D01*
Y252707D01*
G01X772859D02*
Y256040D01*
G01Y255457D02*
X772526Y255790D01*
X772026Y255957D01*
X771442Y256040D01*
X770859Y255874D01*
X770359Y255540D01*
X770026Y255040D01*
X769859Y254374D01*
X770026Y253707D01*
X770359Y253207D01*
X770859Y252874D01*
X771442Y252707D01*
X772026Y252790D01*
X772526Y253040D01*
X772859Y253374D01*
G01X775709Y253290D02*
X776126Y252957D01*
X776709Y252707D01*
X777209D01*
X777709Y252874D01*
X778042Y253124D01*
X778209Y253457D01*
X778126Y253957D01*
X777792Y254207D01*
X776292Y254707D01*
X775959Y255290D01*
X776126Y255707D01*
X776459Y255957D01*
X776959Y256040D01*
X777459Y255957D01*
X777959Y255707D01*
G01X781142Y252707D02*
Y257707D01*
G01X783809Y256040D02*
X781142Y254124D01*
G01X782226Y254874D02*
X783976Y252707D01*
G01X787992Y251790D02*
X788326Y252874D01*
G01X533259Y261707D02*
Y265040D01*
G01Y264457D02*
X532926Y264790D01*
X532426Y264957D01*
X531842Y265040D01*
X531259Y264874D01*
X530759Y264540D01*
X530426Y264040D01*
X530259Y263374D01*
X530426Y262707D01*
X530759Y262207D01*
X531259Y261874D01*
X531842Y261707D01*
X532426Y261790D01*
X532926Y262040D01*
X533259Y262374D01*
G01X537359Y261540D02*
X537192Y261624D01*
Y261790D01*
X537359Y261874D01*
X537526Y261790D01*
Y261624D01*
X537359Y261540D01*
G01X543626Y264374D02*
X543959Y264624D01*
X544209Y265040D01*
X544376Y265624D01*
X544209Y266124D01*
X543876Y266457D01*
X543292Y266707D01*
X541042D01*
Y261707D01*
X543792D01*
X544376Y262040D01*
X544709Y262540D01*
X544876Y263124D01*
X544709Y263707D01*
X544209Y264207D01*
X543626Y264374D01*
X541042D01*
G01X548559Y261707D02*
X548059Y261790D01*
X547559Y262124D01*
X547226Y262707D01*
X547059Y263374D01*
X547226Y264040D01*
X547559Y264624D01*
X548059Y264957D01*
X548559Y265040D01*
X549059Y264957D01*
X549559Y264624D01*
X549892Y264040D01*
X549976Y263374D01*
X549892Y262707D01*
X549559Y262124D01*
X549059Y261790D01*
X548559Y261707D01*
G01X555659D02*
Y265040D01*
G01Y264457D02*
X555326Y264790D01*
X554826Y264957D01*
X554242Y265040D01*
X553659Y264874D01*
X553159Y264540D01*
X552826Y264040D01*
X552659Y263374D01*
X552826Y262707D01*
X553159Y262207D01*
X553659Y261874D01*
X554242Y261707D01*
X554826Y261790D01*
X555326Y262040D01*
X555659Y262374D01*
G01X558592Y261707D02*
Y265040D01*
G01Y264374D02*
X559009Y264707D01*
X559426Y264957D01*
X560009Y265040D01*
X560426Y264957D01*
X560926Y264707D01*
G01X566859Y266707D02*
Y261707D01*
G01Y262457D02*
X566526Y262040D01*
X566026Y261790D01*
X565442Y261707D01*
X564776Y261874D01*
X564276Y262290D01*
X563942Y262790D01*
X563859Y263374D01*
X563942Y263957D01*
X564276Y264457D01*
X564776Y264874D01*
X565442Y265040D01*
X566026Y264957D01*
X566442Y264790D01*
X566859Y264457D01*
G01X576559Y266707D02*
Y261707D01*
G01X575392Y265040D02*
X577726D01*
G01X580742Y261707D02*
Y266707D01*
G01Y264290D02*
X581159Y264707D01*
X581576Y264957D01*
X582242Y265040D01*
X582742Y264957D01*
X583326Y264624D01*
X583576Y264124D01*
Y261707D01*
G01X587759Y265040D02*
Y261707D01*
G01Y266374D02*
X587592Y266457D01*
Y266624D01*
X587759Y266707D01*
X587926Y266624D01*
Y266457D01*
X587759Y266374D01*
G01X594692Y264624D02*
X594109Y264957D01*
X593609Y265040D01*
X592942Y264874D01*
X592442Y264540D01*
X592109Y263957D01*
X592026Y263374D01*
X592109Y262790D01*
X592442Y262290D01*
X592942Y261874D01*
X593609Y261707D01*
X594192Y261874D01*
X594692Y262207D01*
G01X597542Y261707D02*
Y266707D01*
G01X600209Y265040D02*
X597542Y263124D01*
G01X598626Y263874D02*
X600376Y261707D01*
G01X603142D02*
Y265040D01*
G01Y264207D02*
X603476Y264624D01*
X603976Y264957D01*
X604642Y265040D01*
X605226Y264957D01*
X605726Y264624D01*
X605976Y264040D01*
Y261707D01*
G01X608909Y263957D02*
X611576D01*
X611326Y264540D01*
X610909Y264874D01*
X610326Y265040D01*
X609742Y264957D01*
X609242Y264707D01*
X608909Y264124D01*
X608742Y263624D01*
Y263124D01*
X608909Y262624D01*
X609326Y262124D01*
X609826Y261790D01*
X610409Y261707D01*
X610992Y261874D01*
X611576Y262374D01*
G01X614509Y262290D02*
X614926Y261957D01*
X615509Y261707D01*
X616009D01*
X616509Y261874D01*
X616842Y262124D01*
X617009Y262457D01*
X616926Y262957D01*
X616592Y263207D01*
X615092Y263707D01*
X614759Y264290D01*
X614926Y264707D01*
X615259Y264957D01*
X615759Y265040D01*
X616259Y264957D01*
X616759Y264707D01*
G01X620109Y262290D02*
X620526Y261957D01*
X621109Y261707D01*
X621609D01*
X622109Y261874D01*
X622442Y262124D01*
X622609Y262457D01*
X622526Y262957D01*
X622192Y263207D01*
X620692Y263707D01*
X620359Y264290D01*
X620526Y264707D01*
X620859Y264957D01*
X621359Y265040D01*
X621859Y264957D01*
X622359Y264707D01*
G01X625292Y261707D02*
X628626Y263374D01*
X625292Y265040D01*
G01X631476Y262624D02*
X633642D01*
G01Y264124D02*
X631476D01*
G01X643759Y266707D02*
X643092Y266540D01*
X642592Y266124D01*
X642259Y265624D01*
X642009Y264957D01*
X641926Y264207D01*
X642009Y263457D01*
X642259Y262790D01*
X642592Y262290D01*
X643092Y261874D01*
X643759Y261707D01*
X644426Y261874D01*
X644926Y262290D01*
X645259Y262790D01*
X645509Y263457D01*
X645592Y264207D01*
X645509Y264957D01*
X645259Y265624D01*
X644926Y266124D01*
X644426Y266540D01*
X643759Y266707D01*
G01X649359Y261540D02*
X649192Y261624D01*
Y261790D01*
X649359Y261874D01*
X649526Y261790D01*
Y261624D01*
X649359Y261540D01*
G01X653542Y262290D02*
X654126Y261874D01*
X654792Y261707D01*
X655459Y261874D01*
X656042Y262374D01*
X656459Y263124D01*
X656626Y263874D01*
Y264790D01*
X656459Y265540D01*
X656042Y266207D01*
X655542Y266540D01*
X654959Y266707D01*
X654292Y266540D01*
X653792Y266207D01*
X653459Y265707D01*
X653292Y265040D01*
X653459Y264457D01*
X653876Y263874D01*
X654376Y263540D01*
X654959Y263457D01*
X655626Y263624D01*
X656126Y264040D01*
X656626Y264790D01*
G01X658059Y261707D02*
Y265040D01*
G01Y264124D02*
X658309Y264540D01*
X658726Y264874D01*
X659309Y265040D01*
X659892Y264874D01*
X660309Y264540D01*
X660559Y264124D01*
Y261707D01*
G01Y264124D02*
X660809Y264540D01*
X661226Y264874D01*
X661809Y265040D01*
X662392Y264874D01*
X662809Y264540D01*
X663059Y264040D01*
Y261707D01*
G01X666159Y261540D02*
X665992Y261624D01*
Y261790D01*
X666159Y261874D01*
X666326Y261790D01*
Y261624D01*
X666159Y261540D01*
G01Y263790D02*
X665992Y263874D01*
Y264040D01*
X666159Y264124D01*
X666326Y264040D01*
Y263874D01*
X666159Y263790D01*
G01X529009Y271707D02*
Y276707D01*
G01X532509D02*
Y271707D01*
G01Y274207D02*
X529009D01*
G01X537859Y271707D02*
Y275040D01*
G01Y274457D02*
X537526Y274790D01*
X537026Y274957D01*
X536442Y275040D01*
X535859Y274874D01*
X535359Y274540D01*
X535026Y274040D01*
X534859Y273374D01*
X535026Y272707D01*
X535359Y272207D01*
X535859Y271874D01*
X536442Y271707D01*
X537026Y271790D01*
X537526Y272040D01*
X537859Y272374D01*
G01X541959Y271707D02*
Y276707D01*
G01X547059Y271707D02*
Y275957D01*
X547226Y276374D01*
X547559Y276624D01*
X548059Y276707D01*
X548559Y276540D01*
X548809Y276124D01*
G01X547809Y274707D02*
X546142D01*
G01X552076Y273374D02*
X554242D01*
G01X557259Y270040D02*
Y275040D01*
G01Y274290D02*
X557676Y274707D01*
X558092Y274957D01*
X558759Y275040D01*
X559342Y274957D01*
X559926Y274540D01*
X560176Y273957D01*
X560259Y273374D01*
X560176Y272790D01*
X559926Y272207D01*
X559426Y271874D01*
X558759Y271707D01*
X558176Y271790D01*
X557592Y272040D01*
X557259Y272374D01*
G01X564359Y271707D02*
Y276707D01*
G01X568542Y275040D02*
Y272707D01*
X568876Y272124D01*
X569376Y271790D01*
X569959Y271707D01*
X570542Y271790D01*
X571042Y272124D01*
X571376Y272707D01*
G01Y271707D02*
Y275040D01*
G01X574392Y270457D02*
X574976Y270124D01*
X575642Y270040D01*
X576226Y270124D01*
X576726Y270540D01*
X577059Y271124D01*
Y275040D01*
G01Y274374D02*
X576726Y274707D01*
X576226Y274957D01*
X575642Y275040D01*
X574976Y274874D01*
X574559Y274540D01*
X574226Y273957D01*
X574059Y273374D01*
X574142Y272874D01*
X574476Y272290D01*
X574976Y271874D01*
X575642Y271707D01*
X576142Y271790D01*
X576726Y272124D01*
X577059Y272457D01*
G01X579992Y270457D02*
X580576Y270124D01*
X581242Y270040D01*
X581826Y270124D01*
X582326Y270540D01*
X582659Y271124D01*
Y275040D01*
G01Y274374D02*
X582326Y274707D01*
X581826Y274957D01*
X581242Y275040D01*
X580576Y274874D01*
X580159Y274540D01*
X579826Y273957D01*
X579659Y273374D01*
X579742Y272874D01*
X580076Y272290D01*
X580576Y271874D01*
X581242Y271707D01*
X581742Y271790D01*
X582326Y272124D01*
X582659Y272457D01*
G01X586759Y275040D02*
Y271707D01*
G01Y276374D02*
X586592Y276457D01*
Y276624D01*
X586759Y276707D01*
X586926Y276624D01*
Y276457D01*
X586759Y276374D01*
G01X590942Y271707D02*
Y275040D01*
G01Y274207D02*
X591276Y274624D01*
X591776Y274957D01*
X592442Y275040D01*
X593026Y274957D01*
X593526Y274624D01*
X593776Y274040D01*
Y271707D01*
G01X596792Y270457D02*
X597376Y270124D01*
X598042Y270040D01*
X598626Y270124D01*
X599126Y270540D01*
X599459Y271124D01*
Y275040D01*
G01Y274374D02*
X599126Y274707D01*
X598626Y274957D01*
X598042Y275040D01*
X597376Y274874D01*
X596959Y274540D01*
X596626Y273957D01*
X596459Y273374D01*
X596542Y272874D01*
X596876Y272290D01*
X597376Y271874D01*
X598042Y271707D01*
X598542Y271790D01*
X599126Y272124D01*
X599459Y272457D01*
G01X609159Y271540D02*
X608992Y271624D01*
Y271790D01*
X609159Y271874D01*
X609326Y271790D01*
Y271624D01*
X609159Y271540D01*
G01Y273790D02*
X608992Y273874D01*
Y274040D01*
X609159Y274124D01*
X609326Y274040D01*
Y273874D01*
X609159Y273790D01*
G01X620359Y276707D02*
Y271707D01*
G01X619192Y275040D02*
X621526D01*
G01X624542Y271707D02*
Y276707D01*
G01Y274290D02*
X624959Y274707D01*
X625376Y274957D01*
X626042Y275040D01*
X626542Y274957D01*
X627126Y274624D01*
X627376Y274124D01*
Y271707D01*
G01X630309Y273957D02*
X632976D01*
X632726Y274540D01*
X632309Y274874D01*
X631726Y275040D01*
X631142Y274957D01*
X630642Y274707D01*
X630309Y274124D01*
X630142Y273624D01*
Y273124D01*
X630309Y272624D01*
X630726Y272124D01*
X631226Y271790D01*
X631809Y271707D01*
X632392Y271874D01*
X632976Y272374D01*
G01X641259Y270040D02*
Y275040D01*
G01Y274290D02*
X641676Y274707D01*
X642092Y274957D01*
X642759Y275040D01*
X643342Y274957D01*
X643926Y274540D01*
X644176Y273957D01*
X644259Y273374D01*
X644176Y272790D01*
X643926Y272207D01*
X643426Y271874D01*
X642759Y271707D01*
X642176Y271790D01*
X641592Y272040D01*
X641259Y272374D01*
G01X648359Y271707D02*
Y276707D01*
G01X652542Y275040D02*
Y272707D01*
X652876Y272124D01*
X653376Y271790D01*
X653959Y271707D01*
X654542Y271790D01*
X655042Y272124D01*
X655376Y272707D01*
G01Y271707D02*
Y275040D01*
G01X658392Y270457D02*
X658976Y270124D01*
X659642Y270040D01*
X660226Y270124D01*
X660726Y270540D01*
X661059Y271124D01*
Y275040D01*
G01Y274374D02*
X660726Y274707D01*
X660226Y274957D01*
X659642Y275040D01*
X658976Y274874D01*
X658559Y274540D01*
X658226Y273957D01*
X658059Y273374D01*
X658142Y272874D01*
X658476Y272290D01*
X658976Y271874D01*
X659642Y271707D01*
X660142Y271790D01*
X660726Y272124D01*
X661059Y272457D01*
G01X663992Y270457D02*
X664576Y270124D01*
X665242Y270040D01*
X665826Y270124D01*
X666326Y270540D01*
X666659Y271124D01*
Y275040D01*
G01Y274374D02*
X666326Y274707D01*
X665826Y274957D01*
X665242Y275040D01*
X664576Y274874D01*
X664159Y274540D01*
X663826Y273957D01*
X663659Y273374D01*
X663742Y272874D01*
X664076Y272290D01*
X664576Y271874D01*
X665242Y271707D01*
X665742Y271790D01*
X666326Y272124D01*
X666659Y272457D01*
G01X670759Y275040D02*
Y271707D01*
G01Y276374D02*
X670592Y276457D01*
Y276624D01*
X670759Y276707D01*
X670926Y276624D01*
Y276457D01*
X670759Y276374D01*
G01X674942Y271707D02*
Y275040D01*
G01Y274207D02*
X675276Y274624D01*
X675776Y274957D01*
X676442Y275040D01*
X677026Y274957D01*
X677526Y274624D01*
X677776Y274040D01*
Y271707D01*
G01X680792Y270457D02*
X681376Y270124D01*
X682042Y270040D01*
X682626Y270124D01*
X683126Y270540D01*
X683459Y271124D01*
Y275040D01*
G01Y274374D02*
X683126Y274707D01*
X682626Y274957D01*
X682042Y275040D01*
X681376Y274874D01*
X680959Y274540D01*
X680626Y273957D01*
X680459Y273374D01*
X680542Y272874D01*
X680876Y272290D01*
X681376Y271874D01*
X682042Y271707D01*
X682542Y271790D01*
X683126Y272124D01*
X683459Y272457D01*
G01X691992Y271707D02*
Y275040D01*
G01Y274374D02*
X692409Y274707D01*
X692826Y274957D01*
X693409Y275040D01*
X693826Y274957D01*
X694326Y274707D01*
G01X700259Y271707D02*
Y275040D01*
G01Y274457D02*
X699926Y274790D01*
X699426Y274957D01*
X698842Y275040D01*
X698259Y274874D01*
X697759Y274540D01*
X697426Y274040D01*
X697259Y273374D01*
X697426Y272707D01*
X697759Y272207D01*
X698259Y271874D01*
X698842Y271707D01*
X699426Y271790D01*
X699926Y272040D01*
X700259Y272374D01*
G01X704359Y276707D02*
Y271707D01*
G01X703192Y275040D02*
X705526D01*
G01X709959D02*
Y271707D01*
G01Y276374D02*
X709792Y276457D01*
Y276624D01*
X709959Y276707D01*
X710126Y276624D01*
Y276457D01*
X709959Y276374D01*
G01X715559Y271707D02*
X715059Y271790D01*
X714559Y272124D01*
X714226Y272707D01*
X714059Y273374D01*
X714226Y274040D01*
X714559Y274624D01*
X715059Y274957D01*
X715559Y275040D01*
X716059Y274957D01*
X716559Y274624D01*
X716892Y274040D01*
X716976Y273374D01*
X716892Y272707D01*
X716559Y272124D01*
X716059Y271790D01*
X715559Y271707D01*
G01X725259Y270040D02*
Y275040D01*
G01Y274290D02*
X725676Y274707D01*
X726092Y274957D01*
X726759Y275040D01*
X727342Y274957D01*
X727926Y274540D01*
X728176Y273957D01*
X728259Y273374D01*
X728176Y272790D01*
X727926Y272207D01*
X727426Y271874D01*
X726759Y271707D01*
X726176Y271790D01*
X725592Y272040D01*
X725259Y272374D01*
G01X731109Y273957D02*
X733776D01*
X733526Y274540D01*
X733109Y274874D01*
X732526Y275040D01*
X731942Y274957D01*
X731442Y274707D01*
X731109Y274124D01*
X730942Y273624D01*
Y273124D01*
X731109Y272624D01*
X731526Y272124D01*
X732026Y271790D01*
X732609Y271707D01*
X733192Y271874D01*
X733776Y272374D01*
G01X736792Y271707D02*
Y275040D01*
G01Y274374D02*
X737209Y274707D01*
X737626Y274957D01*
X738209Y275040D01*
X738626Y274957D01*
X739126Y274707D01*
G01X748659Y271707D02*
Y275957D01*
X748826Y276374D01*
X749159Y276624D01*
X749659Y276707D01*
X750159Y276540D01*
X750409Y276124D01*
G01X749409Y274707D02*
X747742D01*
G01X754759Y271707D02*
X754259Y271790D01*
X753759Y272124D01*
X753426Y272707D01*
X753259Y273374D01*
X753426Y274040D01*
X753759Y274624D01*
X754259Y274957D01*
X754759Y275040D01*
X755259Y274957D01*
X755759Y274624D01*
X756092Y274040D01*
X756176Y273374D01*
X756092Y272707D01*
X755759Y272124D01*
X755259Y271790D01*
X754759Y271707D01*
G01X760359D02*
Y276707D01*
G01X765959Y271707D02*
Y276707D01*
G01X771559Y271707D02*
X771059Y271790D01*
X770559Y272124D01*
X770226Y272707D01*
X770059Y273374D01*
X770226Y274040D01*
X770559Y274624D01*
X771059Y274957D01*
X771559Y275040D01*
X772059Y274957D01*
X772559Y274624D01*
X772892Y274040D01*
X772976Y273374D01*
X772892Y272707D01*
X772559Y272124D01*
X772059Y271790D01*
X771559Y271707D01*
G01X775076Y275040D02*
X776076Y271707D01*
X777159Y275040D01*
X778242Y271707D01*
X779242Y275040D01*
G01X782759D02*
Y271707D01*
G01Y276374D02*
X782592Y276457D01*
Y276624D01*
X782759Y276707D01*
X782926Y276624D01*
Y276457D01*
X782759Y276374D01*
G01X786942Y271707D02*
Y275040D01*
G01Y274207D02*
X787276Y274624D01*
X787776Y274957D01*
X788442Y275040D01*
X789026Y274957D01*
X789526Y274624D01*
X789776Y274040D01*
Y271707D01*
G01X792792Y270457D02*
X793376Y270124D01*
X794042Y270040D01*
X794626Y270124D01*
X795126Y270540D01*
X795459Y271124D01*
Y275040D01*
G01Y274374D02*
X795126Y274707D01*
X794626Y274957D01*
X794042Y275040D01*
X793376Y274874D01*
X792959Y274540D01*
X792626Y273957D01*
X792459Y273374D01*
X792542Y272874D01*
X792876Y272290D01*
X793376Y271874D01*
X794042Y271707D01*
X794542Y271790D01*
X795126Y272124D01*
X795459Y272457D01*
G01X799559Y271540D02*
X799392Y271624D01*
Y271790D01*
X799559Y271874D01*
X799726Y271790D01*
Y271624D01*
X799559Y271540D01*
G01Y273790D02*
X799392Y273874D01*
Y274040D01*
X799559Y274124D01*
X799726Y274040D01*
Y273874D01*
X799559Y273790D01*
G01X528259Y280707D02*
Y285707D01*
G01Y283207D02*
X528676Y283707D01*
X529176Y283957D01*
X529676Y284040D01*
X530426Y283874D01*
X530926Y283540D01*
X531259Y282957D01*
Y282290D01*
X531092Y281624D01*
X530759Y281124D01*
X530176Y280790D01*
X529676Y280707D01*
X529176Y280790D01*
X528676Y281040D01*
X528259Y281457D01*
G01X534109Y282957D02*
X536776D01*
X536526Y283540D01*
X536109Y283874D01*
X535526Y284040D01*
X534942Y283957D01*
X534442Y283707D01*
X534109Y283124D01*
X533942Y282624D01*
Y282124D01*
X534109Y281624D01*
X534526Y281124D01*
X535026Y280790D01*
X535609Y280707D01*
X536192Y280874D01*
X536776Y281374D01*
G01X546059Y280707D02*
Y284957D01*
X546226Y285374D01*
X546559Y285624D01*
X547059Y285707D01*
X547559Y285540D01*
X547809Y285124D01*
G01X546809Y283707D02*
X545142D01*
G01X550992Y280707D02*
Y284040D01*
G01Y283374D02*
X551409Y283707D01*
X551826Y283957D01*
X552409Y284040D01*
X552826Y283957D01*
X553326Y283707D01*
G01X556509Y282957D02*
X559176D01*
X558926Y283540D01*
X558509Y283874D01*
X557926Y284040D01*
X557342Y283957D01*
X556842Y283707D01*
X556509Y283124D01*
X556342Y282624D01*
Y282124D01*
X556509Y281624D01*
X556926Y281124D01*
X557426Y280790D01*
X558009Y280707D01*
X558592Y280874D01*
X559176Y281374D01*
G01X562109Y282957D02*
X564776D01*
X564526Y283540D01*
X564109Y283874D01*
X563526Y284040D01*
X562942Y283957D01*
X562442Y283707D01*
X562109Y283124D01*
X561942Y282624D01*
Y282124D01*
X562109Y281624D01*
X562526Y281124D01*
X563026Y280790D01*
X563609Y280707D01*
X564192Y280874D01*
X564776Y281374D01*
G01X574059Y280707D02*
Y284957D01*
X574226Y285374D01*
X574559Y285624D01*
X575059Y285707D01*
X575559Y285540D01*
X575809Y285124D01*
G01X574809Y283707D02*
X573142D01*
G01X578992Y280707D02*
Y284040D01*
G01Y283374D02*
X579409Y283707D01*
X579826Y283957D01*
X580409Y284040D01*
X580826Y283957D01*
X581326Y283707D01*
G01X585759Y280707D02*
X585259Y280790D01*
X584759Y281124D01*
X584426Y281707D01*
X584259Y282374D01*
X584426Y283040D01*
X584759Y283624D01*
X585259Y283957D01*
X585759Y284040D01*
X586259Y283957D01*
X586759Y283624D01*
X587092Y283040D01*
X587176Y282374D01*
X587092Y281707D01*
X586759Y281124D01*
X586259Y280790D01*
X585759Y280707D01*
G01X588859D02*
Y284040D01*
G01Y283124D02*
X589109Y283540D01*
X589526Y283874D01*
X590109Y284040D01*
X590692Y283874D01*
X591109Y283540D01*
X591359Y283124D01*
Y280707D01*
G01Y283124D02*
X591609Y283540D01*
X592026Y283874D01*
X592609Y284040D01*
X593192Y283874D01*
X593609Y283540D01*
X593859Y283040D01*
Y280707D01*
G01X601309Y281290D02*
X601726Y280957D01*
X602309Y280707D01*
X602809D01*
X603309Y280874D01*
X603642Y281124D01*
X603809Y281457D01*
X603726Y281957D01*
X603392Y282207D01*
X601892Y282707D01*
X601559Y283290D01*
X601726Y283707D01*
X602059Y283957D01*
X602559Y284040D01*
X603059Y283957D01*
X603559Y283707D01*
G01X608159Y280707D02*
X607659Y280790D01*
X607159Y281124D01*
X606826Y281707D01*
X606659Y282374D01*
X606826Y283040D01*
X607159Y283624D01*
X607659Y283957D01*
X608159Y284040D01*
X608659Y283957D01*
X609159Y283624D01*
X609492Y283040D01*
X609576Y282374D01*
X609492Y281707D01*
X609159Y281124D01*
X608659Y280790D01*
X608159Y280707D01*
G01X613759D02*
Y285707D01*
G01X620859D02*
Y280707D01*
G01Y281457D02*
X620526Y281040D01*
X620026Y280790D01*
X619442Y280707D01*
X618776Y280874D01*
X618276Y281290D01*
X617942Y281790D01*
X617859Y282374D01*
X617942Y282957D01*
X618276Y283457D01*
X618776Y283874D01*
X619442Y284040D01*
X620026Y283957D01*
X620442Y283790D01*
X620859Y283457D01*
G01X623709Y282957D02*
X626376D01*
X626126Y283540D01*
X625709Y283874D01*
X625126Y284040D01*
X624542Y283957D01*
X624042Y283707D01*
X623709Y283124D01*
X623542Y282624D01*
Y282124D01*
X623709Y281624D01*
X624126Y281124D01*
X624626Y280790D01*
X625209Y280707D01*
X625792Y280874D01*
X626376Y281374D01*
G01X629392Y280707D02*
Y284040D01*
G01Y283374D02*
X629809Y283707D01*
X630226Y283957D01*
X630809Y284040D01*
X631226Y283957D01*
X631726Y283707D01*
G01X639259Y280707D02*
Y284040D01*
G01Y283124D02*
X639509Y283540D01*
X639926Y283874D01*
X640509Y284040D01*
X641092Y283874D01*
X641509Y283540D01*
X641759Y283124D01*
Y280707D01*
G01Y283124D02*
X642009Y283540D01*
X642426Y283874D01*
X643009Y284040D01*
X643592Y283874D01*
X644009Y283540D01*
X644259Y283040D01*
Y280707D01*
G01X648859D02*
Y284040D01*
G01Y283457D02*
X648526Y283790D01*
X648026Y283957D01*
X647442Y284040D01*
X646859Y283874D01*
X646359Y283540D01*
X646026Y283040D01*
X645859Y282374D01*
X646026Y281707D01*
X646359Y281207D01*
X646859Y280874D01*
X647442Y280707D01*
X648026Y280790D01*
X648526Y281040D01*
X648859Y281374D01*
G01X651709Y281290D02*
X652126Y280957D01*
X652709Y280707D01*
X653209D01*
X653709Y280874D01*
X654042Y281124D01*
X654209Y281457D01*
X654126Y281957D01*
X653792Y282207D01*
X652292Y282707D01*
X651959Y283290D01*
X652126Y283707D01*
X652459Y283957D01*
X652959Y284040D01*
X653459Y283957D01*
X653959Y283707D01*
G01X657142Y280707D02*
Y285707D01*
G01X659809Y284040D02*
X657142Y282124D01*
G01X658226Y282874D02*
X659976Y280707D01*
G01X664159Y280540D02*
X663992Y280624D01*
Y280790D01*
X664159Y280874D01*
X664326Y280790D01*
Y280624D01*
X664159Y280540D01*
G01X601176Y486707D02*
X603259Y481707D01*
X605342Y486707D01*
G01X607859D02*
X609859D01*
G01X608859D02*
Y481707D01*
G01X607859D02*
X609859D01*
G01X612792D02*
Y486707D01*
X614792D01*
X615459Y486457D01*
X615959Y485874D01*
X616126Y485207D01*
X615959Y484540D01*
X615542Y484040D01*
X614792Y483790D01*
X612792D01*
G01X679426Y-98426D02*
X679759Y-98176D01*
X680009Y-97760D01*
X680176Y-97176D01*
X680009Y-96676D01*
X679676Y-96343D01*
X679092Y-96093D01*
X676842D01*
Y-101093D01*
X679592D01*
X680176Y-100760D01*
X680509Y-100260D01*
X680676Y-99676D01*
X680509Y-99093D01*
X680009Y-98593D01*
X679426Y-98426D01*
X676842D01*
G01X682276Y-101093D02*
X684359Y-96093D01*
X686442Y-101093D01*
G01X685692Y-99343D02*
X683026D01*
G01X691792Y-96510D02*
X691292Y-96260D01*
X690709Y-96093D01*
X690042D01*
X689292Y-96343D01*
X688709Y-96760D01*
X688292Y-97260D01*
X687959Y-98093D01*
X687876Y-98843D01*
X688042Y-99593D01*
X688292Y-100093D01*
X688792Y-100593D01*
X689376Y-100926D01*
X689959Y-101093D01*
X690542D01*
X691126Y-100926D01*
X691626Y-100676D01*
X692042Y-100343D01*
G01X693726Y-101093D02*
Y-96093D01*
G01X696892D02*
X693726Y-99176D01*
G01X697392Y-101093D02*
X695142Y-97760D01*
G01X704926Y-101093D02*
Y-96093D01*
X706592D01*
X707259Y-96343D01*
X707759Y-96676D01*
X708176Y-97176D01*
X708509Y-97760D01*
X708592Y-98593D01*
X708509Y-99426D01*
X708176Y-100010D01*
X707759Y-100510D01*
X707259Y-100843D01*
X706592Y-101093D01*
X704926D01*
G01X710692D02*
Y-96093D01*
X712776D01*
X713442Y-96343D01*
X713859Y-96676D01*
X714026Y-97343D01*
X713859Y-98010D01*
X713359Y-98426D01*
X712776Y-98676D01*
X710692D01*
G01X712776D02*
X714026Y-101093D01*
G01X716959Y-96093D02*
X718959D01*
G01X717959D02*
Y-101093D01*
G01X716959D02*
X718959D01*
G01X721892Y-96093D02*
Y-101093D01*
X725226D01*
G01X727492Y-96093D02*
Y-101093D01*
X730826D01*
G01X754659D02*
Y-97760D01*
G01Y-98676D02*
X754909Y-98260D01*
X755326Y-97926D01*
X755909Y-97760D01*
X756492Y-97926D01*
X756909Y-98260D01*
X757159Y-98676D01*
Y-101093D01*
G01Y-98676D02*
X757409Y-98260D01*
X757826Y-97926D01*
X758409Y-97760D01*
X758992Y-97926D01*
X759409Y-98260D01*
X759659Y-98760D01*
Y-101093D01*
G01X762759Y-97760D02*
Y-101093D01*
G01Y-96426D02*
X762592Y-96343D01*
Y-96176D01*
X762759Y-96093D01*
X762926Y-96176D01*
Y-96343D01*
X762759Y-96426D01*
G01X768359Y-101093D02*
Y-96093D01*
G01X772709Y-100510D02*
X773126Y-100843D01*
X773709Y-101093D01*
X774209D01*
X774709Y-100926D01*
X775042Y-100676D01*
X775209Y-100343D01*
X775126Y-99843D01*
X774792Y-99593D01*
X773292Y-99093D01*
X772959Y-98510D01*
X773126Y-98093D01*
X773459Y-97843D01*
X773959Y-97760D01*
X774459Y-97843D01*
X774959Y-98093D01*
G01X779142Y-102760D02*
X778309Y-101926D01*
X777892Y-101093D01*
Y-97760D01*
X778309Y-96926D01*
X779142Y-96093D01*
G01X783242Y-101093D02*
Y-96093D01*
X787076Y-101093D01*
Y-96093D01*
G01X789092Y-101093D02*
Y-96093D01*
X791092D01*
X791759Y-96343D01*
X792259Y-96926D01*
X792426Y-97593D01*
X792259Y-98260D01*
X791842Y-98760D01*
X791092Y-99010D01*
X789092D01*
G01X796359Y-96093D02*
Y-101093D01*
G01X794442Y-96093D02*
X798276D01*
G01X800209Y-101093D02*
Y-96093D01*
G01X803709D02*
Y-101093D01*
G01Y-98593D02*
X800209D01*
G01X807976Y-102760D02*
X808809Y-101926D01*
X809226Y-101093D01*
Y-97760D01*
X808809Y-96926D01*
X807976Y-96093D01*
G01X630926Y-91093D02*
Y-86093D01*
X632592D01*
X633259Y-86343D01*
X633759Y-86676D01*
X634176Y-87176D01*
X634509Y-87760D01*
X634592Y-88593D01*
X634509Y-89426D01*
X634176Y-90010D01*
X633759Y-90510D01*
X633259Y-90843D01*
X632592Y-91093D01*
X630926D01*
G01X636776Y-86926D02*
X637276Y-86426D01*
X637859Y-86176D01*
X638526Y-86093D01*
X639359Y-86260D01*
X639942Y-86676D01*
X640109Y-87176D01*
X640026Y-87676D01*
X639692Y-88093D01*
X638026Y-88926D01*
X637276Y-89510D01*
X636776Y-90343D01*
X636609Y-91093D01*
X640109D01*
G01X673509Y66707D02*
Y71707D01*
G01X677009D02*
Y66707D01*
G01Y69207D02*
X673509D01*
G01X680859Y66707D02*
X680192Y66790D01*
X679609Y67124D01*
X679109Y67624D01*
X678776Y68207D01*
X678609Y68874D01*
Y69540D01*
X678776Y70207D01*
X679109Y70790D01*
X679609Y71290D01*
X680192Y71624D01*
X680859Y71707D01*
X681526Y71624D01*
X682109Y71290D01*
X682609Y70790D01*
X682942Y70207D01*
X683109Y69540D01*
Y68874D01*
X682942Y68207D01*
X682609Y67624D01*
X682109Y67124D01*
X681526Y66790D01*
X680859Y66707D01*
G01X684792Y71707D02*
Y66707D01*
X688126D01*
G01X693726D02*
X690392D01*
Y71707D01*
X693726D01*
G01X692392Y69290D02*
X690392D01*
G01X717559Y66707D02*
Y70040D01*
G01Y69124D02*
X717809Y69540D01*
X718226Y69874D01*
X718809Y70040D01*
X719392Y69874D01*
X719809Y69540D01*
X720059Y69124D01*
Y66707D01*
G01Y69124D02*
X720309Y69540D01*
X720726Y69874D01*
X721309Y70040D01*
X721892Y69874D01*
X722309Y69540D01*
X722559Y69040D01*
Y66707D01*
G01X725659Y70040D02*
Y66707D01*
G01Y71374D02*
X725492Y71457D01*
Y71624D01*
X725659Y71707D01*
X725826Y71624D01*
Y71457D01*
X725659Y71374D01*
G01X731259Y66707D02*
Y71707D01*
G01X735609Y67290D02*
X736026Y66957D01*
X736609Y66707D01*
X737109D01*
X737609Y66874D01*
X737942Y67124D01*
X738109Y67457D01*
X738026Y67957D01*
X737692Y68207D01*
X736192Y68707D01*
X735859Y69290D01*
X736026Y69707D01*
X736359Y69957D01*
X736859Y70040D01*
X737359Y69957D01*
X737859Y69707D01*
G01X742042Y65040D02*
X741209Y65874D01*
X740792Y66707D01*
Y70040D01*
X741209Y70874D01*
X742042Y71707D01*
G01X746392Y66707D02*
Y71707D01*
X748392D01*
X749059Y71457D01*
X749559Y70874D01*
X749726Y70207D01*
X749559Y69540D01*
X749142Y69040D01*
X748392Y68790D01*
X746392D01*
G01X753659Y71707D02*
Y66707D01*
G01X751742Y71707D02*
X755576D01*
G01X757509Y66707D02*
Y71707D01*
G01X761009D02*
Y66707D01*
G01Y69207D02*
X757509D01*
G01X765276Y65040D02*
X766109Y65874D01*
X766526Y66707D01*
Y70040D01*
X766109Y70874D01*
X765276Y71707D01*
G01X629926Y66907D02*
Y71907D01*
X631592D01*
X632259Y71657D01*
X632759Y71324D01*
X633176Y70824D01*
X633509Y70240D01*
X633592Y69407D01*
X633509Y68574D01*
X633176Y67990D01*
X632759Y67490D01*
X632259Y67157D01*
X631592Y66907D01*
X629926D01*
G01X637359D02*
Y71907D01*
X636359Y70907D01*
G01Y66907D02*
X638359D01*
G01X631592Y371124D02*
X631009Y371457D01*
X630509Y371540D01*
X629842Y371374D01*
X629342Y371040D01*
X629009Y370457D01*
X628926Y369874D01*
X629009Y369290D01*
X629342Y368790D01*
X629842Y368374D01*
X630509Y368207D01*
X631092Y368374D01*
X631592Y368707D01*
G01X635859Y368207D02*
X635359Y368290D01*
X634859Y368624D01*
X634526Y369207D01*
X634359Y369874D01*
X634526Y370540D01*
X634859Y371124D01*
X635359Y371457D01*
X635859Y371540D01*
X636359Y371457D01*
X636859Y371124D01*
X637192Y370540D01*
X637276Y369874D01*
X637192Y369207D01*
X636859Y368624D01*
X636359Y368290D01*
X635859Y368207D01*
G01X639959Y366540D02*
Y371540D01*
G01Y370790D02*
X640376Y371207D01*
X640792Y371457D01*
X641459Y371540D01*
X642042Y371457D01*
X642626Y371040D01*
X642876Y370457D01*
X642959Y369874D01*
X642876Y369290D01*
X642626Y368707D01*
X642126Y368374D01*
X641459Y368207D01*
X640876Y368290D01*
X640292Y368540D01*
X639959Y368874D01*
G01X645559Y366540D02*
Y371540D01*
G01Y370790D02*
X645976Y371207D01*
X646392Y371457D01*
X647059Y371540D01*
X647642Y371457D01*
X648226Y371040D01*
X648476Y370457D01*
X648559Y369874D01*
X648476Y369290D01*
X648226Y368707D01*
X647726Y368374D01*
X647059Y368207D01*
X646476Y368290D01*
X645892Y368540D01*
X645559Y368874D01*
G01X651409Y370457D02*
X654076D01*
X653826Y371040D01*
X653409Y371374D01*
X652826Y371540D01*
X652242Y371457D01*
X651742Y371207D01*
X651409Y370624D01*
X651242Y370124D01*
Y369624D01*
X651409Y369124D01*
X651826Y368624D01*
X652326Y368290D01*
X652909Y368207D01*
X653492Y368374D01*
X654076Y368874D01*
G01X657092Y368207D02*
Y371540D01*
G01Y370874D02*
X657509Y371207D01*
X657926Y371457D01*
X658509Y371540D01*
X658926Y371457D01*
X659426Y371207D01*
G01X604592Y341707D02*
Y346707D01*
X606592D01*
X607259Y346457D01*
X607759Y345874D01*
X607926Y345207D01*
X607759Y344540D01*
X607342Y344040D01*
X606592Y343790D01*
X604592D01*
G01X611859Y341707D02*
Y346707D01*
G01X616042Y345040D02*
Y342707D01*
X616376Y342124D01*
X616876Y341790D01*
X617459Y341707D01*
X618042Y341790D01*
X618542Y342124D01*
X618876Y342707D01*
G01Y341707D02*
Y345040D01*
G01X621892Y340457D02*
X622476Y340124D01*
X623142Y340040D01*
X623726Y340124D01*
X624226Y340540D01*
X624559Y341124D01*
Y345040D01*
G01Y344374D02*
X624226Y344707D01*
X623726Y344957D01*
X623142Y345040D01*
X622476Y344874D01*
X622059Y344540D01*
X621726Y343957D01*
X621559Y343374D01*
X621642Y342874D01*
X621976Y342290D01*
X622476Y341874D01*
X623142Y341707D01*
X623642Y341790D01*
X624226Y342124D01*
X624559Y342457D01*
G01X627492Y340457D02*
X628076Y340124D01*
X628742Y340040D01*
X629326Y340124D01*
X629826Y340540D01*
X630159Y341124D01*
Y345040D01*
G01Y344374D02*
X629826Y344707D01*
X629326Y344957D01*
X628742Y345040D01*
X628076Y344874D01*
X627659Y344540D01*
X627326Y343957D01*
X627159Y343374D01*
X627242Y342874D01*
X627576Y342290D01*
X628076Y341874D01*
X628742Y341707D01*
X629242Y341790D01*
X629826Y342124D01*
X630159Y342457D01*
G01X634259Y345040D02*
Y341707D01*
G01Y346374D02*
X634092Y346457D01*
Y346624D01*
X634259Y346707D01*
X634426Y346624D01*
Y346457D01*
X634259Y346374D01*
G01X638442Y341707D02*
Y345040D01*
G01Y344207D02*
X638776Y344624D01*
X639276Y344957D01*
X639942Y345040D01*
X640526Y344957D01*
X641026Y344624D01*
X641276Y344040D01*
Y341707D01*
G01X644292Y340457D02*
X644876Y340124D01*
X645542Y340040D01*
X646126Y340124D01*
X646626Y340540D01*
X646959Y341124D01*
Y345040D01*
G01Y344374D02*
X646626Y344707D01*
X646126Y344957D01*
X645542Y345040D01*
X644876Y344874D01*
X644459Y344540D01*
X644126Y343957D01*
X643959Y343374D01*
X644042Y342874D01*
X644376Y342290D01*
X644876Y341874D01*
X645542Y341707D01*
X646042Y341790D01*
X646626Y342124D01*
X646959Y342457D01*
G01X657992Y344624D02*
X657409Y344957D01*
X656909Y345040D01*
X656242Y344874D01*
X655742Y344540D01*
X655409Y343957D01*
X655326Y343374D01*
X655409Y342790D01*
X655742Y342290D01*
X656242Y341874D01*
X656909Y341707D01*
X657492Y341874D01*
X657992Y342207D01*
G01X661092Y341707D02*
Y345040D01*
G01Y344374D02*
X661509Y344707D01*
X661926Y344957D01*
X662509Y345040D01*
X662926Y344957D01*
X663426Y344707D01*
G01X667859Y345040D02*
Y341707D01*
G01Y346374D02*
X667692Y346457D01*
Y346624D01*
X667859Y346707D01*
X668026Y346624D01*
Y346457D01*
X667859Y346374D01*
G01X673459Y346707D02*
Y341707D01*
G01X672292Y345040D02*
X674626D01*
G01X677809Y343957D02*
X680476D01*
X680226Y344540D01*
X679809Y344874D01*
X679226Y345040D01*
X678642Y344957D01*
X678142Y344707D01*
X677809Y344124D01*
X677642Y343624D01*
Y343124D01*
X677809Y342624D01*
X678226Y342124D01*
X678726Y341790D01*
X679309Y341707D01*
X679892Y341874D01*
X680476Y342374D01*
G01X683492Y341707D02*
Y345040D01*
G01Y344374D02*
X683909Y344707D01*
X684326Y344957D01*
X684909Y345040D01*
X685326Y344957D01*
X685826Y344707D01*
G01X690259Y345040D02*
Y341707D01*
G01Y346374D02*
X690092Y346457D01*
Y346624D01*
X690259Y346707D01*
X690426Y346624D01*
Y346457D01*
X690259Y346374D01*
G01X697359Y341707D02*
Y345040D01*
G01Y344457D02*
X697026Y344790D01*
X696526Y344957D01*
X695942Y345040D01*
X695359Y344874D01*
X694859Y344540D01*
X694526Y344040D01*
X694359Y343374D01*
X694526Y342707D01*
X694859Y342207D01*
X695359Y341874D01*
X695942Y341707D01*
X696526Y341790D01*
X697026Y342040D01*
X697359Y342374D01*
G01X675176Y485707D02*
X677259Y480707D01*
X679342Y485707D01*
G01X682859Y480707D02*
X682192Y480790D01*
X681609Y481124D01*
X681109Y481624D01*
X680776Y482207D01*
X680609Y482874D01*
Y483540D01*
X680776Y484207D01*
X681109Y484790D01*
X681609Y485290D01*
X682192Y485624D01*
X682859Y485707D01*
X683526Y485624D01*
X684109Y485290D01*
X684609Y484790D01*
X684942Y484207D01*
X685109Y483540D01*
Y482874D01*
X684942Y482207D01*
X684609Y481624D01*
X684109Y481124D01*
X683526Y480790D01*
X682859Y480707D01*
G01X686792D02*
Y485707D01*
X688792D01*
X689459Y485457D01*
X689959Y484874D01*
X690126Y484207D01*
X689959Y483540D01*
X689542Y483040D01*
X688792Y482790D01*
X686792D01*
G01X705092Y-30093D02*
Y-35093D01*
X708426D01*
G01X711109Y-31760D02*
X713609Y-35093D01*
G01Y-31760D02*
X711109Y-35093D01*
G01X713009Y32790D02*
X713426Y32457D01*
X714009Y32207D01*
X714509D01*
X715009Y32374D01*
X715342Y32624D01*
X715509Y32957D01*
X715426Y33457D01*
X715092Y33707D01*
X713592Y34207D01*
X713259Y34790D01*
X713426Y35207D01*
X713759Y35457D01*
X714259Y35540D01*
X714759Y35457D01*
X715259Y35207D01*
G01X719859Y37207D02*
Y32207D01*
G01X718692Y35540D02*
X721026D01*
G01X724042D02*
Y33207D01*
X724376Y32624D01*
X724876Y32290D01*
X725459Y32207D01*
X726042Y32290D01*
X726542Y32624D01*
X726876Y33207D01*
G01Y32207D02*
Y35540D01*
G01X729559Y32207D02*
Y37207D01*
G01Y34707D02*
X729976Y35207D01*
X730476Y35457D01*
X730976Y35540D01*
X731726Y35374D01*
X732226Y35040D01*
X732559Y34457D01*
Y33790D01*
X732392Y33124D01*
X732059Y32624D01*
X731476Y32290D01*
X730976Y32207D01*
X730476Y32290D01*
X729976Y32540D01*
X729559Y32957D01*
G01X742259Y32207D02*
Y37207D01*
G01X746609Y34457D02*
X749276D01*
X749026Y35040D01*
X748609Y35374D01*
X748026Y35540D01*
X747442Y35457D01*
X746942Y35207D01*
X746609Y34624D01*
X746442Y34124D01*
Y33624D01*
X746609Y33124D01*
X747026Y32624D01*
X747526Y32290D01*
X748109Y32207D01*
X748692Y32374D01*
X749276Y32874D01*
G01X752042Y32207D02*
Y35540D01*
G01Y34707D02*
X752376Y35124D01*
X752876Y35457D01*
X753542Y35540D01*
X754126Y35457D01*
X754626Y35124D01*
X754876Y34540D01*
Y32207D01*
G01X757892Y30957D02*
X758476Y30624D01*
X759142Y30540D01*
X759726Y30624D01*
X760226Y31040D01*
X760559Y31624D01*
Y35540D01*
G01Y34874D02*
X760226Y35207D01*
X759726Y35457D01*
X759142Y35540D01*
X758476Y35374D01*
X758059Y35040D01*
X757726Y34457D01*
X757559Y33874D01*
X757642Y33374D01*
X757976Y32790D01*
X758476Y32374D01*
X759142Y32207D01*
X759642Y32290D01*
X760226Y32624D01*
X760559Y32957D01*
G01X764659Y37207D02*
Y32207D01*
G01X763492Y35540D02*
X765826D01*
G01X768842Y32207D02*
Y37207D01*
G01Y34790D02*
X769259Y35207D01*
X769676Y35457D01*
X770342Y35540D01*
X770842Y35457D01*
X771426Y35124D01*
X771676Y34624D01*
Y32207D01*
G01X774776Y33124D02*
X776942D01*
G01Y34624D02*
X774776D01*
G01X779876Y34290D02*
X780459Y34874D01*
X780959Y35207D01*
X781626Y35374D01*
X782209Y35207D01*
X782626Y34874D01*
X782959Y34374D01*
X783042Y33790D01*
X782959Y33290D01*
X782626Y32790D01*
X782126Y32374D01*
X781542Y32207D01*
X780876Y32374D01*
X780292Y32874D01*
X779959Y33624D01*
X779876Y34457D01*
X780042Y35540D01*
X780292Y36124D01*
X780709Y36707D01*
X781292Y37124D01*
X781876Y37207D01*
X782459Y37040D01*
X782876Y36624D01*
G01X786142Y33874D02*
X788142D01*
G01X787059Y34957D02*
Y32790D01*
G01X791159Y32040D02*
X794159Y37207D01*
G01X797176Y33874D02*
X799342D01*
G01X802026Y32957D02*
X802526Y32540D01*
X803109Y32290D01*
X803859Y32207D01*
X804609Y32374D01*
X805192Y32707D01*
X805609Y33290D01*
X805692Y33957D01*
X805526Y34624D01*
X805109Y35040D01*
X804526Y35374D01*
X803942Y35457D01*
X803359Y35374D01*
X802609Y35040D01*
X802859Y37207D01*
X805109D01*
G01X806959Y32207D02*
Y35540D01*
G01Y34624D02*
X807209Y35040D01*
X807626Y35374D01*
X808209Y35540D01*
X808792Y35374D01*
X809209Y35040D01*
X809459Y34624D01*
Y32207D01*
G01Y34624D02*
X809709Y35040D01*
X810126Y35374D01*
X810709Y35540D01*
X811292Y35374D01*
X811709Y35040D01*
X811959Y34540D01*
Y32207D01*
G01X815059Y35540D02*
Y32207D01*
G01Y36874D02*
X814892Y36957D01*
Y37124D01*
X815059Y37207D01*
X815226Y37124D01*
Y36957D01*
X815059Y36874D01*
G01X820659Y32207D02*
Y37207D01*
G01X702092Y11707D02*
Y6707D01*
X705426D01*
G01X707942D02*
Y10040D01*
G01Y9207D02*
X708276Y9624D01*
X708776Y9957D01*
X709442Y10040D01*
X710026Y9957D01*
X710526Y9624D01*
X710776Y9040D01*
Y6707D01*
G01X737552Y536650D02*
X736719Y537484D01*
X736302Y538317D01*
Y541650D01*
X736719Y542484D01*
X737552Y543317D01*
G01X743569Y538317D02*
Y543317D01*
X742569Y542317D01*
G01Y538317D02*
X744569D01*
G01X749169Y538150D02*
X749002Y538234D01*
Y538400D01*
X749169Y538484D01*
X749336Y538400D01*
Y538234D01*
X749169Y538150D01*
G01X753186Y542484D02*
X753686Y542984D01*
X754269Y543234D01*
X754936Y543317D01*
X755769Y543150D01*
X756352Y542734D01*
X756519Y542234D01*
X756436Y541734D01*
X756102Y541317D01*
X754436Y540484D01*
X753686Y539900D01*
X753186Y539067D01*
X753019Y538317D01*
X756519D01*
G01X757869D02*
Y541650D01*
G01Y540734D02*
X758119Y541150D01*
X758536Y541484D01*
X759119Y541650D01*
X759702Y541484D01*
X760119Y541150D01*
X760369Y540734D01*
Y538317D01*
G01Y540734D02*
X760619Y541150D01*
X761036Y541484D01*
X761619Y541650D01*
X762202Y541484D01*
X762619Y541150D01*
X762869Y540650D01*
Y538317D01*
G01X763469D02*
Y541650D01*
G01Y540734D02*
X763719Y541150D01*
X764136Y541484D01*
X764719Y541650D01*
X765302Y541484D01*
X765719Y541150D01*
X765969Y540734D01*
Y538317D01*
G01Y540734D02*
X766219Y541150D01*
X766636Y541484D01*
X767219Y541650D01*
X767802Y541484D01*
X768219Y541150D01*
X768469Y540650D01*
Y538317D01*
G01X775002D02*
Y543317D01*
X777169Y539150D01*
X779336Y543317D01*
Y538317D01*
G01X784269D02*
Y541650D01*
G01Y541067D02*
X783936Y541400D01*
X783436Y541567D01*
X782852Y541650D01*
X782269Y541484D01*
X781769Y541150D01*
X781436Y540650D01*
X781269Y539984D01*
X781436Y539317D01*
X781769Y538817D01*
X782269Y538484D01*
X782852Y538317D01*
X783436Y538400D01*
X783936Y538650D01*
X784269Y538984D01*
G01X787119Y541650D02*
X789619Y538317D01*
G01Y541650D02*
X787119Y538317D01*
G01X794386Y536650D02*
X795219Y537484D01*
X795636Y538317D01*
Y541650D01*
X795219Y542484D01*
X794386Y543317D01*
G01X739636Y548437D02*
X736302Y550104D01*
X739636Y551770D01*
G01X742486Y549354D02*
X744652D01*
G01Y550854D02*
X742486D01*
G01X749169Y553437D02*
X748502Y553270D01*
X748002Y552854D01*
X747669Y552354D01*
X747419Y551687D01*
X747336Y550937D01*
X747419Y550187D01*
X747669Y549520D01*
X748002Y549020D01*
X748502Y548604D01*
X749169Y548437D01*
X749836Y548604D01*
X750336Y549020D01*
X750669Y549520D01*
X750919Y550187D01*
X751002Y550937D01*
X750919Y551687D01*
X750669Y552354D01*
X750336Y552854D01*
X749836Y553270D01*
X749169Y553437D01*
G01X754769Y548270D02*
X754602Y548354D01*
Y548520D01*
X754769Y548604D01*
X754936Y548520D01*
Y548354D01*
X754769Y548270D01*
G01X760202Y548437D02*
X760369Y549520D01*
X760619Y550437D01*
X760952Y551270D01*
X761369Y552187D01*
X762036Y553437D01*
X758702D01*
G01X764136Y549187D02*
X764636Y548770D01*
X765219Y548520D01*
X765969Y548437D01*
X766719Y548604D01*
X767302Y548937D01*
X767719Y549520D01*
X767802Y550187D01*
X767636Y550854D01*
X767219Y551270D01*
X766636Y551604D01*
X766052Y551687D01*
X765469Y551604D01*
X764719Y551270D01*
X764969Y553437D01*
X767219D01*
G01X770069Y548270D02*
X773069Y553437D01*
G01X770069D02*
X769569Y553270D01*
X769319Y553020D01*
X769152Y552520D01*
X769319Y552020D01*
X769569Y551770D01*
X770069Y551604D01*
X770569Y551770D01*
X770819Y552020D01*
X770986Y552520D01*
X770819Y553020D01*
X770569Y553270D01*
X770069Y553437D01*
G01X773069Y550104D02*
X772569Y549937D01*
X772319Y549687D01*
X772152Y549187D01*
X772319Y548687D01*
X772569Y548437D01*
X773069Y548270D01*
X773569Y548437D01*
X773819Y548687D01*
X773986Y549187D01*
X773819Y549687D01*
X773569Y549937D01*
X773069Y550104D01*
G01X735842Y577874D02*
X737842D01*
G01X736759Y578957D02*
Y576790D01*
G01X740859Y576040D02*
X743859Y581207D01*
G01X746876Y577874D02*
X749042D01*
G01X751726Y576957D02*
X752226Y576540D01*
X752809Y576290D01*
X753559Y576207D01*
X754309Y576374D01*
X754892Y576707D01*
X755309Y577290D01*
X755392Y577957D01*
X755226Y578624D01*
X754809Y579040D01*
X754226Y579374D01*
X753642Y579457D01*
X753059Y579374D01*
X752309Y579040D01*
X752559Y581207D01*
X754809D01*
G01X756659Y576207D02*
Y579540D01*
G01Y578624D02*
X756909Y579040D01*
X757326Y579374D01*
X757909Y579540D01*
X758492Y579374D01*
X758909Y579040D01*
X759159Y578624D01*
Y576207D01*
G01Y578624D02*
X759409Y579040D01*
X759826Y579374D01*
X760409Y579540D01*
X760992Y579374D01*
X761409Y579040D01*
X761659Y578540D01*
Y576207D01*
G01X764759Y579540D02*
Y576207D01*
G01Y580874D02*
X764592Y580957D01*
Y581124D01*
X764759Y581207D01*
X764926Y581124D01*
Y580957D01*
X764759Y580874D01*
G01X770359Y576207D02*
Y581207D01*
G01X735842Y592874D02*
X737842D01*
G01X736759Y593957D02*
Y591790D01*
G01X740859Y591040D02*
X743859Y596207D01*
G01X746876Y592874D02*
X749042D01*
G01X751726Y591957D02*
X752226Y591540D01*
X752809Y591290D01*
X753559Y591207D01*
X754309Y591374D01*
X754892Y591707D01*
X755309Y592290D01*
X755392Y592957D01*
X755226Y593624D01*
X754809Y594040D01*
X754226Y594374D01*
X753642Y594457D01*
X753059Y594374D01*
X752309Y594040D01*
X752559Y596207D01*
X754809D01*
G01X756659Y591207D02*
Y594540D01*
G01Y593624D02*
X756909Y594040D01*
X757326Y594374D01*
X757909Y594540D01*
X758492Y594374D01*
X758909Y594040D01*
X759159Y593624D01*
Y591207D01*
G01Y593624D02*
X759409Y594040D01*
X759826Y594374D01*
X760409Y594540D01*
X760992Y594374D01*
X761409Y594040D01*
X761659Y593540D01*
Y591207D01*
G01X764759Y594540D02*
Y591207D01*
G01Y595874D02*
X764592Y595957D01*
Y596124D01*
X764759Y596207D01*
X764926Y596124D01*
Y595957D01*
X764759Y595874D01*
G01X770359Y591207D02*
Y596207D01*
G01X735842Y562874D02*
X737842D01*
G01X736759Y563957D02*
Y561790D01*
G01X740859Y561040D02*
X743859Y566207D01*
G01X746876Y562874D02*
X749042D01*
G01X751976Y565374D02*
X752476Y565874D01*
X753059Y566124D01*
X753726Y566207D01*
X754559Y566040D01*
X755142Y565624D01*
X755309Y565124D01*
X755226Y564624D01*
X754892Y564207D01*
X753226Y563374D01*
X752476Y562790D01*
X751976Y561957D01*
X751809Y561207D01*
X755309D01*
G01X756659D02*
Y564540D01*
G01Y563624D02*
X756909Y564040D01*
X757326Y564374D01*
X757909Y564540D01*
X758492Y564374D01*
X758909Y564040D01*
X759159Y563624D01*
Y561207D01*
G01Y563624D02*
X759409Y564040D01*
X759826Y564374D01*
X760409Y564540D01*
X760992Y564374D01*
X761409Y564040D01*
X761659Y563540D01*
Y561207D01*
G01X764759Y564540D02*
Y561207D01*
G01Y565874D02*
X764592Y565957D01*
Y566124D01*
X764759Y566207D01*
X764926Y566124D01*
Y565957D01*
X764759Y565874D01*
G01X770359Y561207D02*
Y566207D01*
G01X729299Y601707D02*
Y533207D01*
G01X837759Y601817D02*
Y533317D01*
G54D12*
G01X360611Y463561D02*
Y386561D01*
G01X367486Y379686D02*
Y473186D01*
G01X352361Y379686D02*
X367486D01*
G01X352361Y386561D02*
Y379686D01*
G01X360611Y386561D02*
X338611D01*
G01D02*
Y463561D01*
G01X352361Y473186D02*
Y466311D01*
G01X367486Y473186D02*
X352361D01*
G01X338611Y463561D02*
X360611D01*
G01X444486Y379686D02*
Y473186D01*
G01X429361Y379686D02*
X444486D01*
G01X429361Y386561D02*
Y379686D01*
G01X437611Y386561D02*
Y463561D01*
G01X393611D02*
Y386561D01*
G01D02*
X437611D01*
G01X401861Y379686D02*
Y386561D01*
G01X386736Y379686D02*
X401861D01*
G01X386736Y473186D02*
Y379686D01*
G01X429361Y473186D02*
Y466311D01*
G01X444486Y473186D02*
X429361D01*
G01X437611Y463561D02*
X393611D01*
G01X401861Y466311D02*
Y473186D01*
G01D02*
X386736D01*
G01X521486Y379686D02*
Y470436D01*
G01X514611Y386561D02*
Y463561D01*
G01X506361Y379686D02*
X521486D01*
G01X506361Y386561D02*
Y379686D01*
G01X478861D02*
Y386561D01*
G01X470611Y463561D02*
Y386561D01*
G01D02*
X514611D01*
G01X463736Y379686D02*
X478861D01*
G01X463736Y473186D02*
Y379686D01*
G01X506361Y470436D02*
Y463561D01*
G01X521486Y470436D02*
X506361D01*
G01X478861Y466311D02*
Y473186D01*
G01X514611Y463561D02*
X470611D01*
G01X478861Y473186D02*
X463736D01*
G01X591611Y386561D02*
Y463561D01*
G01X583361Y379686D02*
X617736D01*
G01X583361Y386561D02*
Y379686D01*
G01X555861D02*
Y386561D01*
G01X540736Y379686D02*
X555861D01*
G01X540736Y470436D02*
Y379686D01*
G01X547611Y463561D02*
Y386561D01*
G01D02*
X591611D01*
G01X632861Y470436D02*
X598486D01*
G01X583361D02*
Y463561D01*
G01X598486Y470436D02*
X583361D01*
G01X555861D02*
X540736D01*
G01X555861Y463561D02*
Y470436D01*
G01X591611Y463561D02*
X547611D01*
G01X675486Y379686D02*
Y470436D01*
G01X660361Y379686D02*
X675486D01*
G01X660361Y386561D02*
Y379686D01*
G01X668611Y386561D02*
Y463561D01*
G01X624611D02*
Y386561D01*
G01D02*
X668611D01*
G01X632861Y379686D02*
Y386561D01*
G01X617736Y379686D02*
X632861D01*
G01X660361Y470436D02*
Y463561D01*
G01X675486Y470436D02*
X660361D01*
G01X668611Y463561D02*
X624611D01*
G01X632861D02*
Y470436D01*
G01X745611Y386561D02*
Y463561D01*
G01X709861Y379686D02*
Y386561D01*
G01X701611Y463561D02*
Y386561D01*
G01D02*
X745611D01*
G01X694736Y379686D02*
X709861D01*
G01X694736Y470436D02*
Y379686D01*
G01X709861Y463561D02*
Y470436D01*
G01X745611Y463561D02*
X701611D01*
G01X709861Y470436D02*
X694736D01*
G54D13*
G01X-163651Y71037D02*
Y55037D01*
G01X-202151Y71037D02*
Y55037D01*
G01X-159561Y78887D02*
G02X-154879Y71067I-4190J-7820D01*
G01X-157051Y72987D01*
X-153821Y73157D01*
X-154781Y71057D01*
G01X-213151Y92037D02*
Y109037D01*
G01X-152651Y92037D02*
Y109037D01*
G01X-148759Y81360D02*
X-152789Y75870D01*
X-148589Y75850D01*
G01X-65679Y52750D02*
X-69709Y47260D01*
X-65509Y47240D01*
G54D14*
G01X386461Y438219D02*
X367761Y456918D01*
G01X386461Y435885D02*
X367761Y454585D01*
G01X386461Y433552D02*
X367761Y452252D01*
G01X386461Y431219D02*
X367761Y449918D01*
G01Y442112D02*
X386461Y460811D01*
G01X367761Y444445D02*
X386461Y463145D01*
G01X367761Y446779D02*
X386461Y465479D01*
G01X367761Y449113D02*
X386461Y467812D01*
G01Y428885D02*
X367761Y447585D01*
G01X381957Y431055D02*
X367761Y445252D01*
G01X378462Y432217D02*
X367761Y442918D01*
G01X376089Y432256D02*
X367761Y440584D01*
G01X374151Y431860D02*
X367761Y438251D01*
G01X372497Y431181D02*
X367761Y435918D01*
G01X371069Y430276D02*
X367761Y433584D01*
G01X369839Y429173D02*
X367761Y431251D01*
G01X368804Y427875D02*
X367761Y428918D01*
G01X367974Y426370D02*
X367761Y426584D01*
G01X373688Y431704D02*
X386461Y444477D01*
G01X367761Y428112D02*
X386461Y446810D01*
G01X367761Y430445D02*
X386461Y449145D01*
G01X367761Y432778D02*
X386461Y451478D01*
G01X367761Y435112D02*
X386461Y453811D01*
G01X367761Y437445D02*
X386461Y456145D01*
G01X367761Y439778D02*
X386461Y458478D01*
G01X367761Y425851D02*
Y470436D01*
G01Y425852D02*
Y425851D01*
G01X386460Y425852D02*
G03X367762I-9349J-3541D01*
G01X351099Y477036D02*
X367684D01*
G01X386461Y456886D02*
X371312Y472036D01*
G01X369086Y474261D02*
X366311Y477036D01*
G01X386461Y454553D02*
X363978Y477036D01*
G01X386461Y452220D02*
X361645Y477036D01*
G01X386461Y449886D02*
X367761Y468586D01*
G01X365911Y470436D02*
X359311Y477036D01*
G01X386461Y447553D02*
X367761Y466253D01*
G01X363578Y470436D02*
X356978Y477036D01*
G01X386461Y445220D02*
X367761Y463919D01*
G01X361244Y470436D02*
X354644Y477036D01*
G01X386461Y442886D02*
X367761Y461586D01*
G01X358910Y470436D02*
X352310Y477036D01*
G01X386461Y440553D02*
X367761Y459253D01*
G01X356577Y470436D02*
X350538Y476474D01*
G01X354244Y470436D02*
X349372Y475308D01*
G01X352086Y470260D02*
X348511Y473835D01*
G01X352086Y467927D02*
X348511Y471502D01*
G01X352086Y465594D02*
X348511Y469168D01*
G01X351509Y463836D02*
X348511Y466835D01*
G01X349176Y463836D02*
X348511Y464502D01*
G01X367761Y451446D02*
X386461Y470146D01*
G01X367761Y453779D02*
X391017Y477036D01*
G01X367761Y456113D02*
X388684Y477036D01*
G01X367761Y458446D02*
X379865Y470551D01*
G01X367761Y460779D02*
X377141Y470159D01*
G01X367761Y463114D02*
X375029Y470381D01*
G01X367761Y465447D02*
X373255Y470941D01*
G01X367761Y467780D02*
X371730Y471749D01*
G01X367761Y470114D02*
X370414Y472767D01*
G01X365750Y470436D02*
X369295Y473982D01*
G01X363417Y470436D02*
X368377Y475396D01*
G01X361083Y470436D02*
X367683Y477036D01*
G01X358750Y470436D02*
X365350Y477036D01*
G01X349817Y463836D02*
X352086Y466106D01*
G01X356417Y470436D02*
X363017Y477036D01*
G01X348511Y464864D02*
X352086Y468439D01*
G01X354082Y470436D02*
X360682Y477036D01*
G01X348511Y467198D02*
X358349Y477036D01*
G01X348511Y469531D02*
X356016Y477036D01*
G01X348511Y471864D02*
X353682Y477036D01*
G01X348511Y474198D02*
X351349Y477036D01*
G01X367684D02*
G03X386538I9427J3024D01*
G01X348511Y474447D02*
X351099Y477036D01*
G01X348511Y463836D02*
Y474447D01*
G01X352086Y463836D02*
X348511D01*
G01X352086Y470711D02*
Y463836D01*
G01X352361Y470436D02*
X352086Y470711D01*
G01X367761Y470436D02*
X352361D01*
G01X444761Y442108D02*
X463461Y460808D01*
G01X444761Y444441D02*
X463461Y463141D01*
G01X444761Y446775D02*
X463461Y465474D01*
G01X444761Y449108D02*
X463461Y467808D01*
G01Y435890D02*
X444761Y454590D01*
G01X463461Y433557D02*
X444761Y452255D01*
G01X463461Y431222D02*
X444761Y449922D01*
G01X463461Y428889D02*
X444761Y447589D01*
G01X463461Y426556D02*
X444761Y445255D01*
G01X463461Y424222D02*
X444761Y442922D01*
G01X463461Y421889D02*
X444761Y440589D01*
G01X463461Y419556D02*
X444761Y438255D01*
G01X463461Y417222D02*
X444761Y435922D01*
G01X463461Y414888D02*
X444761Y433588D01*
G01X463461Y412555D02*
X444761Y431254D01*
G01X463461Y410221D02*
X444761Y428921D01*
G01Y409440D02*
X463461Y428139D01*
G01X444761Y411773D02*
X463461Y430473D01*
G01X444761Y414106D02*
X463461Y432806D01*
G01X444761Y416441D02*
X463461Y435139D01*
G01X444761Y418774D02*
X463461Y437474D01*
G01X444761Y421107D02*
X463461Y439807D01*
G01X444761Y423441D02*
X463461Y442140D01*
G01X444761Y425774D02*
X463461Y444474D01*
G01X444761Y428107D02*
X463461Y446807D01*
G01X444761Y430440D02*
X463461Y449140D01*
G01X444761Y432774D02*
X463461Y451474D01*
G01X444761Y435108D02*
X463461Y453808D01*
G01X444761Y437441D02*
X463461Y456141D01*
G01X444761Y439775D02*
X463461Y458475D01*
G01Y407888D02*
X444761Y426588D01*
G01X463461Y405555D02*
X444761Y424255D01*
G01X463461Y403221D02*
X444761Y421921D01*
G01X463461Y400888D02*
X444761Y419588D01*
G01X463461Y398555D02*
X444761Y417255D01*
G01X463461Y396220D02*
X444761Y414920D01*
G01X463461Y393887D02*
X444761Y412587D01*
G01X463461Y391554D02*
X444761Y410254D01*
G01X463461Y389221D02*
X444761Y407920D01*
G01X463461Y386887D02*
X444761Y405587D01*
G01X463461Y384554D02*
X444761Y403254D01*
G01X463461Y382221D02*
X444761Y400920D01*
G01X463461Y379886D02*
X444761Y398586D01*
G01Y381439D02*
X463461Y400139D01*
G01X444761Y383772D02*
X463461Y402472D01*
G01X444761Y386105D02*
X463461Y404805D01*
G01X444761Y388439D02*
X463461Y407138D01*
G01X444761Y390772D02*
X463461Y409472D01*
G01X444761Y393105D02*
X463461Y411805D01*
G01X444761Y395439D02*
X463461Y414138D01*
G01X444761Y397772D02*
X463461Y416472D01*
G01X444761Y400106D02*
X463461Y418806D01*
G01X444761Y402440D02*
X463461Y421139D01*
G01X444761Y404773D02*
X463461Y423473D01*
G01X444761Y407106D02*
X463461Y425806D01*
G01X444761Y379411D02*
Y470711D01*
G01X465178Y375836D02*
X444761Y396253D01*
G01X462845Y375836D02*
X444761Y393919D01*
G01X460511Y375836D02*
X444761Y391586D01*
G01X458178Y375836D02*
X444761Y389253D01*
G01X455844Y375836D02*
X444761Y386919D01*
G01X453510Y375836D02*
X444761Y384586D01*
G01X451177Y375836D02*
X444761Y382253D01*
G01X448844Y375836D02*
X444761Y379918D01*
G01X446510Y375836D02*
X442935Y379411D01*
G01X450826Y375836D02*
X463461Y388471D01*
G01X448492Y375836D02*
X463461Y390804D01*
G01X446159Y375836D02*
X463461Y393138D01*
G01X443826Y375836D02*
X463461Y395471D01*
G01X441492Y375836D02*
X463461Y397804D01*
G01X444177Y375836D02*
X440602Y379411D01*
G01X441844Y375836D02*
X438269Y379411D01*
G01X429086Y386260D02*
X429059Y386286D01*
G01X429086Y383927D02*
X426726Y386286D01*
G01X429086Y381594D02*
X425511Y385168D01*
G01X427796Y376140D02*
X431066Y379411D01*
G01X426628Y377307D02*
X429086Y379763D01*
G01X425511Y378522D02*
X429086Y382097D01*
G01X425511Y380856D02*
X429086Y384431D01*
G01X425511Y383190D02*
X428607Y386286D01*
G01X425511Y385523D02*
X426274Y386286D01*
G01X429086Y379411D02*
X444761D01*
G01X429086Y386286D02*
Y379411D01*
G01X425511Y386286D02*
X429086D01*
G01X425511Y378425D02*
Y386286D01*
G01X439509Y375836D02*
X435934Y379411D01*
G01X437176Y375836D02*
X433601Y379411D01*
G01X434843Y375836D02*
X431268Y379411D01*
G01X432509Y375836D02*
X425511Y382834D01*
G01X430176Y375836D02*
X425511Y380501D01*
G01X439159Y375836D02*
X442734Y379411D01*
G01X436825Y375836D02*
X440399Y379410D01*
G01X434492Y375836D02*
X438066Y379411D01*
G01X432158Y375836D02*
X435733Y379410D01*
G01X429825Y375836D02*
X433399Y379410D01*
G01X480121Y375836D02*
X428099D01*
G01D02*
X425511Y378425D01*
G01X386461Y426552D02*
X385855Y427158D01*
G01X385716Y427400D02*
X386461Y428143D01*
G01X384747Y428764D02*
X386461Y430477D01*
G01X383582Y429932D02*
X386461Y432811D01*
G01X382221Y430904D02*
X386461Y435144D01*
G01X380646Y431662D02*
X386461Y437477D01*
G01X378813Y432163D02*
X386461Y439811D01*
G01X376613Y432296D02*
X386461Y442144D01*
G01Y425851D02*
X386460Y425852D01*
G01X386461Y470436D02*
Y425851D01*
G01X463461Y456891D02*
X448326Y472026D01*
G01X446076Y474274D02*
X443315Y477036D01*
G01X463461Y449890D02*
X444761Y468590D01*
G01X463461Y447557D02*
X444761Y466256D01*
G01X463461Y445223D02*
X444761Y463923D01*
G01X463461Y442890D02*
X444761Y461590D01*
G01Y451441D02*
X463461Y470141D01*
G01X444761Y453776D02*
X468021Y477035D01*
G01X444761Y456109D02*
X465688Y477036D01*
G01X444761Y458442D02*
X456871Y470552D01*
G01X444761Y460776D02*
X454145Y470159D01*
G01X444761Y463109D02*
X452032Y470380D01*
G01X444761Y465442D02*
X450258Y470940D01*
G01X444761Y467776D02*
X448733Y471747D01*
G01X444761Y470110D02*
X447416Y472765D01*
G01X443028Y470711D02*
X446298Y473979D01*
G01X444684Y477036D02*
G03X463538I9427J3024D01*
G01X463461Y440557D02*
X444761Y459256D01*
G01X463461Y438223D02*
X444761Y456923D01*
G01X463461Y454557D02*
X440981Y477036D01*
G01X463461Y452224D02*
X438648Y477036D01*
G01X442640Y470711D02*
X436315Y477036D01*
G01X440307Y470711D02*
X433982Y477036D01*
G01X437973Y470711D02*
X431648Y477036D01*
G01X435640Y470711D02*
X429315Y477036D01*
G01X433305Y470711D02*
X426982Y477036D01*
G01X430972Y470711D02*
X424647Y477036D01*
G01X429086Y470265D02*
X422314Y477036D01*
G01X429086Y467932D02*
X419981Y477036D01*
G01X429086Y465597D02*
X417647Y477036D01*
G01X428514Y463836D02*
X415314Y477036D01*
G01X426181Y463836D02*
X412981Y477036D01*
G01X423847Y463836D02*
X410647Y477036D01*
G01X421513Y463836D02*
X408313Y477036D01*
G01X440695Y470711D02*
X445378Y475394D01*
G01X438362Y470711D02*
X444684Y477033D01*
G01X436029Y470711D02*
X442354Y477036D01*
G01X426820Y463836D02*
X429086Y466101D01*
G01X433695Y470711D02*
X440020Y477036D01*
G01X424487Y463836D02*
X429086Y468435D01*
G01X431362Y470711D02*
X437687Y477036D01*
G01X422154Y463836D02*
X435354Y477036D01*
G01X419821Y463836D02*
X433019Y477036D01*
G01X417486Y463836D02*
X430686Y477036D01*
G01X415153Y463836D02*
X428353Y477036D01*
G01X412820Y463836D02*
X426019Y477036D01*
G01X410486Y463836D02*
X423686Y477036D01*
G01X408153Y463836D02*
X421352Y477035D01*
G01X429086Y470711D02*
Y463836D01*
G01X444761Y470711D02*
X429086D01*
G01X419179Y463836D02*
X405980Y477036D01*
G01X386538D02*
X444684D01*
G01X416846Y463836D02*
X403646Y477036D01*
G01X414513Y463836D02*
X401313Y477036D01*
G01X412179Y463836D02*
X398980Y477036D01*
G01X409846Y463836D02*
X396646Y477036D01*
G01X407513Y463836D02*
X402136Y469213D01*
G01X400599Y470750D02*
X394313Y477036D01*
G01X405180Y463836D02*
X402136Y466880D01*
G01X398266Y470750D02*
X391980Y477036D01*
G01X402845Y463836D02*
X402136Y464546D01*
G01X395932Y470750D02*
X389645Y477036D01*
G01X393599Y470750D02*
X387312Y477036D01*
G01X391266Y470750D02*
X386101Y475914D01*
G01X388931Y470750D02*
X385253Y474428D01*
G01X386686Y470662D02*
X384199Y473149D01*
G01X386461Y468554D02*
X382950Y472064D01*
G01X386461Y466221D02*
X381497Y471184D01*
G01X386461Y463887D02*
X379812Y470535D01*
G01X386461Y461554D02*
X377829Y470185D01*
G01X386461Y459221D02*
X375366Y470314D01*
G01X405820Y463836D02*
X419019Y477036D01*
G01X403486Y463836D02*
X416686Y477036D01*
G01X402136Y464820D02*
X414351Y477035D01*
G01X402136Y467153D02*
X412018Y477036D01*
G01X402136Y469487D02*
X409685Y477036D01*
G01X401066Y470750D02*
X407351Y477035D01*
G01X398731Y470750D02*
X405018Y477036D01*
G01X396398Y470750D02*
X402685Y477036D01*
G01X394065Y470750D02*
X400352Y477036D01*
G01X391731Y470750D02*
X398017Y477036D01*
G01X389398Y470750D02*
X395684Y477036D01*
G01X387065Y470750D02*
X393351Y477036D01*
G01X386774Y470750D02*
X386461Y470436D01*
G01X401916Y470750D02*
X386774D01*
G01X402136Y470711D02*
X401916Y470750D01*
G01X402136Y463836D02*
Y470711D01*
G01X429086Y463836D02*
X402136D01*
G01X482711Y383971D02*
X480396Y386285D01*
G01X482711Y381638D02*
X479136Y385213D01*
G01X482711Y379305D02*
X479136Y382880D01*
G01X481984Y377697D02*
X479136Y380545D01*
G01X480817Y376531D02*
X477937Y379411D01*
G01X479136Y380812D02*
X482711Y384387D01*
G01X479136Y383145D02*
X482276Y386286D01*
G01X479136Y385479D02*
X479943Y386286D01*
G01X482711D02*
Y378425D01*
G01X479136Y386286D02*
X482711D01*
G01X479136Y379411D02*
Y386286D01*
G01X479179Y375836D02*
X475604Y379411D01*
G01X478828Y375836D02*
X482711Y379719D01*
G01X476494Y375836D02*
X482711Y382052D01*
G01X474161Y375836D02*
X477736Y379411D01*
G01X482711Y378425D02*
X480121Y375836D01*
G01X476845D02*
X473271Y379411D01*
G01X474511Y375836D02*
X470936Y379411D01*
G01X463461D02*
X479136D01*
G01X463461Y470711D02*
Y379411D01*
G01X472178Y375836D02*
X468603Y379411D01*
G01X469844Y375836D02*
X466270Y379411D01*
G01X467511Y375836D02*
X463936Y379411D01*
G01X471827Y375836D02*
X475401Y379411D01*
G01X469493Y375836D02*
X473068Y379411D01*
G01X467160Y375836D02*
X470735Y379411D01*
G01X464827Y375836D02*
X468402Y379411D01*
G01X462493Y375836D02*
X466068Y379411D01*
G01X460160Y375836D02*
X463735Y379411D01*
G01X457827Y375836D02*
X463461Y381470D01*
G01X455492Y375836D02*
X463461Y383804D01*
G01X453159Y375836D02*
X463461Y386138D01*
G01X482711Y472643D02*
X478317Y477036D01*
G01X482711Y470309D02*
X475983Y477036D01*
G01X482711Y465642D02*
X479136Y469216D01*
G01X482183Y463836D02*
X479136Y466883D01*
G01X479850Y463836D02*
X479136Y464550D01*
G01X480490Y463836D02*
X482711Y466057D01*
G01X479136Y464815D02*
X482711Y468390D01*
G01X479136Y467149D02*
X482711Y470724D01*
G01X479136Y469483D02*
X482711Y473058D01*
G01X478030Y470711D02*
X482239Y474919D01*
G01X475697Y470711D02*
X481072Y476086D01*
G01X479136Y463836D02*
Y470711D01*
G01X482711Y463836D02*
X479136D01*
G01X482711Y474447D02*
Y463836D01*
G01X480121Y477036D02*
X482711Y474447D01*
G01Y467976D02*
X473650Y477036D01*
G01X463538D02*
X480121D01*
G01X477642Y470711D02*
X471317Y477036D01*
G01X475308Y470711D02*
X468983Y477036D01*
G01X472975Y470711D02*
X466650Y477036D01*
G01X470642Y470711D02*
X464317Y477036D01*
G01X468307Y470711D02*
X463102Y475916D01*
G01X465974Y470711D02*
X462255Y474430D01*
G01X463641Y470711D02*
X461201Y473150D01*
G01X463461Y468557D02*
X459952Y472066D01*
G01X463461Y466224D02*
X458500Y471185D01*
G01X463461Y463891D02*
X456816Y470536D01*
G01X463461Y461557D02*
X454832Y470185D01*
G01X463461Y459224D02*
X452372Y470313D01*
G01X473364Y470711D02*
X479689Y477036D01*
G01X471030Y470711D02*
X477355Y477036D01*
G01X468697Y470711D02*
X475022Y477036D01*
G01X466364Y470711D02*
X472689Y477036D01*
G01X464030Y470711D02*
X470355Y477036D01*
G01X479136Y470711D02*
X463461D01*
G01X598761Y442100D02*
X617461Y460800D01*
G01X598761Y444433D02*
X617461Y463133D01*
G01X598761Y446768D02*
X617461Y465466D01*
G01X598761Y449101D02*
X615696Y466036D01*
G01X617461Y433564D02*
X598761Y452263D01*
G01X617461Y431230D02*
X598761Y449930D01*
G01Y409431D02*
X617461Y428131D01*
G01X598761Y411766D02*
X617461Y430466D01*
G01X598761Y414099D02*
X617461Y432799D01*
G01X598761Y416432D02*
X617461Y435132D01*
G01X598761Y418766D02*
X617461Y437465D01*
G01X598761Y421099D02*
X617461Y439799D01*
G01X598761Y423432D02*
X617461Y442132D01*
G01X598761Y425766D02*
X617461Y444465D01*
G01X598761Y428099D02*
X617461Y446799D01*
G01X598761Y430433D02*
X617461Y449133D01*
G01X598761Y432767D02*
X617461Y451466D01*
G01X598761Y435100D02*
X617461Y453800D01*
G01X598761Y437433D02*
X617461Y456133D01*
G01X598761Y439767D02*
X617461Y458466D01*
G01Y428897D02*
X598761Y447597D01*
G01X617461Y426564D02*
X598761Y445264D01*
G01X617461Y424230D02*
X598761Y442930D01*
G01X617461Y421897D02*
X598761Y440597D01*
G01X617461Y419563D02*
X598761Y438263D01*
G01X617461Y417229D02*
X598761Y435929D01*
G01X617461Y414896D02*
X598761Y433596D01*
G01X617461Y412563D02*
X598761Y431263D01*
G01X617461Y410230D02*
X598761Y428929D01*
G01X617461Y407896D02*
X598761Y426596D01*
G01X617461Y405563D02*
X598761Y424263D01*
G01X617461Y403230D02*
X598761Y421928D01*
G01X617461Y400895D02*
X598761Y419595D01*
G01X617461Y398562D02*
X598761Y417262D01*
G01X601416Y384086D02*
X617461Y400130D01*
G01X599083Y384086D02*
X617461Y402464D01*
G01X598761Y386097D02*
X617461Y404797D01*
G01X598761Y388431D02*
X617461Y407130D01*
G01X598761Y390764D02*
X617461Y409464D01*
G01X598761Y393097D02*
X617461Y411797D01*
G01X598761Y395432D02*
X617461Y414131D01*
G01X598761Y397765D02*
X617461Y416465D01*
G01X598761Y400098D02*
X617461Y418798D01*
G01X598761Y402432D02*
X617461Y421131D01*
G01X598761Y404765D02*
X617461Y423465D01*
G01X598761Y407098D02*
X617461Y425798D01*
G01Y396229D02*
X598761Y414928D01*
G01X617461Y393895D02*
X598761Y412595D01*
G01X617461Y391562D02*
X598761Y410262D01*
G01X617461Y389229D02*
X598761Y407928D01*
G01X617461Y386895D02*
X598761Y405595D01*
G01X617461Y384561D02*
X598761Y403261D01*
G01X615603Y384086D02*
X598761Y400927D01*
G01X613269Y384086D02*
X598761Y398594D01*
G01X610936Y384086D02*
X598761Y396261D01*
G01X608603Y384086D02*
X598761Y393927D01*
G01X606268Y384086D02*
X598761Y391594D01*
G01X603935Y384086D02*
X598761Y389261D01*
G01X601602Y384086D02*
X598761Y386928D01*
G01X599268Y384086D02*
X598761Y384593D01*
G01X617461Y384086D02*
X598761D01*
G01D02*
Y466036D01*
G01Y451434D02*
X613363Y466036D01*
G01X598761Y453768D02*
X611029Y466036D01*
G01X598761Y456101D02*
X608696Y466036D01*
G01X598761Y458434D02*
X606363Y466036D01*
G01X598761Y460768D02*
X604029Y466036D01*
G01X598761Y463101D02*
X601696Y466036D01*
G01X598761Y465435D02*
X599363Y466036D01*
G01X617461Y449898D02*
X601323Y466036D01*
G01X617461Y447565D02*
X598990Y466036D01*
G01X617461Y445231D02*
X598761Y463931D01*
G01X617461Y442898D02*
X598761Y461598D01*
G01X617461Y440565D02*
X598761Y459264D01*
G01X617461Y438230D02*
X598761Y456930D01*
G01X617461Y435897D02*
X598761Y454597D01*
G01Y466036D02*
X617461D01*
G01X675761Y442096D02*
X694461Y460796D01*
G01X675761Y444430D02*
X694461Y463129D01*
G01X675761Y446763D02*
X694461Y465463D01*
G01X675761Y449096D02*
X692700Y466036D01*
G01X675761Y409428D02*
X694461Y428128D01*
G01X675761Y411761D02*
X694461Y430461D01*
G01X675761Y414095D02*
X694461Y432794D01*
G01X675761Y416428D02*
X694461Y435128D01*
G01X675761Y418762D02*
X694461Y437462D01*
G01X675761Y421095D02*
X694461Y439795D01*
G01X675761Y423429D02*
X694461Y442129D01*
G01X675761Y425762D02*
X694461Y444462D01*
G01X675761Y428095D02*
X694461Y446795D01*
G01X675761Y430429D02*
X694461Y449129D01*
G01X675761Y432762D02*
X694461Y451462D01*
G01X675761Y435095D02*
X694461Y453795D01*
G01X675761Y437430D02*
X694461Y456129D01*
G01X675761Y439763D02*
X694461Y458463D01*
G01Y433568D02*
X675761Y452268D01*
G01X694461Y431234D02*
X675761Y449934D01*
G01X694461Y428901D02*
X675761Y447600D01*
G01X694461Y426567D02*
X675761Y445267D01*
G01X694461Y424234D02*
X675761Y442934D01*
G01X694461Y421901D02*
X675761Y440600D01*
G01X694461Y419567D02*
X675761Y438267D01*
G01X694461Y417234D02*
X675761Y435934D01*
G01X694461Y414901D02*
X675761Y433599D01*
G01X694461Y412566D02*
X675761Y431266D01*
G01X694461Y410233D02*
X675761Y428933D01*
G01X676086Y384086D02*
X694461Y402460D01*
G01X675761Y386094D02*
X694461Y404793D01*
G01X675761Y388427D02*
X694461Y407127D01*
G01X675761Y390760D02*
X694461Y409460D01*
G01X675761Y393094D02*
X694461Y411793D01*
G01X675761Y395427D02*
X694461Y414127D01*
G01X675761Y397760D02*
X694461Y416460D01*
G01X675761Y400095D02*
X694461Y418793D01*
G01X675761Y402428D02*
X694461Y421128D01*
G01X675761Y404761D02*
X694461Y423461D01*
G01X675761Y407095D02*
X694461Y425794D01*
G01Y407900D02*
X675761Y426600D01*
G01X694461Y405566D02*
X675761Y424266D01*
G01X694461Y403233D02*
X675761Y421933D01*
G01X694461Y400900D02*
X675761Y419600D01*
G01X694461Y398567D02*
X675761Y417266D01*
G01X694461Y396232D02*
X675761Y414932D01*
G01X694461Y393899D02*
X675761Y412599D01*
G01X694461Y391566D02*
X675761Y410265D01*
G01X694461Y389232D02*
X675761Y407932D01*
G01X694461Y386899D02*
X675761Y405599D01*
G01X694461Y384566D02*
X675761Y403265D01*
G01X692606Y384086D02*
X675761Y400932D01*
G01X690273Y384086D02*
X675761Y398599D01*
G01X687940Y384086D02*
X675761Y396264D01*
G01X685606Y384086D02*
X675761Y393931D01*
G01X683273Y384086D02*
X675761Y391598D01*
G01X680940Y384086D02*
X675761Y389264D01*
G01X678605Y384086D02*
X675761Y386931D01*
G01X676272Y384086D02*
X675761Y384598D01*
G01X694461Y384086D02*
X675761D01*
G01D02*
Y466036D01*
G01X615417Y384086D02*
X617461Y386129D01*
G01X613084Y384086D02*
X617461Y388463D01*
G01X610750Y384086D02*
X617461Y390796D01*
G01X608417Y384086D02*
X617461Y393129D01*
G01X606084Y384086D02*
X617461Y395464D01*
G01Y466036D02*
Y384086D01*
G01X603749D02*
X617461Y397797D01*
G01X675761Y451430D02*
X690367Y466036D01*
G01X675761Y453764D02*
X688034Y466036D01*
G01X675761Y456097D02*
X685699Y466036D01*
G01X675761Y458431D02*
X683366Y466036D01*
G01X675761Y460764D02*
X681033Y466036D01*
G01X675761Y463097D02*
X678699Y466036D01*
G01X675761Y465431D02*
X676366Y466036D01*
G01X694461Y447568D02*
X675993Y466036D01*
G01X694461Y445235D02*
X675761Y463935D01*
G01X694461Y442902D02*
X675761Y461601D01*
G01Y466036D02*
X694461D01*
G01Y440568D02*
X675761Y459268D01*
G01X694461Y438235D02*
X675761Y456935D01*
G01X694461Y435902D02*
X675761Y454601D01*
G01X617461Y463899D02*
X615324Y466036D01*
G01X617461Y461566D02*
X612990Y466036D01*
G01X617461Y459232D02*
X610656Y466036D01*
G01X617461Y456899D02*
X608323Y466036D01*
G01X617461Y454565D02*
X605990Y466036D01*
G01X617461Y452231D02*
X603656Y466036D01*
G01X694461Y449903D02*
X678327Y466036D01*
G01X692421Y384086D02*
X694461Y386126D01*
G01X690087Y384086D02*
X694461Y388459D01*
G01X687754Y384086D02*
X694461Y390793D01*
G01X685421Y384086D02*
X694461Y393126D01*
G01X683087Y384086D02*
X694461Y395459D01*
G01X680754Y384086D02*
X694461Y397792D01*
G01X678421Y384086D02*
X694461Y400126D01*
G01Y466036D02*
Y384086D01*
G01Y463902D02*
X692327Y466036D01*
G01X694461Y461569D02*
X689994Y466036D01*
G01X694461Y459236D02*
X687661Y466036D01*
G01X694461Y456903D02*
X685328Y466036D01*
G01X694461Y454569D02*
X682993Y466036D01*
G01X694461Y452236D02*
X680660Y466036D01*
M02*
